G04 ================== begin FILE IDENTIFICATION RECORD ==================*
G04 Layout Name:  D:/<user>/Wistron_project/16316-1/gbr-0621/16316-1.brd*
G04 Film Name:    TSILK*
G04 File Format:  Gerber RS274X*
G04 File Origin:  Cadence Allegro 16.5-S056*
G04 Origin Date:  Wed Jun 21 09:31:48 2017*
G04 *
G04 Layer:  VIA CLASS/FILMMASKTOP*
G04 Layer:  REF DES/ASSEMBLY_TOP*
G04 Layer:  PACKAGE GEOMETRY/SILKSCREEN_TOP*
G04 Layer:  DRAWING FORMAT/LAYER_PCB_STORY*
G04 Layer:  DRAWING FORMAT/LAYER_SILK_T*
G04 Layer:  BOARD GEOMETRY/SILKSCREEN_TOP*
G04 *
G04 Offset:    (0.00 0.00)*
G04 Mirror:    No*
G04 Mode:      Positive*
G04 Rotation:  0*
G04 FullContactRelief:  No*
G04 UndefLineWidth:     6.00*
G04 ================== end FILE IDENTIFICATION RECORD ====================*
%FSLAX35Y35*MOIN*%
%IR0*IPPOS*OFA0.00000B0.00000*MIA0B0*SFA1.00000B1.00000*%
%ADD10C,.01*%
%ADD11C,.02*%
%ADD12C,.012*%
%ADD13C,.013*%
%ADD14C,.015*%
%ADD15C,.016*%
%ADD16C,.018*%
%ADD17C,.002*%
%ADD18C,.006*%
%ADD19C,.008*%
G75*
%LPD*%
G75*
G36*
G01X50900Y148700D02*
X49200Y147000D01*
X47500Y148700D01*
X50900D01*
G37*
G36*
G01X56401Y133489D02*
X54401Y135489D01*
Y131489D01*
X56401Y133489D01*
G37*
G36*
G01X68750Y200850D02*
X63750Y195850D01*
X68750D01*
Y200850D01*
G37*
G36*
G01X58100Y293400D02*
X46900D01*
Y276000D01*
X58100D01*
Y293400D01*
G37*
G36*
G01X58004Y321122D02*
X46804D01*
Y303722D01*
X58004D01*
Y321122D01*
G37*
G36*
G01X70405Y353107D02*
X79205D01*
Y348507D01*
X70405D01*
Y353107D01*
G37*
G36*
G01X27705Y352907D02*
X36505D01*
Y348307D01*
X27705D01*
Y352907D01*
G37*
G36*
G01X48705Y352707D02*
X57505D01*
Y348107D01*
X48705D01*
Y352707D01*
G37*
G36*
G01X101369Y0D02*
Y63703D01*
X124769D01*
Y56467D01*
X142469D01*
Y39403D01*
X122104D01*
G03X122107Y39353I-6037J-387D01*
G01X142469D01*
Y17253D01*
X121316D01*
G03X121341Y17203I-5264J-2663D01*
G01X142469D01*
Y16603D01*
X143919D01*
Y10253D01*
X160169D01*
Y16603D01*
X161467D01*
Y56467D01*
X167069D01*
Y0D01*
X101369D01*
G37*
G36*
G01X135757Y245430D02*
X135817Y245369D01*
X135878Y244579D01*
X135939Y244518D01*
X136000Y243788D01*
X136060Y243727D01*
X136122Y242997D01*
X136182Y242937D01*
X136243Y242207D01*
X136304Y242146D01*
X136365Y241416D01*
X136425Y241355D01*
X136486Y240626D01*
X136547Y240565D01*
X136608Y239774D01*
X136669Y239713D01*
X136730Y238984D01*
X136790Y238923D01*
X136851Y238193D01*
X136912Y238132D01*
X136973Y237402D01*
X137034Y237341D01*
X137094Y236612D01*
X137155Y236551D01*
X137216Y235821D01*
X137277Y235760D01*
X137338Y234969D01*
X137399Y234908D01*
X137459Y234179D01*
X137520Y234118D01*
X137581Y233388D01*
X137642Y233327D01*
Y233023D01*
X142142D01*
X142264Y233266D01*
X142447Y233510D01*
X142568Y233814D01*
X142751Y234057D01*
X142872Y234361D01*
X143055Y234604D01*
X143177Y234908D01*
X143359Y235152D01*
X143481Y235456D01*
X143663Y235699D01*
X143785Y236003D01*
X143967Y236247D01*
X144028Y236429D01*
X144210Y236672D01*
X144332Y236977D01*
X144514Y237220D01*
X144636Y237524D01*
X144819Y237767D01*
X144940Y238071D01*
X145123Y238314D01*
X145244Y238619D01*
X145427Y238862D01*
X145548Y239166D01*
X145731Y239409D01*
X145792Y239591D01*
X145974Y239835D01*
X146096Y240139D01*
X146278Y240382D01*
X146461Y240747D01*
X146522Y240686D01*
X146582Y240200D01*
X146643Y239470D01*
X146704Y239105D01*
X146765Y238254D01*
X146825Y238193D01*
X146886Y237098D01*
X146947Y237037D01*
X147008Y235943D01*
X147069Y235882D01*
X147130Y234726D01*
X147190Y234665D01*
X147251Y233571D01*
X147312Y233510D01*
Y233023D01*
X151752D01*
X151873Y233266D01*
X152056Y233510D01*
X152117Y233692D01*
X152299Y233936D01*
X152360Y234118D01*
X152543Y234361D01*
X152603Y234543D01*
X152786Y234787D01*
X152847Y234969D01*
X153029Y235213D01*
X153090Y235395D01*
X153272Y235638D01*
X153333Y235821D01*
X153516Y236064D01*
X153577Y236247D01*
X153759Y236490D01*
X153820Y236672D01*
X154002Y236915D01*
X154124Y237220D01*
X154307Y237463D01*
X154367Y237645D01*
X154549Y237889D01*
X154610Y238071D01*
X154793Y238314D01*
X154854Y238497D01*
X155036Y238740D01*
X155097Y238923D01*
X155279Y239166D01*
X155340Y239348D01*
X155523Y239591D01*
X155584Y239774D01*
X155766Y240017D01*
X155827Y240200D01*
X156009Y240443D01*
X156070Y240626D01*
X156253Y240869D01*
X156313Y241051D01*
X156496Y241295D01*
X156618Y241599D01*
X156800Y241842D01*
X156861Y242025D01*
X157043Y242268D01*
X157104Y242450D01*
X157286Y242693D01*
X157347Y242876D01*
X157530Y243119D01*
X157590Y243302D01*
X157773Y243545D01*
X157834Y243727D01*
X158016Y243971D01*
X158077Y244153D01*
X158260Y244396D01*
X158320Y244579D01*
X158503Y244822D01*
X158564Y245004D01*
X158746Y245248D01*
X158868Y245552D01*
X159050Y245795D01*
X159111Y245917D01*
Y245978D01*
X154063D01*
X153820Y245491D01*
X153759Y245248D01*
X153577Y244944D01*
X153516Y244701D01*
X153394Y244518D01*
X153333Y244275D01*
X153151Y243971D01*
X153090Y243727D01*
X152907Y243423D01*
X152847Y243180D01*
X152725Y242997D01*
X152664Y242754D01*
X152482Y242450D01*
X152421Y242207D01*
X152238Y241903D01*
X152178Y241660D01*
X152056Y241477D01*
X151995Y241234D01*
X151813Y240930D01*
X151752Y240686D01*
X151570Y240382D01*
X151509Y240139D01*
X151387Y239956D01*
X151326Y239713D01*
X151144Y239409D01*
X151083Y239166D01*
X150901Y238862D01*
X150840Y238619D01*
X150718Y238436D01*
X150657Y238193D01*
X150475Y237889D01*
X150414Y237949D01*
X150353Y238923D01*
X150292Y239288D01*
X150231Y240261D01*
X150171Y240626D01*
X150110Y241599D01*
X150049Y241964D01*
X149988Y242937D01*
X149927Y243302D01*
X149866Y244275D01*
X149806Y244640D01*
X149745Y245613D01*
X149684Y245978D01*
X145183D01*
Y245917D01*
X145001Y245673D01*
X144819Y245248D01*
X144636Y245004D01*
X144454Y244579D01*
X144271Y244336D01*
X144089Y243910D01*
X143906Y243667D01*
X143785Y243362D01*
X143602Y243119D01*
X143420Y242693D01*
X143237Y242450D01*
X143055Y242025D01*
X142872Y241781D01*
X142690Y241355D01*
X142507Y241112D01*
X142386Y240808D01*
X142203Y240565D01*
X142021Y240139D01*
X141838Y239896D01*
X141656Y239470D01*
X141473Y239227D01*
X141291Y238801D01*
X141109Y238558D01*
X140987Y238254D01*
X140805Y238010D01*
X140683Y237767D01*
X140622Y237828D01*
X140561Y239166D01*
X140500Y239896D01*
X140440Y241234D01*
X140379Y241964D01*
X140318Y243302D01*
X140257Y244153D01*
X140196Y245369D01*
X140136Y245978D01*
X135696D01*
X135757Y245430D01*
G37*
G36*
G01X129310Y245613D02*
X129249Y245552D01*
X129188Y245065D01*
X129127Y245004D01*
X129066Y244518D01*
X129006Y244457D01*
X128945Y243910D01*
X128884Y243849D01*
X128823Y243362D01*
X128762Y243302D01*
X128701Y242815D01*
X128641Y242754D01*
X128580Y242207D01*
X128519Y242146D01*
X128458Y241660D01*
X128397Y241599D01*
X128336Y241112D01*
X128276Y241051D01*
X128215Y240504D01*
X128154Y240443D01*
X128093Y239956D01*
X128033Y239896D01*
X127972Y239409D01*
X127911Y239348D01*
X127850Y238801D01*
X127789Y238740D01*
X127728Y238254D01*
X127668Y238193D01*
X127607Y237706D01*
X127546Y237645D01*
X127485Y237098D01*
X127424Y237037D01*
X127364Y236551D01*
X127303Y236490D01*
X127242Y236003D01*
X127181Y235943D01*
X127120Y235395D01*
X127059Y235334D01*
X126999Y234848D01*
X126938Y234787D01*
X126877Y234301D01*
X126816Y234240D01*
X126755Y233692D01*
X126694Y233631D01*
X126634Y233145D01*
X126573Y233084D01*
Y233023D01*
X131925D01*
X131986Y233388D01*
X132047Y233449D01*
X132107Y233936D01*
X132168Y233996D01*
X132229Y234543D01*
X132290Y234604D01*
X132351Y235091D01*
X132411Y235152D01*
X132472Y235638D01*
X132533Y235699D01*
X132594Y236247D01*
X132655Y236307D01*
X132716Y236794D01*
X132776Y236855D01*
X132837Y237341D01*
X132898Y237402D01*
X132959Y237949D01*
X133020Y238010D01*
X133081Y238497D01*
X133141Y238558D01*
X133202Y239044D01*
X133263Y239105D01*
X133324Y239653D01*
X133385Y239713D01*
X133446Y240200D01*
X133506Y240261D01*
X133567Y240747D01*
X133628Y240808D01*
X133689Y241295D01*
X133749Y241355D01*
X133810Y241903D01*
X133871Y241964D01*
X133932Y242450D01*
X133993Y242511D01*
X134053Y242997D01*
X134114Y243058D01*
X134175Y243606D01*
X134236Y243667D01*
X134297Y244153D01*
X134358Y244214D01*
X134418Y244701D01*
X134479Y244761D01*
X134540Y245309D01*
X134601Y245369D01*
X134662Y245856D01*
X134723Y245917D01*
Y245978D01*
X129370D01*
X129310Y245613D01*
G37*
G36*
G01X105043Y245248D02*
X105104Y244761D01*
X105164Y244701D01*
X105225Y243971D01*
X105286Y243910D01*
X105347Y243119D01*
X105408Y243058D01*
X105469Y242328D01*
X105529Y242268D01*
X105590Y241538D01*
X105651Y241477D01*
X105712Y240747D01*
X105773Y240686D01*
X105833Y239956D01*
X105894Y239896D01*
X105955Y239105D01*
X106016Y239044D01*
X106077Y238314D01*
X106138Y238254D01*
X106198Y237524D01*
X106259Y237463D01*
X106320Y236733D01*
X106381Y236672D01*
X106442Y235943D01*
X106503Y235882D01*
X106563Y235152D01*
X106624Y235091D01*
X106685Y234301D01*
X106746Y234240D01*
X106807Y233510D01*
X106868Y233449D01*
X106928Y233023D01*
X111368D01*
X111551Y233266D01*
X111672Y233571D01*
X111855Y233814D01*
X111976Y234118D01*
X112159Y234361D01*
X112220Y234543D01*
X112402Y234787D01*
X112523Y235091D01*
X112706Y235334D01*
X112828Y235638D01*
X113010Y235882D01*
X113132Y236186D01*
X113314Y236429D01*
X113375Y236612D01*
X113557Y236855D01*
X113679Y237159D01*
X113862Y237402D01*
X113983Y237706D01*
X114166Y237949D01*
X114287Y238254D01*
X114470Y238497D01*
X114592Y238801D01*
X114774Y239044D01*
X114835Y239227D01*
X115017Y239470D01*
X115139Y239774D01*
X115321Y240017D01*
X115443Y240321D01*
X115625Y240565D01*
Y240626D01*
X115747Y240747D01*
X115808Y240686D01*
X115869Y239591D01*
X115929Y239531D01*
X115990Y238436D01*
X116051Y238375D01*
X116112Y237280D01*
X116173Y237220D01*
X116234Y236064D01*
X116294Y236003D01*
X116355Y234908D01*
X116416Y234848D01*
X116477Y233753D01*
X116538Y233692D01*
X116598Y233023D01*
X121038D01*
X121160Y233327D01*
X121342Y233571D01*
X121403Y233753D01*
X121586Y233996D01*
X121646Y234179D01*
X121829Y234422D01*
X121890Y234604D01*
X122072Y234848D01*
X122194Y235152D01*
X122376Y235395D01*
X122437Y235578D01*
X122620Y235821D01*
X122681Y236003D01*
X122863Y236247D01*
X122923Y236429D01*
X123106Y236672D01*
X123167Y236855D01*
X123349Y237098D01*
X123410Y237280D01*
X123593Y237524D01*
X123653Y237706D01*
X123836Y237949D01*
X123897Y238132D01*
X124079Y238375D01*
X124140Y238558D01*
X124323Y238801D01*
X124444Y239105D01*
X124627Y239348D01*
X124687Y239531D01*
X124870Y239774D01*
X124931Y239956D01*
X125113Y240200D01*
X125174Y240382D01*
X125357Y240626D01*
X125417Y240808D01*
X125600Y241051D01*
X125660Y241234D01*
X125843Y241477D01*
X125904Y241660D01*
X126086Y241903D01*
X126147Y242085D01*
X126329Y242328D01*
X126390Y242511D01*
X126573Y242754D01*
X126694Y243058D01*
X126877Y243302D01*
X126938Y243484D01*
X127120Y243727D01*
X127181Y243910D01*
X127364Y244153D01*
X127424Y244336D01*
X127607Y244579D01*
X127668Y244761D01*
X127850Y245004D01*
X127911Y245187D01*
X128093Y245430D01*
X128154Y245613D01*
X128336Y245856D01*
Y245917D01*
X128397Y245978D01*
X123288D01*
X123228Y245734D01*
X122985Y245309D01*
X122923Y245065D01*
X122741Y244761D01*
X122681Y244518D01*
X122559Y244336D01*
X122498Y244092D01*
X122316Y243788D01*
X122255Y243545D01*
X122072Y243241D01*
X122011Y242997D01*
X121890Y242815D01*
X121829Y242572D01*
X121646Y242268D01*
X121586Y242025D01*
X121403Y241720D01*
X121342Y241477D01*
X121221Y241295D01*
X121160Y241051D01*
X120977Y240747D01*
X120917Y240504D01*
X120734Y240200D01*
X120673Y239956D01*
X120552Y239774D01*
X120491Y239531D01*
X120309Y239227D01*
X120247Y238984D01*
X120065Y238679D01*
X120004Y238436D01*
X119883Y238254D01*
X119822Y238010D01*
X119700Y237889D01*
X119640Y237949D01*
X119579Y239166D01*
X119518Y239227D01*
X119457Y240504D01*
X119396Y240565D01*
X119335Y241842D01*
X119275Y241903D01*
X119214Y243241D01*
X119153Y243302D01*
X119092Y244579D01*
X119031Y244640D01*
X118970Y245917D01*
X118910Y245978D01*
X114409D01*
X114227Y245552D01*
X114044Y245309D01*
X113862Y244883D01*
X113679Y244640D01*
X113497Y244214D01*
X113314Y243971D01*
X113132Y243545D01*
X112949Y243302D01*
X112828Y242997D01*
X112645Y242754D01*
X112463Y242328D01*
X112280Y242085D01*
X112098Y241660D01*
X111915Y241416D01*
X111794Y241112D01*
X111611Y240869D01*
X111429Y240443D01*
X111246Y240200D01*
X111064Y239774D01*
X110881Y239531D01*
X110699Y239105D01*
X110516Y238862D01*
X110395Y238558D01*
X110212Y238314D01*
X110030Y237889D01*
X109909Y237767D01*
X109847Y237828D01*
X109787Y239774D01*
X109726Y239835D01*
X109665Y241842D01*
X109604Y241903D01*
X109544Y243910D01*
X109483Y243971D01*
X109422Y245978D01*
X104921D01*
X105043Y245248D01*
G37*
G36*
G01X132837Y252425D02*
X132351Y252364D01*
X132168Y252242D01*
X131925Y252181D01*
X131682Y252060D01*
X131377Y251816D01*
X131317D01*
X130648Y251086D01*
Y251026D01*
X130465Y250782D01*
X130344Y250539D01*
X130283Y250235D01*
X130222Y250174D01*
X130161Y249566D01*
X130222Y248775D01*
X130283Y248714D01*
X130344Y248471D01*
X130526Y248228D01*
Y248167D01*
X131073Y247680D01*
X131134D01*
X131256Y247559D01*
X131499Y247498D01*
X131560Y247437D01*
X132047Y247377D01*
X132107Y247315D01*
X133081Y247377D01*
X133141Y247437D01*
X133446Y247498D01*
X133506Y247559D01*
X133749Y247620D01*
X133993Y247741D01*
X134358Y248045D01*
X134418D01*
X135088Y248775D01*
X135148Y248958D01*
X135331Y249201D01*
X135392Y249444D01*
X135453Y249505D01*
X135513Y249992D01*
X135574Y250053D01*
X135513Y250965D01*
X135453Y251026D01*
X135392Y251269D01*
X135270Y251512D01*
X134844Y251999D01*
X134601Y252181D01*
X134236Y252364D01*
X133810Y252425D01*
X133749Y252485D01*
X132898D01*
X132837Y252425D01*
G37*
G36*
G01X122072Y271674D02*
G02I-11811J0D01*
G37*
G36*
G01X104363Y303020D02*
Y298020D01*
X124363D01*
Y303020D01*
X104363D01*
G37*
G36*
G01X133451Y269617D02*
Y271417D01*
X137051D01*
Y269617D01*
X133451D01*
G37*
G36*
G01X137051Y265117D02*
Y275917D01*
X138851D01*
Y265117D01*
X137051D01*
G37*
G36*
G01X131651D02*
Y275917D01*
X133451D01*
Y265117D01*
X131651D01*
G37*
G36*
G01X91500Y352900D02*
X100300D01*
Y348300D01*
X91500D01*
Y352900D01*
G37*
G36*
G01X134495Y474607D02*
X101728D01*
Y470275D01*
X134495D01*
Y474607D01*
G37*
G36*
G01X159491Y11735D02*
G02X157491I-1000J0D01*
G01Y14735D01*
G02X159491I1000J0D01*
G01Y11735D01*
G37*
G36*
G01X146691D02*
G02X144691I-1000J0D01*
G01Y14735D01*
G02X146691I1000J0D01*
G01Y11735D01*
G37*
G36*
G01X172900Y121600D02*
X167900D01*
Y126600D01*
X172900Y121600D01*
G37*
G36*
G01X181100Y191050D02*
Y195050D01*
X185100D01*
X181100Y191050D01*
G37*
G36*
G01X200103Y246221D02*
X199373Y246160D01*
X199312Y246099D01*
X198887Y246038D01*
X198826Y245978D01*
X198522Y245917D01*
X198340Y245795D01*
X198096Y245734D01*
X197488Y245430D01*
X197184Y245187D01*
X197123D01*
X196758Y244883D01*
X196697D01*
X195785Y243971D01*
X195724Y244031D01*
X195785Y244457D01*
X195846Y244518D01*
X195907Y245004D01*
X195968Y245065D01*
X196028Y245552D01*
X196089Y245613D01*
X196150Y245917D01*
Y245978D01*
X191528D01*
X191467Y245917D01*
X191406Y245430D01*
X191345Y245369D01*
X191285Y244822D01*
X191223Y244761D01*
X191163Y244275D01*
X191102Y244214D01*
X191041Y243727D01*
X190980Y243667D01*
X190920Y243119D01*
X190859Y243058D01*
X190798Y242572D01*
X190737Y242511D01*
X190676Y242025D01*
X190615Y241964D01*
X190555Y241477D01*
X190494Y241416D01*
X190433Y240869D01*
X190372Y240808D01*
X190311Y240321D01*
X190251Y240261D01*
X190190Y239774D01*
X190129Y239713D01*
X190068Y239166D01*
X190007Y239105D01*
X189946Y238619D01*
X189886Y238558D01*
X189825Y238071D01*
X189764Y238010D01*
X189703Y237463D01*
X189642Y237402D01*
X189581Y236915D01*
X189521Y236855D01*
X189460Y236368D01*
X189399Y236307D01*
X189338Y235821D01*
X189277Y235760D01*
X189216Y235213D01*
X189156Y235152D01*
X189095Y234665D01*
X189034Y234604D01*
X188973Y234118D01*
X188912Y234057D01*
X188852Y233510D01*
X188791Y233449D01*
X188730Y233023D01*
X193717D01*
X193778Y233388D01*
X193839Y233449D01*
X193899Y233996D01*
X193960Y234057D01*
X194021Y234543D01*
X194082Y234604D01*
X194143Y235091D01*
X194204Y235152D01*
X194264Y235638D01*
X194325Y235699D01*
X194386Y236186D01*
X194447Y236247D01*
X194508Y236794D01*
X194569Y236855D01*
X194629Y237341D01*
X194690Y237402D01*
X194751Y237889D01*
X194812Y237949D01*
X194873Y238436D01*
X194934Y238497D01*
X194994Y238984D01*
X195055Y239044D01*
X195116Y239470D01*
X195177Y239531D01*
X195238Y239835D01*
X195299Y239896D01*
X195359Y240139D01*
X195420Y240200D01*
X195481Y240443D01*
X195542Y240504D01*
X195603Y240747D01*
X195785Y240990D01*
X195846Y241173D01*
X196089Y241477D01*
Y241538D01*
X196515Y242025D01*
X196576D01*
X197001Y242389D01*
X197366Y242572D01*
X197853Y242632D01*
X197914Y242693D01*
X198522Y242632D01*
X198765Y242450D01*
X198887D01*
Y242328D01*
X199009Y242207D01*
X199069Y241842D01*
X199130Y241781D01*
X199069Y241051D01*
X199009Y240990D01*
X198947Y240382D01*
X198887Y240321D01*
X198826Y239774D01*
X198765Y239713D01*
X198704Y239227D01*
X198644Y239166D01*
X198583Y238619D01*
X198522Y238558D01*
X198461Y238071D01*
X198400Y238010D01*
X198340Y237524D01*
X198279Y237463D01*
X198218Y236915D01*
X198157Y236855D01*
X198096Y236368D01*
X198035Y236307D01*
X197975Y235760D01*
X197914Y235699D01*
X197853Y235213D01*
X197792Y235152D01*
X197731Y234665D01*
X197670Y234604D01*
X197610Y234057D01*
X197549Y233996D01*
X197488Y233510D01*
X197427Y233449D01*
X197366Y233023D01*
X202353D01*
X202414Y233510D01*
X202475Y233571D01*
X202536Y234057D01*
X202597Y234118D01*
X202658Y234665D01*
X202718Y234726D01*
X202779Y235213D01*
X202840Y235273D01*
X202901Y235821D01*
X202962Y235882D01*
X203023Y236368D01*
X203083Y236429D01*
X203144Y236915D01*
X203205Y236977D01*
X203266Y237524D01*
X203327Y237584D01*
X203387Y238071D01*
X203448Y238132D01*
X203509Y238679D01*
X203570Y238740D01*
X203631Y239227D01*
X203692Y239288D01*
X203752Y239835D01*
X203813Y239896D01*
X203874Y240382D01*
X203935Y240443D01*
X203996Y240990D01*
X204057Y241051D01*
X204117Y241660D01*
X204178Y241720D01*
X204239Y242450D01*
X204300Y242511D01*
X204239Y244092D01*
X204178Y244153D01*
X204117Y244396D01*
X204057Y244457D01*
Y244579D01*
X203874Y244822D01*
Y244883D01*
X203448Y245369D01*
X202962Y245795D01*
X202475Y246038D01*
X202171Y246099D01*
X202110Y246160D01*
X201502Y246221D01*
X201441Y246282D01*
X200164D01*
X200103Y246221D01*
G37*
G36*
G01X184655D02*
X183925Y246160D01*
X183864Y246099D01*
X183499Y246038D01*
X183439Y245978D01*
X183135Y245917D01*
X183074Y245856D01*
X182831Y245795D01*
X182770Y245734D01*
X182527Y245673D01*
X182283Y245552D01*
X182040Y245369D01*
X181979D01*
X181675Y245126D01*
X181614D01*
X181128Y244701D01*
X181067D01*
X180398Y244031D01*
X180337Y244092D01*
X180398Y244579D01*
X180459Y244640D01*
X180520Y245126D01*
X180580Y245187D01*
X180641Y245673D01*
X180702Y245734D01*
Y245978D01*
X176080D01*
X176019Y245552D01*
X175958Y245491D01*
X175897Y244944D01*
X175836Y244883D01*
X175775Y244396D01*
X175715Y244336D01*
X175654Y243849D01*
X175593Y243788D01*
X175532Y243241D01*
X175472Y243180D01*
X175410Y242693D01*
X175350Y242632D01*
X175289Y242146D01*
X175228Y242085D01*
X175167Y241599D01*
X175107Y241538D01*
X175046Y240990D01*
X174985Y240930D01*
X174924Y240443D01*
X174863Y240382D01*
X174803Y239896D01*
X174742Y239835D01*
X174681Y239288D01*
X174620Y239227D01*
X174559Y238740D01*
X174498Y238679D01*
X174438Y238193D01*
X174377Y238132D01*
X174316Y237584D01*
X174255Y237524D01*
X174194Y237037D01*
X174133Y236977D01*
X174073Y236490D01*
X174012Y236429D01*
X173951Y235943D01*
X173890Y235882D01*
X173829Y235334D01*
X173768Y235273D01*
X173708Y234787D01*
X173647Y234726D01*
X173586Y234240D01*
X173525Y234179D01*
X173464Y233631D01*
X173403Y233571D01*
X173343Y233084D01*
X173282Y233023D01*
X178330D01*
X178391Y233571D01*
X178451Y233631D01*
X178512Y234118D01*
X178573Y234179D01*
X178634Y234665D01*
X178695Y234726D01*
X178756Y235213D01*
X178816Y235273D01*
X178877Y235760D01*
X178938Y235821D01*
X178999Y236368D01*
X179060Y236429D01*
X179121Y236915D01*
X179181Y236977D01*
X179242Y237463D01*
X179303Y237524D01*
X179364Y238010D01*
X179425Y238071D01*
X179486Y238558D01*
X179546Y238619D01*
X179607Y239105D01*
X179668Y239166D01*
X179729Y239531D01*
X179790Y239591D01*
X179850Y239896D01*
X179911Y239956D01*
X179972Y240261D01*
X180398Y241112D01*
X180641Y241416D01*
Y241477D01*
X181188Y242085D01*
X181492Y242328D01*
X181979Y242572D01*
X182466Y242632D01*
X182527Y242693D01*
X183135Y242632D01*
X183499Y242328D01*
X183621Y242146D01*
X183682Y241660D01*
X183621Y240869D01*
X183560Y240808D01*
X183499Y240261D01*
X183439Y240200D01*
X183378Y239653D01*
X183317Y239591D01*
X183256Y239044D01*
X183196Y238984D01*
X183135Y238497D01*
X183074Y238436D01*
X183013Y237889D01*
X182952Y237828D01*
X182891Y237341D01*
X182831Y237280D01*
X182770Y236794D01*
X182709Y236733D01*
X182648Y236186D01*
X182587Y236125D01*
X182527Y235638D01*
X182466Y235578D01*
X182405Y235030D01*
X182344Y234969D01*
X182283Y234483D01*
X182222Y234422D01*
X182162Y233936D01*
X182101Y233875D01*
X182040Y233327D01*
X181979Y233266D01*
Y233023D01*
X186905D01*
X186966Y233327D01*
X187027Y233388D01*
X187088Y233936D01*
X187149Y233996D01*
X187210Y234483D01*
X187270Y234543D01*
X187331Y235091D01*
X187392Y235152D01*
X187453Y235638D01*
X187514Y235699D01*
X187574Y236186D01*
X187635Y236247D01*
X187696Y236794D01*
X187757Y236855D01*
X187818Y237341D01*
X187879Y237402D01*
X187939Y237949D01*
X188000Y238010D01*
X188061Y238497D01*
X188122Y238558D01*
X188183Y239044D01*
X188244Y239105D01*
X188304Y239653D01*
X188365Y239713D01*
X188426Y240200D01*
X188487Y240261D01*
X188547Y240808D01*
X188609Y240869D01*
X188669Y241477D01*
X188730Y241538D01*
X188791Y242207D01*
X188852Y242268D01*
X188912Y243241D01*
X188852Y243971D01*
X188791Y244031D01*
X188730Y244336D01*
X188669Y244396D01*
X188609Y244640D01*
X188426Y244883D01*
Y244944D01*
X188000Y245430D01*
X187574Y245795D01*
X187210Y245978D01*
X186966Y246038D01*
X186905Y246099D01*
X186480Y246160D01*
X186419Y246221D01*
X185446Y246282D01*
X184716D01*
X184655Y246221D01*
G37*
G36*
G01X169937Y245734D02*
X169755Y245491D01*
X169694Y245309D01*
X169511Y245065D01*
X169450Y244883D01*
X169268Y244640D01*
X169207Y244457D01*
X169025Y244214D01*
X168903Y243910D01*
X168720Y243667D01*
X168660Y243484D01*
X168477Y243241D01*
X168416Y243058D01*
X168234Y242815D01*
X168173Y242632D01*
X167991Y242389D01*
X167869Y242085D01*
X167686Y241842D01*
X167626Y241660D01*
X167443Y241416D01*
X167383Y241234D01*
X167200Y240990D01*
X167139Y240808D01*
X166957Y240565D01*
X166896Y240382D01*
X166714Y240139D01*
X166592Y239835D01*
X166409Y239591D01*
X166349Y239409D01*
X166166Y239166D01*
X166105Y238984D01*
X165923Y238740D01*
Y238679D01*
X165801Y238558D01*
X165740Y238619D01*
X165679Y239591D01*
X165619Y239653D01*
X165558Y240808D01*
X165497Y240869D01*
X165436Y242085D01*
X165375Y242146D01*
X165315Y243302D01*
X165254Y243362D01*
X165193Y244579D01*
X165132Y244640D01*
X165072Y245795D01*
X165010Y245856D01*
Y245978D01*
X160145D01*
X160206Y245917D01*
X160267Y245309D01*
X160327Y245248D01*
X160388Y244640D01*
X160449Y244579D01*
X160510Y244031D01*
X160571Y243971D01*
X160632Y243362D01*
X160692Y243302D01*
X160753Y242693D01*
X160814Y242632D01*
X160875Y242085D01*
X160936Y242025D01*
X160996Y241416D01*
X161057Y241355D01*
X161118Y240747D01*
X161179Y240686D01*
X161240Y240139D01*
X161301Y240078D01*
X161361Y239470D01*
X161422Y239409D01*
X161483Y238801D01*
X161544Y238740D01*
X161605Y238193D01*
X161666Y238132D01*
X161726Y237524D01*
X161787Y237463D01*
X161848Y236855D01*
X161909Y236794D01*
X161970Y236247D01*
X162031Y236186D01*
X162091Y235578D01*
X162152Y235517D01*
X162213Y234908D01*
X162273Y234848D01*
X162335Y234301D01*
X162395Y234240D01*
X162456Y233631D01*
X162517Y233571D01*
X162578Y232962D01*
X162638Y232901D01*
X162517Y232658D01*
X162335Y232415D01*
X162213Y232111D01*
X162031Y231867D01*
X161970Y231685D01*
X161787Y231442D01*
X161726Y231260D01*
X161544Y231016D01*
X161483Y230834D01*
X161301Y230590D01*
X161179Y230286D01*
X160996Y230043D01*
X160936Y229860D01*
X160753Y229617D01*
X160692Y229435D01*
X160510Y229191D01*
X160449Y229009D01*
X160267Y228766D01*
X160145Y228462D01*
X159962Y228218D01*
X159902Y228036D01*
X159719Y227793D01*
X159659Y227610D01*
X159476Y227367D01*
X159415Y227184D01*
X159233Y226941D01*
X159111Y226637D01*
X158990Y226515D01*
X164098D01*
X164159Y226698D01*
X164342Y226941D01*
X164402Y227124D01*
X164585Y227367D01*
X164646Y227549D01*
X164828Y227793D01*
X164950Y228097D01*
X165132Y228340D01*
X165193Y228523D01*
X165375Y228766D01*
X165436Y228948D01*
X165619Y229191D01*
X165679Y229374D01*
X165862Y229617D01*
X165984Y229921D01*
X166166Y230165D01*
X166227Y230347D01*
X166409Y230590D01*
X166470Y230773D01*
X166653Y231016D01*
X166714Y231199D01*
X166896Y231442D01*
X166957Y231624D01*
X167139Y231867D01*
X167261Y232172D01*
X167443Y232415D01*
X167504Y232597D01*
X167686Y232841D01*
X167747Y233023D01*
X167930Y233266D01*
X167991Y233449D01*
X168173Y233692D01*
X168295Y233996D01*
X168477Y234240D01*
X168538Y234422D01*
X168720Y234665D01*
X168781Y234848D01*
X168964Y235091D01*
X169025Y235273D01*
X169207Y235517D01*
X169329Y235821D01*
X169511Y236064D01*
X169572Y236247D01*
X169755Y236490D01*
X169815Y236672D01*
X169998Y236915D01*
X170059Y237098D01*
X170241Y237341D01*
X170302Y237524D01*
X170484Y237767D01*
X170606Y238071D01*
X170788Y238314D01*
X170849Y238497D01*
X171032Y238740D01*
X171092Y238923D01*
X171275Y239166D01*
X171336Y239348D01*
X171518Y239591D01*
X171640Y239896D01*
X171822Y240139D01*
X171883Y240321D01*
X172066Y240565D01*
X172126Y240747D01*
X172309Y240990D01*
X172370Y241173D01*
X172552Y241416D01*
X172674Y241720D01*
X172856Y241964D01*
X172917Y242146D01*
X173099Y242389D01*
X173160Y242572D01*
X173343Y242815D01*
X173403Y242997D01*
X173586Y243241D01*
X173708Y243545D01*
X173890Y243788D01*
X173951Y243971D01*
X174133Y244214D01*
X174194Y244396D01*
X174377Y244640D01*
X174438Y244822D01*
X174620Y245065D01*
X174681Y245248D01*
X174863Y245491D01*
X174985Y245795D01*
X175107Y245917D01*
Y246038D01*
X170059D01*
X169937Y245734D01*
G37*
G36*
G01X142451Y274117D02*
Y275917D01*
X146951D01*
Y274117D01*
X142451D01*
G37*
G36*
G01Y269617D02*
Y271417D01*
X145151D01*
Y269617D01*
X142451D01*
G37*
G36*
G01X140651Y265117D02*
Y275917D01*
X142451D01*
Y265117D01*
X140651D01*
G37*
G36*
G01X141682Y487441D02*
X143682Y489441D01*
X139682D01*
X141682Y487441D01*
G37*
G36*
G01X207401Y248471D02*
X207523Y248228D01*
X206976D01*
X206915Y248289D01*
X206733Y248714D01*
X206550Y248958D01*
Y249079D01*
X206368Y249140D01*
X205942Y249201D01*
Y248228D01*
X205516D01*
Y250024D01*
X205942D01*
Y249566D01*
X206246D01*
X206854Y249627D01*
X206915Y249809D01*
X206854Y250174D01*
X206672D01*
X206611Y250235D01*
X205942D01*
Y250025D01*
X205516D01*
Y250600D01*
X206672D01*
X207036Y250539D01*
X207280Y250356D01*
X207341Y250114D01*
X207401Y250053D01*
X207341Y249688D01*
X207097Y249384D01*
X206854Y249323D01*
X206793Y249262D01*
X206915Y249140D01*
X206976D01*
X207036Y249079D01*
X207158Y248897D01*
X207219Y248714D01*
X207401Y248471D01*
G37*
G36*
G01X207888Y247741D02*
X207584Y247498D01*
X207341Y247437D01*
X207158Y247315D01*
X206124Y247255D01*
X206064Y247315D01*
X205699Y247377D01*
X205334Y247559D01*
X205090Y247741D01*
X204665Y248228D01*
X204422Y248714D01*
X204360Y249627D01*
X204361Y249633D01*
X204746D01*
X204725Y249444D01*
X204786Y248836D01*
X204908Y248593D01*
X205151Y248289D01*
Y248228D01*
X205577Y247863D01*
X205820Y247741D01*
X206246Y247680D01*
X206307Y247620D01*
X207036Y247680D01*
X207097Y247741D01*
X207341Y247802D01*
X207706Y248106D01*
X208131Y248593D01*
X208192Y248836D01*
X208253Y248897D01*
X208314Y249323D01*
X208253Y249931D01*
X208192Y249992D01*
X208131Y250235D01*
X207827Y250600D01*
Y250721D01*
X207706D01*
X207341Y251026D01*
X207219D01*
X207158Y251086D01*
X206793Y251147D01*
X206733Y251208D01*
X206003Y251147D01*
X205942Y251086D01*
X205699Y251026D01*
X205455Y250843D01*
X205394D01*
X204969Y250356D01*
X204786Y249992D01*
X204746Y249634D01*
X204361D01*
X204422Y250114D01*
X204665Y250600D01*
X204847Y250843D01*
X205334Y251269D01*
X205699Y251451D01*
X206064Y251512D01*
X206124Y251573D01*
X206915D01*
X206976Y251512D01*
X207341Y251451D01*
X207584Y251330D01*
X207888Y251086D01*
X207949D01*
X208375Y250600D01*
X208496Y250356D01*
X208557Y250114D01*
X208618Y250053D01*
X208679Y248958D01*
X208618Y248897D01*
X208557Y248593D01*
X208375Y248228D01*
X207949Y247741D01*
X207888D01*
G37*
G36*
G01X235632Y302805D02*
X226832D01*
Y307405D01*
X235632D01*
Y302805D01*
G37*
G36*
G01X253975Y302767D02*
X245175D01*
Y307367D01*
X253975D01*
Y302767D01*
G37*
G36*
G01X217400Y302800D02*
X208600D01*
Y307400D01*
X217400D01*
Y302800D01*
G37*
G36*
G01X265670Y409520D02*
X261620D01*
X265670Y405470D01*
Y409520D01*
G37*
G36*
G01X273397Y303056D02*
X264597D01*
Y307656D01*
X273397D01*
Y303056D01*
G37*
G36*
G01X339604Y1661D02*
G02X337604I-1000J0D01*
G01Y2661D01*
G02X339604I1000J0D01*
G01Y1661D01*
G37*
G36*
G01X346690D02*
G02X344690I-1000J0D01*
G01Y2661D01*
G02X346690I1000J0D01*
G01Y1661D01*
G37*
G36*
G01X353776D02*
G02X351776I-1000J0D01*
G01Y2661D01*
G02X353776I1000J0D01*
G01Y1661D01*
G37*
G36*
G01X360862D02*
G02X358862I-1000J0D01*
G01Y2661D01*
G02X360862I1000J0D01*
G01Y1661D01*
G37*
G36*
G01X367948D02*
G02X365948I-1000J0D01*
G01Y2661D01*
G02X367948I1000J0D01*
G01Y1661D01*
G37*
G36*
G01X375034D02*
G02X373034I-1000J0D01*
G01Y2661D01*
G02X375034I1000J0D01*
G01Y1661D01*
G37*
G36*
G01X382120D02*
G02X380120I-1000J0D01*
G01Y2661D01*
G02X382120I1000J0D01*
G01Y1661D01*
G37*
G36*
G01X334883Y55761D02*
Y63561D01*
X444083D01*
Y55761D01*
X334883D01*
G37*
G36*
G01X329729Y212962D02*
Y217962D01*
X332229Y215462D01*
X329729Y212962D01*
G37*
G36*
G01X386095Y330441D02*
Y336441D01*
X380095Y330441D01*
X386095D01*
G37*
G36*
G01X442286Y497030D02*
Y470830D01*
X444236D01*
Y449830D01*
X435036D01*
Y400530D01*
X391736D01*
Y449830D01*
X382536D01*
Y470830D01*
X384486D01*
Y497030D01*
X442286D01*
G37*
G36*
G01X389206Y1661D02*
G02X387206I-1000J0D01*
G01Y2661D01*
G02X389206I1000J0D01*
G01Y1661D01*
G37*
G36*
G01X396292D02*
G02X394292I-1000J0D01*
G01Y2661D01*
G02X396292I1000J0D01*
G01Y1661D01*
G37*
G36*
G01X403378D02*
G02X401378I-1000J0D01*
G01Y2661D01*
G02X403378I1000J0D01*
G01Y1661D01*
G37*
G36*
G01X410464D02*
G02X408464I-1000J0D01*
G01Y2661D01*
G02X410464I1000J0D01*
G01Y1661D01*
G37*
G36*
G01X417550D02*
G02X415550I-1000J0D01*
G01Y2661D01*
G02X417550I1000J0D01*
G01Y1661D01*
G37*
G36*
G01X424636D02*
G02X422636I-1000J0D01*
G01Y2661D01*
G02X424636I1000J0D01*
G01Y1661D01*
G37*
G36*
G01X431722D02*
G02X429722I-1000J0D01*
G01Y2661D01*
G02X431722I1000J0D01*
G01Y1661D01*
G37*
G36*
G01X438808D02*
G02X436808I-1000J0D01*
G01Y2661D01*
G02X438808I1000J0D01*
G01Y1661D01*
G37*
G36*
G01X445894D02*
G02X443894I-1000J0D01*
G01Y2661D01*
G02X445894I1000J0D01*
G01Y1661D01*
G37*
G36*
G01X452980D02*
G02X450980I-1000J0D01*
G01Y2661D01*
G02X452980I1000J0D01*
G01Y1661D01*
G37*
G36*
G01X460066D02*
G02X458066I-1000J0D01*
G01Y2661D01*
G02X460066I1000J0D01*
G01Y1661D01*
G37*
G36*
G01X467152D02*
G02X465152I-1000J0D01*
G01Y2661D01*
G02X467152I1000J0D01*
G01Y1661D01*
G37*
G36*
G01X474238D02*
G02X472238I-1000J0D01*
G01Y2661D01*
G02X474238I1000J0D01*
G01Y1661D01*
G37*
G36*
G01X481324D02*
G02X479324I-1000J0D01*
G01Y2661D01*
G02X481324I1000J0D01*
G01Y1661D01*
G37*
G36*
G01X488410D02*
G02X486410I-1000J0D01*
G01Y2661D01*
G02X488410I1000J0D01*
G01Y1661D01*
G37*
G36*
G01X495496D02*
G02X493496I-1000J0D01*
G01Y2661D01*
G02X495496I1000J0D01*
G01Y1661D01*
G37*
G36*
G01X502582D02*
G02X500582I-1000J0D01*
G01Y2661D01*
G02X502582I1000J0D01*
G01Y1661D01*
G37*
G36*
G01X509668D02*
G02X507668I-1000J0D01*
G01Y2661D01*
G02X509668I1000J0D01*
G01Y1661D01*
G37*
G36*
G01X486883Y55761D02*
Y63561D01*
X591883D01*
Y55761D01*
X486883D01*
G37*
G36*
G01X516754Y1661D02*
G02X514754I-1000J0D01*
G01Y2661D01*
G02X516754I1000J0D01*
G01Y1661D01*
G37*
G36*
G01X523840D02*
G02X521840I-1000J0D01*
G01Y2661D01*
G02X523840I1000J0D01*
G01Y1661D01*
G37*
G36*
G01X530926D02*
G02X528926I-1000J0D01*
G01Y2661D01*
G02X530926I1000J0D01*
G01Y1661D01*
G37*
G36*
G01X538012D02*
G02X536012I-1000J0D01*
G01Y2661D01*
G02X538012I1000J0D01*
G01Y1661D01*
G37*
G36*
G01X545098D02*
G02X543098I-1000J0D01*
G01Y2661D01*
G02X545098I1000J0D01*
G01Y1661D01*
G37*
G36*
G01X552184D02*
G02X550184I-1000J0D01*
G01Y2661D01*
G02X552184I1000J0D01*
G01Y1661D01*
G37*
G36*
G01X559270D02*
G02X557270I-1000J0D01*
G01Y2661D01*
G02X559270I1000J0D01*
G01Y1661D01*
G37*
G36*
G01X566356D02*
G02X564356I-1000J0D01*
G01Y2661D01*
G02X566356I1000J0D01*
G01Y1661D01*
G37*
G36*
G01X573442D02*
G02X571442I-1000J0D01*
G01Y2661D01*
G02X573442I1000J0D01*
G01Y1661D01*
G37*
G36*
G01X580528D02*
G02X578528I-1000J0D01*
G01Y2661D01*
G02X580528I1000J0D01*
G01Y1661D01*
G37*
G36*
G01X587614D02*
G02X585614I-1000J0D01*
G01Y2661D01*
G02X587614I1000J0D01*
G01Y1661D01*
G37*
G36*
G01X638063Y208393D02*
Y214393D01*
X632063Y208393D01*
X638063D01*
G37*
G36*
G01X620965Y185471D02*
X625965D01*
X623465Y182971D01*
X620965Y185471D01*
G37*
G36*
G01X590550Y469900D02*
Y465850D01*
X594600Y469900D01*
X590550D01*
G37*
G36*
G01X599400Y424240D02*
X601900Y426740D01*
X596900D01*
X599400Y424240D01*
G37*
G36*
G01X655853Y386307D02*
Y381307D01*
X660853Y386307D01*
X655853D01*
G37*
G36*
G01X750433Y2611D02*
Y1111D01*
G03X751933I750J0D01*
G01Y2611D01*
G03X750433I-750J0D01*
G37*
G36*
G01X736259D02*
Y1111D01*
G03X737759I750J0D01*
G01Y2611D01*
G03X736259I-750J0D01*
G37*
G36*
G01X722085D02*
Y1111D01*
G03X723585I750J0D01*
G01Y2611D01*
G03X722085I-750J0D01*
G37*
G36*
G01X707911D02*
Y1111D01*
G03X709411I750J0D01*
G01Y2611D01*
G03X707911I-750J0D01*
G37*
G36*
G01X704961Y0D02*
Y63561D01*
X763561D01*
Y0D01*
X760767D01*
Y55650D01*
X754861D01*
Y61361D01*
X713461D01*
Y55650D01*
X706161D01*
Y0D01*
X704961D01*
G37*
G36*
G01X757520Y54411D02*
Y52911D01*
G03X759020I750J0D01*
G01Y54411D01*
G03X757520I-750J0D01*
G37*
G36*
G01X743346D02*
Y52911D01*
G03X744846I750J0D01*
G01Y54411D01*
G03X743346I-750J0D01*
G37*
G36*
G01X729172D02*
Y52911D01*
G03X730672I750J0D01*
G01Y54411D01*
G03X729172I-750J0D01*
G37*
G36*
G01X714998D02*
Y52911D01*
G03X716498I750J0D01*
G01Y54411D01*
G03X714998I-750J0D01*
G37*
G36*
G01X708362Y471121D02*
X703362D01*
X708362Y466121D01*
Y471121D01*
G37*
G36*
G01X769108Y300401D02*
X777108D01*
Y309501D01*
X769108D01*
Y300401D01*
G37*
G36*
G01X791520Y331200D02*
X789020Y328700D01*
X794020D01*
X791520Y331200D01*
G37*
%LPC*%
G75*
G36*
G01X110261Y261044D02*
X112336Y261249D01*
X114331Y261854D01*
X116166Y262834D01*
X117235Y263714D01*
X114795Y266154D01*
X114365D01*
X114267Y266162D01*
X113566Y266374D01*
X113241Y266549D01*
Y266154D01*
X111641D01*
Y269309D01*
X108924Y272026D01*
X108516Y271694D01*
X107880Y271353D01*
X107224Y271154D01*
X104666D01*
Y266154D01*
X103096D01*
Y277854D01*
X102301Y278648D01*
X101421Y277579D01*
X100441Y275744D01*
X99836Y273749D01*
X99631Y271674D01*
X99836Y269599D01*
X100441Y267604D01*
X101421Y265769D01*
X102746Y264159D01*
X104356Y262834D01*
X106191Y261854D01*
X108186Y261249D01*
X110261Y261044D01*
G37*
G36*
G01X118220Y264699D02*
X119101Y265769D01*
X120081Y267604D01*
X120686Y269599D01*
X120891Y271674D01*
X120686Y273749D01*
X120081Y275744D01*
X119101Y277579D01*
X117776Y279189D01*
X116166Y280514D01*
X114331Y281494D01*
X112336Y282099D01*
X110261Y282304D01*
X108186Y282099D01*
X106191Y281494D01*
X104356Y280514D01*
X103285Y279632D01*
X104527Y278389D01*
X106916D01*
X107190Y278354D01*
X107881Y278144D01*
X108516Y277804D01*
X109076Y277349D01*
X109531Y276789D01*
X109871Y276154D01*
X110081Y275464D01*
X110151Y274749D01*
X110081Y274034D01*
X109871Y273344D01*
X109767Y273151D01*
X111641Y271277D01*
Y278194D01*
X113241D01*
Y274139D01*
X113566Y274314D01*
X114261Y274524D01*
X114986Y274594D01*
X115711Y274524D01*
X116406Y274314D01*
X117046Y273969D01*
X117606Y273509D01*
X118066Y272949D01*
X118411Y272309D01*
X118620Y271616D01*
X118691Y270889D01*
Y269799D01*
X118621Y269074D01*
X118411Y268379D01*
X118066Y267739D01*
X117606Y267179D01*
X117046Y266719D01*
X116496Y266423D01*
X118220Y264699D01*
G37*
G36*
G01X115296Y267623D02*
X115416Y267634D01*
X115832Y267764D01*
X116214Y267966D01*
X116550Y268243D01*
X116823Y268577D01*
X117024Y268958D01*
X117152Y269372D01*
X117191Y269799D01*
Y270889D01*
X117153Y271319D01*
X117021Y271734D01*
X116821Y272114D01*
X116546Y272449D01*
X116211Y272725D01*
X115829Y272925D01*
X115414Y273054D01*
X114987Y273094D01*
X114557Y273054D01*
X114141Y272924D01*
X113761Y272724D01*
X113426Y272449D01*
X113241Y272224D01*
Y269677D01*
X115296Y267623D01*
G37*
G36*
G01X104666Y272729D02*
X107276D01*
X107306Y272739D01*
X107686Y272939D01*
X107868Y273082D01*
X104666Y276284D01*
Y272729D01*
G37*
G36*
G01X108607Y274310D02*
X108611Y274324D01*
X108651Y274749D01*
X108611Y275174D01*
X108486Y275579D01*
X108286Y275959D01*
X108016Y276289D01*
X107686Y276559D01*
X107306Y276759D01*
X107221Y276789D01*
X106127D01*
X108607Y274310D01*
G37*
G36*
G01X392636Y473030D02*
X432636D01*
Y465780D01*
X442158D01*
Y455480D01*
X431886D01*
Y405030D01*
X399286D01*
Y455480D01*
X384614D01*
Y465780D01*
X392636D01*
Y473030D01*
G37*
%LPD*%
G75*
G36*
G01X427986Y412380D02*
G02X430986I1500J0D01*
G01Y407880D01*
G02X427986I-1500J0D01*
G01Y412380D01*
G37*
G36*
G01Y427341D02*
G02X430986I1500J0D01*
G01Y422841D01*
G02X427986I-1500J0D01*
G01Y427341D01*
G37*
G36*
G01Y442302D02*
G02X430986I1500J0D01*
G01Y437802D01*
G02X427986I-1500J0D01*
G01Y442302D01*
G37*
G36*
G01Y457263D02*
G02X430986I1500J0D01*
G01Y452763D01*
G02X427986I-1500J0D01*
G01Y457263D01*
G37*
G54D10*
G01X384168Y-102362D02*
G03X373695I-5236J0D01*
G01X352673D02*
G03X342200I-5237J0D01*
G01X447158D02*
G03X436686I-5236J0D01*
G01X415663D02*
G03X405191I-5236J0D01*
G01X510148D02*
G03X499676I-5236J0D01*
G01X478653D02*
G03X468181I-5236J0D01*
G54D11*
G01X-34018Y-300855D02*
G02I-12000J0D01*
G01X-39168D02*
G02I-6850J0D01*
G01X-30018D02*
X-62018D01*
G01X-30018Y-316855D02*
Y-396855D01*
G01D02*
X1320682D01*
G01X-30018Y-352355D02*
X1320682D01*
G01X-46018Y-316855D02*
Y-284855D01*
G01X-30018Y-316855D02*
X1320682D01*
G01X72050Y138800D02*
X81150D01*
G01X30300Y215000D02*
Y220000D01*
G01X59826Y247639D02*
Y252639D01*
G01X69005Y348507D02*
Y341807D01*
G01X26305Y348307D02*
Y341607D01*
G01X47305Y348107D02*
Y341407D01*
G01X91933Y121788D02*
X86933D01*
G01X107430Y121810D02*
X102430D01*
G01X99730Y121820D02*
X94730D01*
G01X138700Y195800D02*
X143700D01*
G01X90100Y348300D02*
Y341600D01*
G01X155800Y170900D02*
X150800D01*
G01X163800D02*
X158800D01*
G01X171800D02*
X166800D01*
G01X187298Y147880D02*
Y142880D01*
G01X146400Y195800D02*
X151400D01*
G01X154200D02*
X159200D01*
G01X169800D02*
X174800D01*
G01X161900D02*
X166900D01*
G01X232200Y359900D02*
Y364900D01*
G01X237032Y307405D02*
Y314105D01*
G01X255375Y307367D02*
Y314067D01*
G01X218800Y307400D02*
Y314100D01*
G01X232200Y367600D02*
Y372600D01*
G01Y375300D02*
Y380300D01*
G01X220000Y476000D02*
Y481000D01*
G01Y468000D02*
Y473000D01*
G01X242500Y448200D02*
Y464800D01*
G01X277702Y55800D02*
X287302D01*
G01X266400Y139200D02*
Y155800D01*
G01X265650Y230300D02*
Y246900D01*
G01X265600Y205200D02*
Y221800D01*
G01X328250Y281016D02*
X318650D01*
G01X274797Y307656D02*
Y314356D01*
G01X327559Y299345D02*
Y303995D01*
G01X500500Y551500D02*
Y500000D01*
X701500D01*
G01X533182Y-316855D02*
Y-396855D01*
G01X537000Y421400D02*
Y426400D01*
G01Y429000D02*
Y434000D01*
G01X551500Y437200D02*
Y453800D01*
G01X559460Y474670D02*
X565460D01*
G01X609170Y344898D02*
X601170D01*
G01X609170Y306489D02*
X601170D01*
G01X629400Y437400D02*
X624400D01*
G01X670682Y-316855D02*
Y-396855D01*
G01X653726Y41868D02*
Y51468D01*
G01X651400Y356900D02*
Y351900D01*
G01Y349200D02*
Y344200D01*
G01X698805Y325402D02*
X693805D01*
G01X651400Y341500D02*
Y336500D01*
G01X651423Y333807D02*
Y328807D01*
G01Y326124D02*
Y321124D01*
G01X649100Y368400D02*
X644100D01*
G01X707305Y325402D02*
X702305D01*
G01X710393Y364242D02*
Y347642D01*
G01Y339192D02*
Y322592D01*
G01X716398Y462229D02*
Y457229D01*
G01X729900Y466900D02*
Y471900D01*
G01X715900Y470400D02*
Y465400D01*
G01X715834Y478100D02*
Y473100D01*
G01Y485900D02*
Y480900D01*
G01X701500Y500000D02*
Y563000D01*
G01X785682Y-316855D02*
Y-396855D01*
G01X777408Y297951D02*
X785108D01*
G01X953182Y-316855D02*
Y-396855D01*
G01X1123182Y-316855D02*
Y-396855D01*
G01X1320682Y-316855D02*
Y-396855D01*
G01X1348682Y-300855D02*
G02I-12000J0D01*
G01X1343532D02*
G02I-6850J0D01*
G01X1336682Y-316855D02*
Y-284855D01*
G01X1352682Y-300855D02*
X1320682D01*
G54D12*
G01X15748Y0D02*
X46456D01*
G01X326770D02*
X287400D01*
G01X334655Y555512D02*
Y530315D01*
G01X492136Y555512D02*
Y530315D01*
G01X597707Y0D02*
X628416D01*
G01X811023D02*
X780315D01*
G54D13*
G01X48500Y147100D02*
X50000D01*
G01X56200Y133550D02*
Y127500D01*
X61450D01*
G01X33000Y398600D02*
Y401450D01*
X35700D01*
G01X81107Y392795D02*
Y389945D01*
X78407D01*
G01X140960Y487641D02*
X142460D01*
G01X223509Y77549D02*
X220659D01*
Y80249D01*
G01X243009Y77549D02*
X240159D01*
Y80249D01*
G01X292338Y300539D02*
X289488D01*
Y303239D01*
G01X279338Y300539D02*
X276488D01*
Y303239D01*
G01X336133Y212762D02*
X332161D01*
Y215690D01*
G01X327959Y298745D02*
X326109D01*
G01X327959Y304645D02*
X326109D01*
G01X332525Y433011D02*
X335375D01*
Y430311D01*
G01X620765Y179067D02*
Y183039D01*
X623693D01*
G01X597600Y424290D02*
X601600D01*
G01X675654Y435806D02*
X678504D01*
Y433106D01*
G01X793320Y331150D02*
X789320D01*
G54D14*
G01X38950Y295050D02*
X46700D01*
G01X38854Y322772D02*
X46604D01*
G54D15*
G01X607820Y369870D02*
X601120D01*
G01X607820Y392250D02*
X601120D01*
G01X768737Y276049D02*
X775437D01*
G54D16*
G01X149751Y271417D02*
G03I-10900J0D01*
G54D17*
G01X107533Y308110D02*
X106873D01*
G01X106973Y308200D02*
X107633D01*
G01X107723Y308310D02*
X107073D01*
G01X107173Y308400D02*
X107823D01*
G01X107923Y308510D02*
X107263D01*
G01X107363Y308610D02*
X108013D01*
G01X108113Y308700D02*
X107463D01*
G01X107553Y308810D02*
X108213D01*
G01X108303Y308900D02*
X107653D01*
G01X107743Y309010D02*
X108403D01*
G01X108503Y309110D02*
X107843D01*
G01X107943Y309200D02*
X108593D01*
G01X108693Y309310D02*
X108048D01*
G01X108043D02*
X108093D01*
G01X108133Y309400D02*
X108173D01*
G01X108133D02*
X108783D01*
G01X108883Y309510D02*
X108233D01*
G01X108333Y309610D02*
X108983D01*
G01X109083Y309700D02*
X108423D01*
G01X108523Y309810D02*
X109173D01*
G01X109273Y309900D02*
X108613D01*
G01X108713Y310010D02*
X109373D01*
G01X109463Y310110D02*
X108813D01*
G01X108913Y310200D02*
X109563D01*
G01X109653Y310310D02*
X109003D01*
G01X109103Y310400D02*
X109753D01*
G01X109853Y310510D02*
X109193D01*
G01X109293Y310610D02*
X109953D01*
G01X110043Y310700D02*
X109393D01*
G01X109483Y310810D02*
X110143D01*
G01X110333Y311010D02*
X109683D01*
G01X109873Y311200D02*
X110523D01*
G01X105233Y325620D02*
X105263Y325640D01*
G01X105233Y325080D02*
Y325620D01*
G01X105243Y325060D02*
X105233Y325080D01*
G01X105293Y324950D02*
X105243Y325060D01*
G01X105303Y324940D02*
X105293Y324950D01*
G01X110483Y319350D02*
X105303Y324940D01*
G01X105233Y325610D02*
X105293D01*
G01X105233Y325510D02*
X105383D01*
G01X105473Y325400D02*
X105233D01*
G01Y325310D02*
X105573D01*
G01X105663Y325200D02*
X105233D01*
G01Y325110D02*
X105753D01*
G01X105853Y325010D02*
X105263D01*
G01X105333Y324900D02*
X105943D01*
G01X106033Y324810D02*
X105423D01*
G01X105513Y324700D02*
X106123D01*
G01X106223Y324610D02*
X105613D01*
G01X105703Y324510D02*
X106313D01*
G01X106403Y324400D02*
X105793D01*
G01X105883Y324310D02*
X106503D01*
G01X106593Y324200D02*
X105983D01*
G01X106073Y324110D02*
X106683D01*
G01X106783Y324010D02*
X106163D01*
G01X106263Y323900D02*
X106873D01*
G01X106963Y323810D02*
X106353D01*
G01X106443Y323700D02*
X107063D01*
G01X107153Y323610D02*
X106543D01*
G01X106633Y323510D02*
X107243D01*
G01X107343Y323400D02*
X106723D01*
G01X106813Y323310D02*
X107433D01*
G01X107523Y323200D02*
X106913D01*
G01X107003Y323110D02*
X107613D01*
G01X107713Y323010D02*
X107093D01*
G01X107193Y322900D02*
X107803D01*
G01X107893Y322810D02*
X107283D01*
G01X107373Y322700D02*
X107983D01*
G01X108083Y322610D02*
X107473D01*
G01X107563Y322510D02*
X108173D01*
G01X108263Y322400D02*
X107653D01*
G01X107743Y322310D02*
X108363D01*
G01X108453Y322200D02*
X107843D01*
G01X107933Y322110D02*
X108543D01*
G01X108643Y322010D02*
X108023D01*
G01X108113Y321900D02*
X108733D01*
G01X108823Y321810D02*
X108213D01*
G01X108303Y321700D02*
X108923D01*
G01X109013Y321610D02*
X108393D01*
G01X108483Y321510D02*
X109103D01*
G01X109203Y321400D02*
X108583D01*
G01X108673Y321310D02*
X109293D01*
G01X109383Y321200D02*
X108763D01*
G01X108853Y321110D02*
X109483D01*
G01X109573Y321010D02*
X108953D01*
G01X109043Y320900D02*
X109663D01*
G01X109753Y320810D02*
X109133D01*
G01X109233Y320700D02*
X109853D01*
G01X109943Y320610D02*
X109323D01*
G01X109413Y320510D02*
X110033D01*
G01X110133Y320400D02*
X109513D01*
G01X109693Y320200D02*
X110933D01*
G01X110943Y320010D02*
X109883D01*
G01X109633Y322300D02*
X110143D01*
G01X109593Y322260D02*
X109633Y322300D01*
G01X109593Y321800D02*
Y322260D01*
G01X109633Y321760D02*
X109593Y321800D01*
G01Y322200D02*
X119843D01*
G01X119773Y322010D02*
X109593D01*
G01Y321810D02*
X119613D01*
G01X112243Y323110D02*
X110813D01*
G01X110233Y322370D02*
X110143Y322300D01*
G01X110253Y322420D02*
X110233Y322370D01*
G01X110253Y322430D02*
Y322420D01*
G01X110373Y322680D02*
X110253Y322430D01*
G01X110393Y322690D02*
X110373Y322680D01*
G01X110823Y323110D02*
X110393Y322690D01*
G01X110153Y322310D02*
X110883D01*
G01X110993Y322640D02*
X111103Y322710D01*
G01X110823Y322470D02*
X110993Y322640D01*
G01X110803Y322360D02*
X110823Y322470D01*
G01X110893Y322300D02*
X110803Y322360D01*
G01X110963Y322610D02*
X110343D01*
G01X110293Y322510D02*
X110863D01*
G01X110813Y322400D02*
X110243D01*
G01X110503Y322810D02*
X112183D01*
G01Y323010D02*
X110713D01*
G01X111063Y319410D02*
X114293Y315930D01*
G01X111053Y319410D02*
X111063D01*
G01X111013Y319460D02*
X111053Y319410D01*
G01X110983Y319520D02*
X111013Y319460D01*
G01X110803Y321650D02*
X110983Y319520D01*
G01X110903Y321760D02*
X110803Y321650D01*
G01X111323Y315610D02*
X110853D01*
G01X110843Y315810D02*
X111303D01*
G01X111283Y316010D02*
X110823D01*
G01X110803Y316200D02*
X111273D01*
G01X111253Y316400D02*
X110783D01*
G01X110763Y316610D02*
X111233D01*
G01X111223Y316810D02*
X110753D01*
G01X110733Y317010D02*
X111203D01*
G01X111183Y317200D02*
X110713D01*
G01X110703Y317400D02*
X111173D01*
G01X111153Y317610D02*
X110683D01*
G01X110663Y317810D02*
X111133D01*
G01X111113Y318010D02*
X110653D01*
G01X110633Y318200D02*
X111103D01*
G01X111083Y318400D02*
X110613D01*
G01X110603Y318510D02*
X111113D01*
G01X111613Y318810D02*
X110583D01*
G01X110563Y319010D02*
X111433D01*
G01X110503Y319320D02*
X110483Y319350D01*
G01X110543Y319220D02*
X110503Y319320D01*
G01X110543Y319210D02*
Y319220D01*
G01Y319200D02*
Y319210D01*
G01X111243Y319200D02*
X110543D01*
G01X110443Y319400D02*
X111063D01*
G01X110993Y319510D02*
X110343D01*
G01X110253Y319610D02*
X110983D01*
G01X110973Y319700D02*
X110163D01*
G01X110063Y319810D02*
X110963D01*
G01X110953Y319900D02*
X109973D01*
G01X109783Y320110D02*
X110933D01*
G01X110923Y320310D02*
X110443D01*
G01X110233Y321760D02*
X109633D01*
G01X110333Y321670D02*
X110233Y321760D01*
G01X110453Y320320D02*
X110333Y321670D01*
G01X110293Y321700D02*
X110853D01*
G01X110803Y321610D02*
X110343D01*
G01X110353Y321510D02*
X110823D01*
G01Y321400D02*
X110353D01*
G01X110363Y321310D02*
X110833D01*
G01X110843Y321200D02*
X110373D01*
G01X110383Y321110D02*
X110853D01*
G01X110863Y321010D02*
X110393D01*
G01X110403Y320900D02*
X110873D01*
G01Y320810D02*
X110413D01*
G01Y320700D02*
X110883D01*
G01X110893Y320610D02*
X110433D01*
G01Y320510D02*
X110903D01*
G01X110913Y320400D02*
X110443D01*
G01X110283Y320250D02*
X105263Y325640D01*
G01X110393Y320220D02*
X110283Y320250D01*
G01X110453Y320320D02*
X110393Y320220D01*
G01X109603Y320310D02*
X110223D01*
G01X110543Y319200D02*
X110983Y314050D01*
G01X110993Y314010D02*
X111463D01*
G01X111473Y313810D02*
X111003D01*
G01X111023Y313610D02*
X111493D01*
G01X111513Y313400D02*
X111043D01*
G01X111063Y313200D02*
X111533D01*
G01X111573Y313110D02*
X111073D01*
G01X111083Y312460D02*
X110983Y312350D01*
G01X111113Y312530D02*
X111083Y312460D01*
G01X110933Y312310D02*
X111623D01*
G01Y312110D02*
X110743D01*
G01X110553Y311900D02*
X111643D01*
G01X111003Y311700D02*
X110353D01*
G01X110263Y311610D02*
X110913D01*
G01X110813Y311510D02*
X110163D01*
G01X110063Y311400D02*
X110723D01*
G01X110623Y311310D02*
X109973D01*
G01X109783Y311110D02*
X110433D01*
G01X110233Y310900D02*
X109583D01*
G01X110963Y314310D02*
X111433D01*
G01X111413Y314510D02*
X110953D01*
G01X110933Y314700D02*
X111403D01*
G01X111383Y314900D02*
X110913D01*
G01X110893Y315110D02*
X111363D01*
G01X111353Y315310D02*
X110883D01*
G01X110873Y315400D02*
X111343D01*
G01X111333Y315510D02*
X110863D01*
G01X110843Y315700D02*
X111313D01*
G01X111303Y315900D02*
X110833D01*
G01X110813Y316110D02*
X111283D01*
G01X111263Y316310D02*
X110793D01*
G01X110783Y316510D02*
X111243D01*
G01X111223Y316700D02*
X110763D01*
G01X110743Y316900D02*
X111213D01*
G01X111193Y317110D02*
X110723D01*
G01X110713Y317310D02*
X111173D01*
G01X111163Y317510D02*
X110693D01*
G01X110673Y317700D02*
X111143D01*
G01X111123Y317900D02*
X110653D01*
G01X110643Y318110D02*
X111103D01*
G01X111093Y318310D02*
X110623D01*
G01X111253Y318530D02*
X113983Y315590D01*
G01X111133Y318550D02*
X111253Y318530D01*
G01X111083Y318450D02*
X111133Y318550D01*
G01X111353Y315200D02*
X110893D01*
G01X110903Y315010D02*
X111373D01*
G01X111393Y314810D02*
X110923D01*
G01X110943Y314610D02*
X111413D01*
G01X111423Y314400D02*
X110953D01*
G01X110973Y314200D02*
X111443D01*
G01X111453Y314110D02*
X110983D01*
G01X111113Y312590D02*
Y312530D01*
G01X110983Y314050D02*
X111113Y312590D01*
G01X111103Y312510D02*
X111783D01*
G01X111633Y312330D02*
X111613Y312260D01*
G01X111683Y312410D02*
X111633Y312330D01*
G01X111613Y312200D02*
X110843D01*
G01X110653Y312010D02*
X111633D01*
G01X111653Y311700D02*
X111153D01*
G01X111123Y311740D02*
X111023Y311720D01*
G01X111393Y309300D02*
X111503D01*
G01X111393Y309310D02*
Y309300D01*
G01X111193Y311660D02*
X111393Y309310D01*
G01X111123Y311740D02*
X111193Y311660D01*
G01X111493Y309400D02*
X111383D01*
G01X111388D02*
X116983D01*
G01X117048Y309310D02*
X111393D01*
G01X111633Y308260D02*
X112523D01*
G01X111593Y308300D02*
X111633Y308260D01*
G01X111593Y308980D02*
Y308300D01*
G01X111563Y309050D02*
X111593Y308980D01*
G01X111413Y309210D02*
X111563Y309050D01*
G01X111403Y309230D02*
X111413Y309210D01*
G01X111393Y309290D02*
X111403Y309230D01*
G01X112563Y308310D02*
X111593D01*
G01Y308510D02*
X112563D01*
G01Y308700D02*
X111593D01*
G01Y308900D02*
X112563D01*
G01X111843Y309610D02*
X111373D01*
G01X111353Y309700D02*
X111823D01*
G01X111813Y309900D02*
X111343D01*
G01X111323Y310110D02*
X111793D01*
G01X111773Y310310D02*
X111303D01*
G01X111293Y310510D02*
X111763D01*
G01X111743Y310700D02*
X111273D01*
G01X111253Y310900D02*
X111723D01*
G01X111713Y311110D02*
X111243D01*
G01X111223Y311310D02*
X111693D01*
G01X111673Y311510D02*
X111213D01*
G01X111103Y312700D02*
X111973D01*
G01X112163Y312900D02*
X111083D01*
G01X111053Y313310D02*
X111523D01*
G01X111533Y313160D02*
X111083Y318450D01*
G01X111273Y318510D02*
X111893D01*
G01X112083Y318310D02*
X111463D01*
G01X111643Y318110D02*
X112263D01*
G01X111523Y318900D02*
X110573D01*
G01X110553Y319110D02*
X111343D01*
G01X111153Y319310D02*
X110513D01*
G01X111213Y322720D02*
X111103Y322710D01*
G01X111263Y322630D02*
X111213Y322720D01*
G01X111263Y322400D02*
Y322630D01*
G01X111163Y322300D02*
X111263Y322400D01*
G01X110893Y322300D02*
X111163D01*
G01X111093Y322700D02*
X110403D01*
G01X111273Y323690D02*
X111303Y323710D01*
G01X111263Y323660D02*
X111273Y323690D01*
G01X111263Y323460D02*
Y323660D01*
G01X111253Y323420D02*
X111263Y323460D01*
G01X111233Y323370D02*
X111253Y323420D01*
G01X111183Y323310D02*
X111233Y323370D01*
G01X111093Y323270D02*
X111183Y323310D01*
G01X110823Y323110D02*
X111093Y323270D01*
G01X111303Y323700D02*
X112133D01*
G01X111263Y323510D02*
X114153D01*
G01X114143Y323310D02*
X111163D01*
G01X111213Y322700D02*
X112183D01*
G01Y322510D02*
X111263D01*
G01X111173Y322310D02*
X112283D01*
G01X111473Y313900D02*
X111003D01*
G01X111013Y313700D02*
X111483D01*
G01X111503Y313510D02*
X111033D01*
G01X111603Y313070D02*
X111703Y313100D01*
G01X111533Y313160D02*
X111603Y313070D01*
G01X111513Y309110D02*
X117293D01*
G01X111833Y309680D02*
X111613Y312260D01*
G01X111833Y309610D02*
Y309680D01*
G01X111933Y309520D02*
X111833Y309610D01*
G01X116033Y309520D02*
X111933D01*
G01X111683Y312400D02*
X111033D01*
G01X111113Y312610D02*
X111873D01*
G01X111693Y312410D02*
X111683D01*
G01X111693Y312420D02*
Y312410D01*
G01Y312420D02*
X114283Y315110D01*
G01X114093Y314900D02*
X113453D01*
G01X113253Y314700D02*
X113903D01*
G01X113713Y314510D02*
X113063D01*
G01X112873Y314310D02*
X113513D01*
G01X113423Y314200D02*
X112773D01*
G01X112823Y314260D02*
X111703Y313100D01*
G01X111713Y313110D02*
X112353D01*
G01X112263Y313010D02*
X111083D01*
G01X111093Y312810D02*
X112073D01*
G01X111813Y313200D02*
X112453D01*
G01X112553Y313310D02*
X111913D01*
G01X112003Y313400D02*
X112653D01*
G01X112743Y313510D02*
X112103D01*
G01X112193Y313610D02*
X112843D01*
G01X112933Y313700D02*
X112293D01*
G01X112393Y313810D02*
X113033D01*
G01X113133Y313900D02*
X112483D01*
G01X112583Y314010D02*
X113223D01*
G01X113323Y314110D02*
X112673D01*
G01X113503Y316110D02*
X114133D01*
G01X113943Y316310D02*
X113323D01*
G01X113133Y316510D02*
X113753D01*
G01X113573Y316700D02*
X112943D01*
G01X112853Y316810D02*
X113473D01*
G01X113383Y316900D02*
X112763D01*
G01X112673Y317010D02*
X113293D01*
G01X113193Y317110D02*
X112573D01*
G01X112483Y317200D02*
X113103D01*
G01X113013Y317310D02*
X112393D01*
G01X112293Y317400D02*
X112923D01*
G01X112823Y317510D02*
X112203D01*
G01X112113Y317610D02*
X112733D01*
G01X112643Y317700D02*
X112013D01*
G01X111923Y317810D02*
X112543D01*
G01X112453Y317900D02*
X111833D01*
G01X111743Y318010D02*
X112363D01*
G01X112173Y318200D02*
X111553D01*
G01X111363Y318400D02*
X111983D01*
G01X111803Y318610D02*
X110603D01*
G01X110593Y318700D02*
X111713D01*
G01X113563Y317980D02*
X113603Y317940D01*
G01X112183Y322400D02*
X111263D01*
G01X112283Y322300D02*
X112183Y322400D01*
G01X111263Y322610D02*
X112183D01*
G01X113513Y323310D02*
X113623Y323200D01*
G01X113243Y323280D02*
X113513Y323310D01*
G01X112963Y323250D02*
X113243Y323280D01*
G01X112843Y323240D02*
X112963Y323250D01*
G01X112743Y323220D02*
X112843Y323240D01*
G01X112493Y323180D02*
X112743Y323220D01*
G01X112483Y323180D02*
X112493D01*
G01X112393Y323160D02*
X112483Y323180D01*
G01X112383Y323160D02*
X112393D01*
G01X112263Y323140D02*
X112383Y323160D01*
G01X112183Y323040D02*
X112263Y323140D01*
G01X112183Y322400D02*
Y323040D01*
G01X112123Y323710D02*
X111303D01*
G01X112143Y323700D02*
X112123Y323710D01*
G01X112173Y323690D02*
X112143Y323700D01*
G01X112203Y323670D02*
X112173Y323690D01*
G01X112283Y323650D02*
X112203Y323670D01*
G01X112303Y323660D02*
X112283Y323650D01*
G01X112543Y323700D02*
X112303Y323660D01*
G01X113043Y323770D02*
X112543Y323700D01*
G01X113163Y323780D02*
X113043Y323770D01*
G01X113223Y323780D02*
X113163D01*
G01X113383Y323800D02*
X113223Y323780D01*
G01X113523Y323810D02*
X113383Y323800D01*
G01X110983Y323200D02*
X112633D01*
G01X112183Y322900D02*
X110613D01*
G01X112283Y322300D02*
X118123D01*
G01X116193Y323810D02*
X113503D01*
G01X113523D02*
X113623Y323910D01*
G01X111653Y311810D02*
X110453D01*
G01X111193Y311610D02*
X111663D01*
G01X111683Y311400D02*
X111213D01*
G01X111233Y311200D02*
X111703D01*
G01X111713Y311010D02*
X111243D01*
G01X111263Y310810D02*
X111733D01*
G01X111753Y310610D02*
X111283D01*
G01X111303Y310400D02*
X111763D01*
G01X111783Y310200D02*
X111323D01*
G01X111333Y310010D02*
X111803D01*
G01X111823Y309810D02*
X111353D01*
G01X111583Y309010D02*
X112633D01*
G01X112563Y308300D02*
X112523Y308260D01*
G01X112563Y308940D02*
Y308300D01*
G01X112663Y309040D02*
X112563Y308940D01*
G01Y308400D02*
X111593D01*
G01Y308610D02*
X112563D01*
G01Y308810D02*
X111593D01*
G01X116133Y309990D02*
Y310000D01*
G01X116123Y309920D02*
X116133Y309990D01*
G01X116123Y309660D02*
Y309920D01*
G01X116133Y309640D02*
X116123Y309660D01*
G01X116033Y309520D02*
X116133Y309640D01*
G01Y310010D02*
X116903D01*
G01X116863Y309810D02*
X116123D01*
G01X116103Y309610D02*
X116903D01*
G01X114743Y315440D02*
Y315580D01*
G01X117443Y312540D02*
X114743Y315440D01*
G01X114763Y315610D02*
X113973D01*
G01X113983Y315450D02*
X112823Y314260D01*
G01X113983Y315590D02*
Y315450D01*
G01X112973Y314400D02*
X113613D01*
G01X113803Y314610D02*
X113163D01*
G01X113353Y314810D02*
X114003D01*
G01X114193Y315010D02*
X113543D01*
G01X114433Y315110D02*
X116113Y313290D01*
G01X114283Y315110D02*
X114433D01*
G01X113643D02*
X114283D01*
G01X116103Y313310D02*
X116733D01*
G01X116543Y313510D02*
X115913D01*
G01X115733Y313700D02*
X116363D01*
G01X116173Y313900D02*
X115543D01*
G01X115453Y314010D02*
X116083D01*
G01X115983Y314110D02*
X115353D01*
G01X115263Y314200D02*
X115893D01*
G01X115803Y314310D02*
X115173D01*
G01X115083Y314400D02*
X115713D01*
G01X115613Y314510D02*
X114983D01*
G01X114893Y314610D02*
X115523D01*
G01X115433Y314700D02*
X114803D01*
G01X114713Y314810D02*
X115343D01*
G01X115243Y314900D02*
X114613D01*
G01X114523Y315010D02*
X115153D01*
G01X115063Y315110D02*
X114413D01*
G01X114783Y315400D02*
X113933D01*
G01X113983Y315510D02*
X114743D01*
G01X114863Y315700D02*
X113873D01*
G01X113783Y315810D02*
X114963D01*
G01X115063Y315900D02*
X113693D01*
G01X113603Y316010D02*
X114223D01*
G01X114433Y315930D02*
X115863Y317400D01*
G01X114293Y315930D02*
X114433D01*
G01X115763Y317310D02*
X116403D01*
G01X116213Y317110D02*
X115573D01*
G01X115483Y317010D02*
X116113D01*
G01X116023Y316900D02*
X115383D01*
G01X115283Y316810D02*
X115923D01*
G01X115833Y316700D02*
X115193D01*
G01X115093Y316610D02*
X115733D01*
G01X115633Y316510D02*
X114993D01*
G01X114903Y316400D02*
X115543D01*
G01X115443Y316310D02*
X114803D01*
G01X114713Y316200D02*
X115343D01*
G01X115253Y316110D02*
X114613D01*
G01X114513Y316010D02*
X115153D01*
G01X114873Y315310D02*
X113843D01*
G01X113743Y315200D02*
X114963D01*
G01X114033Y316200D02*
X113413D01*
G01X113223Y316400D02*
X113853D01*
G01X113663Y316610D02*
X113043D01*
G01X113653Y317940D02*
X116143D01*
G01X113603D02*
X113653D01*
G01X116153Y317700D02*
X116793D01*
G01X116603Y317510D02*
X115963D01*
G01X117083Y318010D02*
X113563D01*
G01X113603Y318970D02*
X113653D01*
G01X113563Y318930D02*
X113603Y318970D01*
G01X113563Y317980D02*
Y318930D01*
G01Y318810D02*
X116823D01*
G01X116853Y318610D02*
X113563D01*
G01Y318400D02*
X117473D01*
G01X117273Y318200D02*
X113563D01*
G01X113623Y322860D02*
Y323200D01*
G01X113663Y322810D02*
X113623Y322860D01*
G01X113613Y323200D02*
X116243D01*
G01X116113Y322810D02*
X113663D01*
G01X116163Y322860D02*
X116113Y322810D01*
G01X116163Y323140D02*
Y322860D01*
G01X113623Y322900D02*
X116163D01*
G01Y323010D02*
X113623D01*
G01Y323110D02*
X116163D01*
G01X115713Y323420D02*
Y323380D01*
G01X115613Y323520D02*
X115713Y323420D01*
G01X114173Y323520D02*
X115613D01*
G01X114073Y323420D02*
X114173Y323520D01*
G01X114073Y323380D02*
Y323420D01*
G01X114173Y323270D02*
X114073Y323380D01*
G01X115613Y323270D02*
X114173D01*
G01X115713Y323380D02*
X115613Y323270D01*
G01X115713Y323400D02*
X117683D01*
G01X117393Y323510D02*
X115623D01*
G01X113623Y323940D02*
Y323910D01*
G01X113663Y323980D02*
X113623Y323940D01*
G01X116113Y323980D02*
X113663D01*
G01X116163Y323940D02*
X116113Y323980D01*
G01X116163Y323840D02*
Y323940D01*
G01X113613Y323900D02*
X116163D01*
G01X114073Y323400D02*
X111243D01*
G01X111263Y323610D02*
X117023D01*
G01X116243Y323740D02*
X116163Y323840D01*
G01X116293Y323740D02*
X116243D01*
G01X116853Y323650D02*
X116293Y323740D01*
G01X117033Y323610D02*
X116853Y323650D01*
G01X116473Y323700D02*
X112603D01*
G01X116673Y323170D02*
X117083Y323080D01*
G01X116383Y323220D02*
X116673Y323170D01*
G01X116353Y323220D02*
X116383D01*
G01X116273Y323240D02*
X116353Y323220D01*
G01X116163Y323140D02*
X116273Y323240D01*
G01X116463Y323200D02*
X118053D01*
G01X116773Y318970D02*
X113653D01*
G01X113563Y318900D02*
X116823D01*
G01X116813Y318930D02*
X116773Y318970D01*
G01X116993Y318580D02*
X117193Y318780D01*
G01X116883Y318550D02*
X116993Y318580D01*
G01X116823Y318650D02*
X116883Y318550D01*
G01X116823Y318830D02*
Y318650D01*
G01Y318840D02*
Y318830D01*
G01X116813Y318930D02*
X116823Y318840D01*
G01X117023Y318610D02*
X117663D01*
G01X116823Y318700D02*
X113563D01*
G01X115673Y317200D02*
X116313D01*
G01X116233Y317880D02*
X116143Y317940D01*
G01X116213Y317770D02*
X116233Y317880D01*
G01X115863Y317400D02*
X116213Y317770D01*
G01X116503Y317400D02*
X115863D01*
G01X116193Y317900D02*
X116983D01*
G01X116893Y317810D02*
X116223D01*
G01X116063Y317610D02*
X116693D01*
G01X116263Y313810D02*
X115633D01*
G01X115823Y313610D02*
X116453D01*
G01X116633Y313400D02*
X116003D01*
G01X116193Y313200D02*
X116823D01*
G01X116913Y313110D02*
X116283D01*
G01X116373Y313010D02*
X117013D01*
G01X117103Y312900D02*
X116473D01*
G01X116563Y312810D02*
X117193D01*
G01X117383Y312610D02*
X116753D01*
G01X116933Y312400D02*
X118073D01*
G01X118063Y312310D02*
X117033D01*
G01X116173Y310180D02*
X116133Y310000D01*
G01X116173Y310190D02*
Y310180D01*
G01X116283Y310500D02*
X116173Y310190D01*
G01X116293Y310510D02*
X116283Y310500D01*
G01X116503Y310820D02*
X116293Y310510D01*
G01X116513Y310830D02*
X116503Y310820D01*
G01X116753Y311050D02*
X116513Y310830D01*
G01X116763Y311050D02*
X116753D01*
G01X116883Y311130D02*
X116763Y311050D01*
G01X116893Y311140D02*
X116883Y311130D01*
G01X116953Y311170D02*
X116893Y311140D01*
G01X117113Y311240D02*
X116953Y311170D01*
G01X116123Y309900D02*
X116883D01*
G01X116923Y309510D02*
X111373D01*
G01X116913Y309530D02*
X116923Y309510D01*
G01X116863Y309790D02*
X116913Y309530D01*
G01X116863Y309800D02*
Y309790D01*
G01Y309820D02*
Y309800D01*
G01X111413Y309200D02*
X117153D01*
G01X117073Y309270D02*
X117013Y309360D01*
G01X117083Y309260D02*
X117073Y309270D01*
G01X117093Y309250D02*
X117083Y309260D01*
G01X116933Y309500D02*
X116923Y309510D01*
G01X117013Y309370D02*
X116933Y309500D01*
G01X116883Y309700D02*
X116123D01*
G01X116153Y310110D02*
X116923D01*
G01X116913Y310080D02*
X116863Y309820D01*
G01X116923Y310100D02*
X116913Y310080D01*
G01X117143Y309830D02*
X117153Y309850D01*
G01X117093Y310360D02*
X117313Y310520D01*
G01X117083Y310350D02*
X117093Y310360D01*
G01X117073Y310330D02*
X117083Y310350D01*
G01X116933Y310120D02*
X117073Y310330D01*
G01X116923Y310100D02*
X116933Y310120D01*
G01X117153Y310400D02*
X116253D01*
G01X116213Y310310D02*
X117053D01*
G01X116983Y310200D02*
X116173D01*
G01X116353Y310610D02*
X117613D01*
G01X117023Y311200D02*
X118693D01*
G01X118783Y311110D02*
X116843D01*
G01X116603Y310900D02*
X118973D01*
G01X119153Y310700D02*
X116433D01*
G01X117013Y309310D02*
X117053D01*
G01X117093Y309250D02*
X117313Y309090D01*
G01X116883Y308510D02*
X118433D01*
G01X118593Y308610D02*
X116703D01*
G01X116263Y309040D02*
X112663D01*
G01X116343Y309010D02*
X116263Y309040D01*
G01X116353Y309000D02*
X116343Y309010D01*
G01X116353Y308990D02*
Y309000D01*
G01X116393Y308920D02*
X116353Y308990D01*
G01X116403Y308920D02*
X116393D01*
G01X116413Y308910D02*
X116403Y308920D01*
G01X116483Y308810D02*
X116413Y308910D01*
G01X116493Y308800D02*
X116483Y308810D01*
G01X116723Y308580D02*
X116493Y308800D01*
G01Y308810D02*
X118833D01*
G01X116743Y308570D02*
X116723Y308580D01*
G01X117543Y308270D02*
X117883Y308280D01*
G01X117533Y308270D02*
X117543D01*
G01X117523D02*
X117533D01*
G01X117363Y308290D02*
X117523Y308270D01*
G01X117343Y308290D02*
X117363D01*
G01X116743Y308570D02*
X117343Y308290D01*
G01X117993Y308310D02*
X117323D01*
G01Y309080D02*
X117313Y309090D01*
G01X117343Y309080D02*
X117323D01*
G01X117513Y309020D02*
X117343Y309080D01*
G01X117733Y309010D02*
X117753D01*
G01X117603D02*
X117733D01*
G01X117533Y309020D02*
X117603Y309010D01*
G01X117513Y309020D02*
X117533D01*
G01X117173Y309640D02*
X117143Y309830D01*
G01X117183Y309610D02*
X117173Y309640D01*
G01X117353Y309390D02*
X117183Y309610D01*
G01X117373Y309380D02*
X117353Y309390D01*
G01X117543Y309300D02*
X117373Y309380D01*
G01X117553Y309300D02*
X117543D01*
G01X117593Y309290D02*
X117553Y309300D01*
G01X117653Y309290D02*
X117593D01*
G01X117673D02*
X117653D01*
G01X117703Y310320D02*
X117713D01*
G01X117613D02*
X117703D01*
G01X117593Y310310D02*
X117613Y310320D01*
G01X117283Y310150D02*
X117593Y310310D01*
G01X117263Y310130D02*
X117283Y310150D01*
G01X117153Y309850D02*
X117263Y310130D01*
G01X117323Y310530D02*
X117313Y310520D01*
G01X117343Y310530D02*
X117323D01*
G01X117513Y310590D02*
X117343Y310530D01*
G01X117533Y310590D02*
X117513D01*
G01X117603Y310600D02*
X117533Y310590D01*
G01X117623Y310610D02*
X117603Y310600D01*
G01X117683Y310610D02*
X117623D01*
G01X117713Y310600D02*
X117683Y310610D01*
G01X117293Y310510D02*
X116293D01*
G01X117203Y309990D02*
X118143D01*
G01X118163Y309790D02*
X117153D01*
G01X117203Y309590D02*
X118113D01*
G01X117933Y309390D02*
X117363D01*
G01X117673Y309290D02*
X117803Y309310D01*
G01X118003Y310180D02*
X117353D01*
G01X117753Y310600D02*
X117953Y310550D01*
G01X117713Y310600D02*
X117753D01*
G01X117203Y311270D02*
X117113Y311240D01*
G01X117213Y311280D02*
X117203Y311270D01*
G01X117353Y311310D02*
X117213Y311280D01*
G01X117433Y311330D02*
X117353Y311310D01*
G01X117213Y312110D02*
X116113Y313290D01*
G01X117473Y311830D02*
X117213Y312110D01*
G01X117503Y311780D02*
X117473Y311830D01*
G01X117533Y311630D02*
X117503Y311780D01*
G01X117543Y311610D02*
X117533Y311630D01*
G01X117543Y311590D02*
Y311610D01*
G01X117523Y311420D02*
X117543Y311590D01*
G01X117523Y311410D02*
Y311420D01*
G01X117433Y311330D02*
X117523Y311410D01*
G01X116653Y312700D02*
X117293D01*
G01X117613Y312600D02*
X118123Y318830D01*
G01X117553Y312520D02*
X117613Y312600D01*
G01X117443Y312540D02*
X117553Y312520D01*
G01X117213Y318810D02*
X117193Y318780D01*
G01X117853Y318810D02*
X117213D01*
G01D02*
X118023Y319650D01*
G01X117603Y319200D02*
X119863D01*
G01Y319010D02*
X117413D01*
G01X117113Y318700D02*
X117753D01*
G01X117563Y318510D02*
X113563D01*
G01Y318310D02*
X117373D01*
G01X117173Y318110D02*
X113563D01*
G01X117783Y314610D02*
X118243D01*
G01X118233Y314400D02*
X117763D01*
G01X117743Y314200D02*
X118213D01*
G01X118203Y314010D02*
X117733D01*
G01X117713Y313810D02*
X118183D01*
G01X118173Y313610D02*
X117703D01*
G01X117683Y313400D02*
X118153D01*
G01X118133Y313200D02*
X117673D01*
G01X117653Y313010D02*
X118113D01*
G01X118103Y312810D02*
X117633D01*
G01X117613Y312610D02*
X118083D01*
G01X118043Y312110D02*
X117213D01*
G01X117403Y311900D02*
X118043D01*
G01X118223Y311700D02*
X117523D01*
G01X117533Y311510D02*
X118413D01*
G01X117363Y323000D02*
X117083Y323080D01*
G01X117373Y322990D02*
X117363Y323000D01*
G01X117483Y322960D02*
X117373Y322990D01*
G01X117483Y322950D02*
Y322960D01*
G01X117593Y322910D02*
X117483Y322950D01*
G01X117603Y322900D02*
X117593Y322910D01*
G01X118463Y322900D02*
X117603D01*
G01X117323Y323010D02*
X118353D01*
G01X117153Y323570D02*
X117033Y323610D01*
G01X117263Y323550D02*
X117153Y323570D01*
G01X117503Y323470D02*
X117263Y323550D01*
G01X117613Y323430D02*
X117503Y323470D01*
G01X117673Y323410D02*
X117613Y323430D01*
G01X116963Y323110D02*
X118213D01*
G01X117893Y323310D02*
X115643D01*
G01X118213Y322350D02*
X118123Y322300D01*
G01X118203Y322450D02*
X118213Y322350D01*
G01X118133Y322560D02*
X118203Y322450D01*
G01X118113Y322580D02*
X118133Y322560D01*
G01X117813Y322800D02*
X118113Y322580D01*
G01X117803Y322810D02*
X117813Y322800D01*
G01X117793Y322810D02*
X117803D01*
G01X117603Y322900D02*
X117793Y322810D01*
G01X118133Y322310D02*
X119853D01*
G01X119833Y322510D02*
X118173D01*
G01X117943Y322700D02*
X119753D01*
G01X119863Y320700D02*
X118083D01*
G01X118053Y319680D02*
X118023Y319650D01*
G01X118083Y319740D02*
X118053Y319680D01*
G01X118083Y320760D02*
Y319740D01*
G01X117983Y319610D02*
X118653D01*
G01X118823Y319810D02*
X118083D01*
G01Y320010D02*
X119013D01*
G01X119203Y320200D02*
X118083D01*
G01Y320310D02*
X119863D01*
G01Y320510D02*
X118083D01*
G01X118193Y320840D02*
X118293Y320940D01*
G01X118123Y320840D02*
X118193D01*
G01X118083Y320800D02*
X118123Y320840D01*
G01X118083Y320760D02*
Y320800D01*
G01X117793Y319400D02*
X119863D01*
G01X118583Y318700D02*
X118113D01*
G01X117953Y318910D02*
X114743Y315580D01*
G01X118063Y318930D02*
X117953Y318910D01*
G01X118123Y318830D02*
X118063Y318930D01*
G01X117843Y315400D02*
X118313D01*
G01X118323Y315510D02*
X117853D01*
G01X117873Y315700D02*
X118343D01*
G01X118353Y315900D02*
X117893D01*
G01X117903Y316110D02*
X118373D01*
G01X118383Y316310D02*
X117923D01*
G01X117933Y316510D02*
X118403D01*
G01X118423Y316700D02*
X117953D01*
G01X117973Y316900D02*
X118433D01*
G01X118453Y317110D02*
X117983D01*
G01X118003Y317310D02*
X118473D01*
G01X118483Y317510D02*
X118023D01*
G01X118033Y317700D02*
X118503D01*
G01X118513Y317900D02*
X118053D01*
G01X118063Y318110D02*
X118533D01*
G01X118553Y318310D02*
X118083D01*
G01X118103Y318510D02*
X118563D01*
G01X117953Y318900D02*
X117313D01*
G01X117833Y315200D02*
X118303D01*
G01X118283Y315010D02*
X117813D01*
G01X117803Y314810D02*
X118263D01*
G01X118253Y314700D02*
X117793D01*
G01X117773Y314510D02*
X118243D01*
G01X118223Y314310D02*
X117753D01*
G01X117743Y314110D02*
X118213D01*
G01X118193Y313900D02*
X117723D01*
G01X117713Y313700D02*
X118173D01*
G01X118163Y313510D02*
X117693D01*
G01X117673Y313310D02*
X118143D01*
G01X118123Y313110D02*
X117663D01*
G01X117643Y312900D02*
X118113D01*
G01X118093Y312700D02*
X117623D01*
G01X118083Y312510D02*
X116843D01*
G01X117123Y312200D02*
X118053D01*
G01X118043Y312010D02*
X117313D01*
G01X117483Y311810D02*
X118123D01*
G01X118063Y311870D02*
X119023Y310850D01*
G01X119343Y310510D02*
X118013D01*
G01X117993Y310530D02*
X117953Y310550D01*
G01X117993Y310530D02*
X118303Y310270D01*
G01X118073Y310090D02*
X117243D01*
G01X117163Y309890D02*
X118153D01*
G01X117963Y310220D02*
X117713Y310320D01*
G01X117983Y310210D02*
X117963Y310220D01*
G01X118133Y310010D02*
X117983Y310210D01*
G01X118143Y309980D02*
X118133Y310010D01*
G01X117803Y310290D02*
X117533D01*
G01X117823Y309310D02*
X117803D01*
G01X118043Y309450D02*
X117823Y309310D01*
G01X118053Y309470D02*
X118043Y309450D01*
G01X118163Y309700D02*
X118053Y309470D01*
G01X118173Y309720D02*
X118163Y309700D01*
G01X118143Y309980D02*
X118173Y309720D01*
G01X118013Y309110D02*
X119033D01*
G01X117893Y308280D02*
X117883D01*
G01X118183Y308350D02*
X117893Y308280D01*
G01X118193Y308360D02*
X118183Y308350D01*
G01X118703Y308670D02*
X118193Y308360D01*
G01X117953Y309060D02*
X117993Y309080D01*
G01X117753Y309010D02*
X117953Y309060D01*
G01X118063Y309490D02*
X117283D01*
G01X117163Y309680D02*
X118163D01*
G01X118053Y311890D02*
X118033Y311960D01*
G01X118063Y311880D02*
X118053Y311890D01*
G01X118063Y311870D02*
Y311880D01*
G01X117823Y323350D02*
X117673Y323410D01*
G01X117833Y323340D02*
X117823Y323350D01*
G01X119083Y323060D02*
X119143Y323070D01*
G01X119073Y323060D02*
X119083D01*
G01X118963Y323030D02*
X119073Y323060D01*
G01X118953Y323030D02*
X118963D01*
G01X118823Y322980D02*
X118953Y323030D01*
G01X118823Y322970D02*
Y322980D01*
G01X118763Y322940D02*
X118823Y322970D01*
G01X118743Y322920D02*
X118763Y322940D01*
G01X118683Y322870D02*
X118743Y322920D01*
G01X118663Y322850D02*
X118683Y322870D01*
G01X118523Y322850D02*
X118663D01*
G01X118343Y323020D02*
X118523Y322850D01*
G01X118333Y323030D02*
X118343Y323020D01*
G01X117833Y323340D02*
X118333Y323030D01*
G01X118893Y323010D02*
X119413D01*
G01X119463Y321700D02*
X118303D01*
G01X118353Y321650D02*
X118293Y320940D01*
G01X118263Y320900D02*
X118813D01*
G01X119103Y321630D02*
X119133Y321620D01*
G01X119023Y321640D02*
X119103Y321630D01*
G01X118953Y321660D02*
X119023Y321640D01*
G01X118943Y321660D02*
X118953D01*
G01X118813Y321570D02*
X118943Y321660D01*
G01X118763Y320960D02*
X118813Y321570D01*
G01X118863Y320850D02*
X118763Y320960D01*
G01X118863Y321610D02*
X118353D01*
G01X118253Y321760D02*
X110903D01*
G01X118353Y321650D02*
X118253Y321760D01*
G01X117893Y319510D02*
X118713D01*
G01X118683Y319660D02*
X119233Y320240D01*
G01X118653Y319610D02*
X118683Y319660D01*
G01X118653Y319570D02*
Y319610D01*
G01X118753Y319460D02*
X118653Y319570D01*
G01X119113Y320110D02*
X118083D01*
G01Y319900D02*
X118913D01*
G01X118723Y319700D02*
X118063D01*
G01X118083Y318900D02*
X118613D01*
G01X118603Y318890D02*
X118033Y311960D01*
G01X118313Y311610D02*
X117543D01*
G01X117513Y311400D02*
X118503D01*
G01X118593Y311310D02*
X117323D01*
G01X116713Y311010D02*
X118873D01*
G01X119063Y310810D02*
X116493D01*
G01X116343Y309010D02*
X118973D01*
G01X118793Y308760D02*
X118703Y308670D01*
G01X118853Y308830D02*
X118793Y308760D01*
G01X118983Y309020D02*
X118853Y308830D01*
G01X118743Y308700D02*
X116593D01*
G01X116413Y308900D02*
X118903D01*
G01X119103Y309270D02*
X119163Y309440D01*
G01X119063Y309170D02*
X119103Y309270D01*
G01X119063Y309160D02*
Y309170D01*
G01X118993Y309030D02*
X119063Y309160D01*
G01X118983Y309020D02*
X118993Y309030D01*
G01X119153Y309400D02*
X118338D01*
G01X118343D02*
X118403D01*
G01X118303Y309340D02*
X117993Y309080D01*
G01X118333Y309390D02*
X118303Y309340D01*
G01X118133Y309200D02*
X119083D01*
G01X119113Y309310D02*
X118323D01*
G01X119083D02*
X119113D01*
G01X118333Y310220D02*
X118303Y310270D01*
G01X118453Y309830D02*
X118333Y310220D01*
G01X118453Y309770D02*
Y309830D01*
G01X118333Y309390D02*
X118453Y309770D01*
G01X118263Y310310D02*
X119523D01*
G01X119713Y310110D02*
X118373D01*
G01X118433Y309900D02*
X119893D01*
G01X119193Y309700D02*
X118433D01*
G01X118373Y309510D02*
X119173D01*
G01X118263Y308400D02*
X117103D01*
G01X117803Y314900D02*
X118273D01*
G01X118293Y315110D02*
X117823D01*
G01X117843Y315310D02*
X118303D01*
G01X118333Y315610D02*
X117863D01*
G01X117873Y315810D02*
X118343D01*
G01X118363Y316010D02*
X117893D01*
G01X117913Y316200D02*
X118373D01*
G01X118393Y316400D02*
X117933D01*
G01X117943Y316610D02*
X118413D01*
G01X118433Y316810D02*
X117963D01*
G01X117973Y317010D02*
X118443D01*
G01X118463Y317200D02*
X117993D01*
G01X118013Y317400D02*
X118473D01*
G01X118493Y317610D02*
X118023D01*
G01X118043Y317810D02*
X118503D01*
G01X118523Y318010D02*
X118063D01*
G01X118073Y318200D02*
X118543D01*
G01X118563Y318400D02*
X118093D01*
G01X118103Y318610D02*
X118573D01*
G01X118593Y318810D02*
X118123D01*
G01X118603Y318890D02*
X118693Y318980D01*
G01X119023Y320840D02*
X119143D01*
G01X118863Y320850D02*
X119023Y320840D01*
G01X118773Y321010D02*
X118303D01*
G01X118313Y321110D02*
X118783D01*
G01Y321200D02*
X118323D01*
G01Y321310D02*
X118793D01*
G01X118803Y321400D02*
X118333D01*
G01X118343Y321510D02*
X118813D01*
G01X119213Y323070D02*
X119143D01*
G01X119223Y323060D02*
X119213Y323070D01*
G01X119483Y322990D02*
X119223Y323060D01*
G01X119493Y322980D02*
X119483Y322990D01*
G01X119693Y322810D02*
X119493Y322980D01*
G01X119703Y322800D02*
X119693Y322810D01*
G01X119823Y322570D02*
X119703Y322800D01*
G01X119833Y322550D02*
X119823Y322570D01*
G01X119853Y322270D02*
X119833Y322550D01*
G01X119853Y322260D02*
Y322270D01*
G01X119773Y322000D02*
X119853Y322260D01*
G01X119763Y321990D02*
X119773Y322000D01*
G01X119603Y321790D02*
X119763Y321990D01*
G01X119593Y321770D02*
X119603Y321790D01*
G01X119363Y321650D02*
X119593Y321770D01*
G01X119343Y321650D02*
X119363D01*
G01X119223Y321630D02*
X119343Y321650D01*
G01X119213Y321630D02*
X119223D01*
G01X119153Y321620D02*
X119213Y321630D01*
G01X119133Y321620D02*
X119153D01*
G01X118723Y322900D02*
X119583D01*
G01X119693Y322810D02*
X117803D01*
G01X118083Y322610D02*
X119803D01*
G01X119843Y322400D02*
X118213D01*
G01X119703Y321900D02*
X109593D01*
G01Y322110D02*
X119803D01*
G01X120113Y321810D02*
X120743D01*
G01X120843Y321900D02*
X120213D01*
G01X120303Y322010D02*
X120943D01*
G01X121033Y322110D02*
X120403D01*
G01X120503Y322200D02*
X121133D01*
G01X121223Y322310D02*
X120603D01*
G01X120693Y322400D02*
X121323D01*
G01X121423Y322510D02*
X120793D01*
G01X120893Y322610D02*
X121523D01*
G01X121713Y322810D02*
X121083D01*
G01X121273Y323010D02*
X121903D01*
G01X120653Y321700D02*
X120023D01*
G01X119923Y321610D02*
X120553D01*
G01X120453Y321510D02*
X119823D01*
G01X119723Y321400D02*
X120363D01*
G01X120263Y321310D02*
X119633D01*
G01X119533Y321200D02*
X120173D01*
G01X120073Y321110D02*
X119443D01*
G01X119343Y321010D02*
X119973D01*
G01X119823Y318980D02*
X118693D01*
G01X119863Y319000D02*
X119823Y318980D01*
G01X119863Y319010D02*
Y319000D01*
G01Y320830D02*
Y319010D01*
G01Y320840D02*
Y320830D01*
G01X119893Y320920D02*
X119863Y320840D01*
G01X119343Y320260D02*
X119233Y320240D01*
G01X119403Y320160D02*
X119343Y320260D01*
G01X119403Y319560D02*
Y320160D01*
G01X119303Y319460D02*
X119403Y319560D01*
G01X118753Y319460D02*
X119303D01*
G01X119373Y320200D02*
X119863D01*
G01Y320110D02*
X119403D01*
G01Y320010D02*
X119863D01*
G01Y319900D02*
X119403D01*
G01Y319810D02*
X119863D01*
G01Y319700D02*
X119403D01*
G01Y319610D02*
X119863D01*
G01Y319510D02*
X119353D01*
G01X119863Y319310D02*
X117693D01*
G01X117503Y319110D02*
X119863D01*
G01Y320400D02*
X118083D01*
G01Y320610D02*
X119863D01*
G01Y320810D02*
X118083D01*
G01X119143Y320840D02*
X119213Y320870D01*
G01X119243Y320900D02*
X119883D01*
G01X119243Y310610D02*
X117693D01*
G01X118133Y310400D02*
X119433D01*
G01X119613Y310200D02*
X118343D01*
G01X118393Y310010D02*
X119803D01*
G01X119993Y309810D02*
X119303D01*
G01X119163Y309460D02*
Y309440D01*
G01X119203Y309730D02*
X119163Y309460D01*
G01X119263Y309810D02*
X119203Y309730D01*
G01X119183Y309610D02*
X118403D01*
G01X119263Y309810D02*
X119373Y309790D01*
G01X118453Y309810D02*
X119263D01*
G01X119453Y309700D02*
X120083D01*
G01X120173Y309610D02*
X119543D01*
G01X119633Y309510D02*
X120273D01*
G01X120323Y309400D02*
X120363D01*
G01X120373D02*
X119733D01*
G01X119823Y309310D02*
X120458D01*
G01X120453D02*
X120403D01*
G01X120558Y309200D02*
X119913D01*
G01X120003Y309110D02*
X120643D01*
G01X120733Y309010D02*
X120098D01*
G01X120198Y308900D02*
X120833D01*
G01X120923Y308810D02*
X120283D01*
G01X120388Y308700D02*
X121013D01*
G01X121113Y308610D02*
X120473D01*
G01X120563Y308510D02*
X121203D01*
G01X121293Y308400D02*
X120653D01*
G01X120743Y308310D02*
X121393D01*
G01X121573Y308110D02*
X120933D01*
G01X120843Y308200D02*
X121483D01*
G01X121663Y308010D02*
X121023D01*
G01X121123Y307900D02*
X121763D01*
G01X121853Y307810D02*
X121213D01*
G01X121303Y307700D02*
X121943D01*
G01X122043Y307610D02*
X121393D01*
G01X121493Y307510D02*
X122133D01*
G01X122223Y307400D02*
X121583D01*
G01X121673Y307310D02*
X122323D01*
G01X122413Y307200D02*
X121773D01*
G01X121863Y307110D02*
X122503D01*
G01X122693Y306900D02*
X122053D01*
G01X122233Y306700D02*
X122843D01*
G01X122833Y306760D02*
X119023Y310850D01*
G01X122503Y306420D02*
X122523Y306400D01*
G01X119373Y309790D02*
X122503Y306420D01*
G01X122423Y306510D02*
X122643D01*
G01X105563Y306740D02*
X110983Y312350D01*
G01X105533Y306710D02*
X105563Y306740D01*
G01X105543Y306690D02*
X105533Y306710D01*
G01X105853Y306420D02*
X105543Y306690D01*
G01X105883Y306410D02*
X105853Y306420D01*
G01X105903D02*
X105883Y306410D01*
G01X111023Y311720D02*
X105903Y306420D01*
G01X105983Y306510D02*
X105753D01*
G01X105633Y306610D02*
X106083D01*
G01X106183Y306700D02*
X105533D01*
G01X105623Y306810D02*
X106283D01*
G01X106373Y306900D02*
X105723D01*
G01X105813Y307010D02*
X106473D01*
G01X106563Y307110D02*
X105913D01*
G01X106003Y307200D02*
X106663D01*
G01X106763Y307310D02*
X106103D01*
G01X106203Y307400D02*
X106853D01*
G01X106953Y307510D02*
X106303D01*
G01X106393Y307610D02*
X107053D01*
G01X107143Y307700D02*
X106493D01*
G01X106593Y307810D02*
X107243D01*
G01X107343Y307900D02*
X106683D01*
G01X106783Y308010D02*
X107433D01*
G01X119213Y320870D02*
X123793Y325610D01*
G01X123823Y325000D02*
X119893Y320920D01*
G01X120983Y322700D02*
X121613D01*
G01X121803Y322900D02*
X121173D01*
G01X121373Y323110D02*
X122003D01*
G01X122103Y323200D02*
X121473D01*
G01X121563Y323310D02*
X122193D01*
G01X122293Y323400D02*
X121663D01*
G01X121763Y323510D02*
X122383D01*
G01X122483Y323610D02*
X121853D01*
G01X122043Y323810D02*
X122673D01*
G01X122873Y324010D02*
X122243D01*
G01X122433Y324200D02*
X123063D01*
G01X122963Y324110D02*
X122343D01*
G01X122533Y324310D02*
X123153D01*
G01X123253Y324400D02*
X122623D01*
G01X122723Y324510D02*
X123353D01*
G01X123453Y324610D02*
X122823D01*
G01X122913Y324700D02*
X123543D01*
G01X123643Y324810D02*
X123013D01*
G01X123113Y324900D02*
X123733D01*
G01X123843Y325110D02*
X123303D01*
G01X123833Y325030D02*
X123843Y325110D01*
G01X123823Y325000D02*
X123833Y325030D01*
G01X123213Y325010D02*
X123823D01*
G01X123843Y325600D02*
X123793Y325610D01*
G01X123843Y325110D02*
Y325600D01*
G01X123783Y325610D02*
X123823D01*
G01X123843Y325510D02*
X123693D01*
G01X123593Y325400D02*
X123843D01*
G01Y325310D02*
X123493D01*
G01X123403Y325200D02*
X123843D01*
G01X122773Y323900D02*
X122143D01*
G01X121953Y323700D02*
X122583D01*
G01X122603Y307010D02*
X121953D01*
G01X122143Y306810D02*
X122783D01*
G01X122553Y306420D02*
X122523Y306400D01*
G01X122843Y306710D02*
X122553Y306420D01*
G01X122853Y306730D02*
X122843Y306710D01*
G01Y306740D02*
X122853Y306730D01*
G01X122833Y306760D02*
X122843Y306740D01*
G01X122323Y306610D02*
X122743D01*
G54D18*
G01X121778Y-377522D02*
X122652Y-376647D01*
X123307Y-375189D01*
X123744Y-373146D01*
X123307Y-371397D01*
X122434Y-370230D01*
X120905Y-369355D01*
X115010D01*
Y-386855D01*
X122215D01*
X123744Y-385689D01*
X124617Y-383938D01*
X125054Y-381897D01*
X124617Y-379855D01*
X123307Y-378105D01*
X121778Y-377522D01*
X115010D01*
G01X134475Y-386855D02*
Y-375189D01*
G01Y-377522D02*
X135567Y-376355D01*
X136659Y-375480D01*
X138187Y-375189D01*
X139278Y-375480D01*
X140589Y-376355D01*
G01X150447Y-392105D02*
X151757Y-392688D01*
X153504Y-392105D01*
X154595Y-390939D01*
X155469Y-389480D01*
X156778Y-384814D01*
X159617Y-375189D01*
G01X152630D02*
X156778Y-384814D01*
G01X176025Y-376647D02*
X174497Y-375480D01*
X173187Y-375189D01*
X171440Y-375772D01*
X170130Y-376938D01*
X169257Y-378980D01*
X169038Y-381022D01*
X169257Y-383064D01*
X170130Y-384814D01*
X171440Y-386272D01*
X173187Y-386855D01*
X174715Y-386272D01*
X176025Y-385105D01*
G01X186757Y-378980D02*
X193744D01*
X193089Y-376938D01*
X191997Y-375772D01*
X190469Y-375189D01*
X188940Y-375480D01*
X187630Y-376355D01*
X186757Y-378397D01*
X186320Y-380147D01*
Y-381897D01*
X186757Y-383647D01*
X187849Y-385397D01*
X189159Y-386563D01*
X190687Y-386855D01*
X192215Y-386272D01*
X193744Y-384522D01*
G01X229835Y-370814D02*
X228525Y-369938D01*
X226997Y-369355D01*
X225250D01*
X223285Y-370230D01*
X221757Y-371688D01*
X220665Y-373439D01*
X219792Y-376355D01*
X219573Y-378980D01*
X220010Y-381605D01*
X220665Y-383355D01*
X221975Y-385105D01*
X223504Y-386272D01*
X225032Y-386855D01*
X226560D01*
X228089Y-386272D01*
X229399Y-385397D01*
X230491Y-384231D01*
G01X246462Y-386855D02*
Y-375189D01*
G01Y-377230D02*
X245589Y-376064D01*
X244278Y-375480D01*
X242750Y-375189D01*
X241222Y-375772D01*
X239912Y-376938D01*
X239038Y-378688D01*
X238602Y-381022D01*
X239038Y-383355D01*
X239912Y-385105D01*
X241222Y-386272D01*
X242750Y-386855D01*
X244278Y-386563D01*
X245589Y-385689D01*
X246462Y-384522D01*
G01X256320Y-386855D02*
Y-375189D01*
G01Y-378105D02*
X257194Y-376647D01*
X258504Y-375480D01*
X260250Y-375189D01*
X261778Y-375480D01*
X263089Y-376647D01*
X263744Y-378688D01*
Y-386855D01*
G01X272947Y-392105D02*
X274257Y-392688D01*
X276004Y-392105D01*
X277095Y-390939D01*
X277969Y-389480D01*
X279278Y-384814D01*
X282117Y-375189D01*
G01X275130D02*
X279278Y-384814D01*
G01X295032Y-386855D02*
X293722Y-386563D01*
X292412Y-385397D01*
X291538Y-383355D01*
X291102Y-381022D01*
X291538Y-378688D01*
X292412Y-376647D01*
X293722Y-375480D01*
X295032Y-375189D01*
X296342Y-375480D01*
X297652Y-376647D01*
X298525Y-378688D01*
X298744Y-381022D01*
X298525Y-383355D01*
X297652Y-385397D01*
X296342Y-386563D01*
X295032Y-386855D01*
G01X308820D02*
Y-375189D01*
G01Y-378105D02*
X309694Y-376647D01*
X311004Y-375480D01*
X312750Y-375189D01*
X314278Y-375480D01*
X315589Y-376647D01*
X316244Y-378688D01*
Y-386855D01*
G01X342947Y-384522D02*
X344694Y-385980D01*
X346659Y-386855D01*
X348405D01*
X350152Y-385980D01*
X351462Y-384522D01*
X352117Y-382480D01*
X351680Y-380439D01*
X350589Y-378688D01*
X348624Y-377522D01*
X346004Y-376938D01*
X344475Y-375772D01*
X343820Y-373730D01*
X344257Y-371688D01*
X345349Y-370230D01*
X346877Y-369355D01*
X348405D01*
X349934Y-369938D01*
X351244Y-371397D01*
G01X369835Y-370814D02*
X368525Y-369938D01*
X366997Y-369355D01*
X365250D01*
X363285Y-370230D01*
X361757Y-371688D01*
X360665Y-373439D01*
X359792Y-376355D01*
X359573Y-378980D01*
X360010Y-381605D01*
X360665Y-383355D01*
X361975Y-385105D01*
X363504Y-386272D01*
X365032Y-386855D01*
X366560D01*
X368089Y-386272D01*
X369399Y-385397D01*
X370491Y-384231D01*
G01X387335Y-370814D02*
X386025Y-369938D01*
X384497Y-369355D01*
X382750D01*
X380785Y-370230D01*
X379257Y-371688D01*
X378165Y-373439D01*
X377292Y-376355D01*
X377073Y-378980D01*
X377510Y-381605D01*
X378165Y-383355D01*
X379475Y-385105D01*
X381004Y-386272D01*
X382532Y-386855D01*
X384060D01*
X385589Y-386272D01*
X386899Y-385397D01*
X387991Y-384231D01*
G01X210605Y-341855D02*
Y-324355D01*
X216282Y-338938D01*
X221959Y-324355D01*
Y-341855D01*
G01X233782D02*
X232472Y-341563D01*
X231162Y-340397D01*
X230288Y-338355D01*
X229852Y-336022D01*
X230288Y-333688D01*
X231162Y-331647D01*
X232472Y-330480D01*
X233782Y-330189D01*
X235092Y-330480D01*
X236402Y-331647D01*
X237275Y-333688D01*
X237494Y-336022D01*
X237275Y-338355D01*
X236402Y-340397D01*
X235092Y-341563D01*
X233782Y-341855D01*
G01X255212Y-324355D02*
Y-341855D01*
G01Y-339231D02*
X254339Y-340689D01*
X253028Y-341563D01*
X251500Y-341855D01*
X249754Y-341272D01*
X248444Y-339814D01*
X247570Y-338064D01*
X247352Y-336022D01*
X247570Y-333980D01*
X248444Y-332230D01*
X249754Y-330772D01*
X251500Y-330189D01*
X253028Y-330480D01*
X254120Y-331064D01*
X255212Y-332230D01*
G01X265507Y-333980D02*
X272494D01*
X271839Y-331938D01*
X270747Y-330772D01*
X269219Y-330189D01*
X267690Y-330480D01*
X266380Y-331355D01*
X265507Y-333397D01*
X265070Y-335147D01*
Y-336897D01*
X265507Y-338647D01*
X266599Y-340397D01*
X267909Y-341563D01*
X269437Y-341855D01*
X270965Y-341272D01*
X272494Y-339522D01*
G01X286282Y-341855D02*
Y-324355D01*
G01X566882Y-386855D02*
Y-369355D01*
X564262Y-372855D01*
G01Y-386855D02*
X569502D01*
G01X580234Y-379564D02*
X581762Y-377522D01*
X583072Y-376355D01*
X584819Y-375772D01*
X586347Y-376355D01*
X587439Y-377522D01*
X588312Y-379272D01*
X588530Y-381313D01*
X588312Y-383064D01*
X587439Y-384814D01*
X586128Y-386272D01*
X584600Y-386855D01*
X582854Y-386272D01*
X581325Y-384522D01*
X580452Y-381897D01*
X580234Y-378980D01*
X580670Y-375189D01*
X581325Y-373146D01*
X582417Y-371105D01*
X583945Y-369647D01*
X585474Y-369355D01*
X587002Y-369938D01*
X588094Y-371397D01*
G01X597079Y-383355D02*
X598388Y-385397D01*
X600135Y-386563D01*
X602100Y-386855D01*
X603847Y-386563D01*
X605594Y-385105D01*
X606685Y-383355D01*
X606904Y-381605D01*
X606467Y-379564D01*
X604939Y-378105D01*
X603410Y-377522D01*
X601445D01*
G01X603410D02*
X604720Y-376647D01*
X605812Y-375189D01*
X606249Y-373439D01*
X605812Y-371688D01*
X604720Y-370230D01*
X602755Y-369355D01*
X600790Y-369647D01*
X598825Y-370814D01*
G01X619382Y-386855D02*
Y-369355D01*
X616762Y-372855D01*
G01Y-386855D02*
X622002D01*
G01X632734Y-379564D02*
X634262Y-377522D01*
X635572Y-376355D01*
X637319Y-375772D01*
X638847Y-376355D01*
X639939Y-377522D01*
X640812Y-379272D01*
X641030Y-381313D01*
X640812Y-383064D01*
X639939Y-384814D01*
X638628Y-386272D01*
X637100Y-386855D01*
X635354Y-386272D01*
X633825Y-384522D01*
X632952Y-381897D01*
X632734Y-378980D01*
X633170Y-375189D01*
X633825Y-373146D01*
X634917Y-371105D01*
X636445Y-369647D01*
X637974Y-369355D01*
X639502Y-369938D01*
X640594Y-371397D01*
G01X553765Y-341855D02*
Y-324355D01*
X559005D01*
X560752Y-325230D01*
X562062Y-327272D01*
X562499Y-329605D01*
X562062Y-331938D01*
X560970Y-333688D01*
X559005Y-334564D01*
X553765D01*
G01X580435Y-325814D02*
X579125Y-324938D01*
X577597Y-324355D01*
X575850D01*
X573885Y-325230D01*
X572357Y-326688D01*
X571265Y-328439D01*
X570392Y-331355D01*
X570173Y-333980D01*
X570610Y-336605D01*
X571265Y-338355D01*
X572575Y-340105D01*
X574104Y-341272D01*
X575632Y-341855D01*
X577160D01*
X578689Y-341272D01*
X579999Y-340397D01*
X581091Y-339231D01*
G01X594878Y-332522D02*
X595752Y-331647D01*
X596407Y-330189D01*
X596844Y-328146D01*
X596407Y-326397D01*
X595534Y-325230D01*
X594005Y-324355D01*
X588110D01*
Y-341855D01*
X595315D01*
X596844Y-340689D01*
X597717Y-338938D01*
X598154Y-336897D01*
X597717Y-334855D01*
X596407Y-333105D01*
X594878Y-332522D01*
X588110D01*
G01X604082Y-347688D02*
X617182D01*
G01X623110Y-341855D02*
Y-324355D01*
X633154Y-341855D01*
Y-324355D01*
G01X645632Y-341855D02*
X643885Y-341563D01*
X642357Y-340397D01*
X641047Y-338647D01*
X640173Y-336605D01*
X639737Y-334272D01*
Y-331938D01*
X640173Y-329605D01*
X641047Y-327563D01*
X642357Y-325814D01*
X643885Y-324647D01*
X645632Y-324355D01*
X647378Y-324647D01*
X648907Y-325814D01*
X650217Y-327563D01*
X651091Y-329605D01*
X651527Y-331938D01*
Y-334272D01*
X651091Y-336605D01*
X650217Y-338647D01*
X648907Y-340397D01*
X647378Y-341563D01*
X645632Y-341855D01*
G01X696473Y-324355D02*
X701932Y-341855D01*
X707391Y-324355D01*
G01X723799Y-341855D02*
X715065D01*
Y-324355D01*
X723799D01*
G01X720305Y-332813D02*
X715065D01*
G01X732565Y-341855D02*
Y-324355D01*
X738024D01*
X739770Y-325230D01*
X740862Y-326397D01*
X741299Y-328730D01*
X740862Y-331064D01*
X739552Y-332522D01*
X738024Y-333397D01*
X732565D01*
G01X738024D02*
X741299Y-341855D01*
G01X754432Y-342438D02*
X753995Y-342147D01*
Y-341563D01*
X754432Y-341272D01*
X754869Y-341563D01*
Y-342147D01*
X754432Y-342438D01*
G01X728182Y-386855D02*
Y-369355D01*
X725562Y-372855D01*
G01Y-386855D02*
X730802D01*
G01X834382Y-369355D02*
Y-386855D01*
G01X829360Y-369355D02*
X839404D01*
G01X847297Y-384522D02*
X849044Y-385980D01*
X851009Y-386855D01*
X852755D01*
X854502Y-385980D01*
X855812Y-384522D01*
X856467Y-382480D01*
X856030Y-380439D01*
X854939Y-378688D01*
X852974Y-377522D01*
X850354Y-376938D01*
X848825Y-375772D01*
X848170Y-373730D01*
X848607Y-371688D01*
X849699Y-370230D01*
X851227Y-369355D01*
X852755D01*
X854284Y-369938D01*
X855594Y-371397D01*
G01X866762Y-369355D02*
X872002D01*
G01X869382D02*
Y-386855D01*
G01X866762D02*
X872002D01*
G01X882515Y-369355D02*
Y-386855D01*
X891249D01*
G01X899579D02*
Y-369355D01*
G01X907875D02*
X899579Y-380147D01*
G01X909185Y-386855D02*
X903290Y-375189D01*
G01X830015Y-324355D02*
Y-341855D01*
X838749D01*
G01X855812D02*
Y-330189D01*
G01Y-332230D02*
X854939Y-331064D01*
X853628Y-330480D01*
X852100Y-330189D01*
X850572Y-330772D01*
X849262Y-331938D01*
X848388Y-333688D01*
X847952Y-336022D01*
X848388Y-338355D01*
X849262Y-340105D01*
X850572Y-341272D01*
X852100Y-341855D01*
X853628Y-341563D01*
X854939Y-340689D01*
X855812Y-339522D01*
G01X864797Y-347105D02*
X866107Y-347688D01*
X867854Y-347105D01*
X868945Y-345939D01*
X869819Y-344480D01*
X871128Y-339814D01*
X873967Y-330189D01*
G01X866980D02*
X871128Y-339814D01*
G01X883607Y-333980D02*
X890594D01*
X889939Y-331938D01*
X888847Y-330772D01*
X887319Y-330189D01*
X885790Y-330480D01*
X884480Y-331355D01*
X883607Y-333397D01*
X883170Y-335147D01*
Y-336897D01*
X883607Y-338647D01*
X884699Y-340397D01*
X886009Y-341563D01*
X887537Y-341855D01*
X889065Y-341272D01*
X890594Y-339522D01*
G01X901325Y-341855D02*
Y-330189D01*
G01Y-332522D02*
X902417Y-331355D01*
X903509Y-330480D01*
X905037Y-330189D01*
X906128Y-330480D01*
X907439Y-331355D01*
G01X994432Y-386855D02*
X992685Y-386563D01*
X991157Y-385397D01*
X989847Y-383647D01*
X988973Y-381605D01*
X988537Y-379272D01*
Y-376938D01*
X988973Y-374605D01*
X989847Y-372563D01*
X991157Y-370814D01*
X992685Y-369647D01*
X994432Y-369355D01*
X996178Y-369647D01*
X997707Y-370814D01*
X999017Y-372563D01*
X999891Y-374605D01*
X1000327Y-376938D01*
Y-379272D01*
X999891Y-381605D01*
X999017Y-383647D01*
X997707Y-385397D01*
X996178Y-386563D01*
X994432Y-386855D01*
G01X996178Y-382188D02*
X998799Y-386855D01*
G01X1007129Y-369355D02*
Y-381897D01*
X1008002Y-384522D01*
X1009749Y-386272D01*
X1011932Y-386855D01*
X1014115Y-386272D01*
X1015862Y-384522D01*
X1016735Y-381897D01*
Y-369355D01*
G01X1026812D02*
X1032052D01*
G01X1029432D02*
Y-386855D01*
G01X1026812D02*
X1032052D01*
G01X1041910D02*
Y-369355D01*
X1051954Y-386855D01*
Y-369355D01*
G01X1069235Y-370814D02*
X1067925Y-369938D01*
X1066397Y-369355D01*
X1064650D01*
X1062685Y-370230D01*
X1061157Y-371688D01*
X1060065Y-373439D01*
X1059192Y-376355D01*
X1058973Y-378980D01*
X1059410Y-381605D01*
X1060065Y-383355D01*
X1061375Y-385105D01*
X1062904Y-386272D01*
X1064432Y-386855D01*
X1065960D01*
X1067489Y-386272D01*
X1068799Y-385397D01*
X1069891Y-384231D01*
G01X1081932Y-386855D02*
Y-378980D01*
X1077565Y-369355D01*
G01X1086299D02*
X1081932Y-378980D01*
G01X972129Y-341855D02*
Y-324355D01*
X976495D01*
X978242Y-325230D01*
X979552Y-326397D01*
X980644Y-328146D01*
X981517Y-330189D01*
X981735Y-333105D01*
X981517Y-336022D01*
X980644Y-338064D01*
X979552Y-339814D01*
X978242Y-340980D01*
X976495Y-341855D01*
X972129D01*
G01X991157Y-333980D02*
X998144D01*
X997489Y-331938D01*
X996397Y-330772D01*
X994869Y-330189D01*
X993340Y-330480D01*
X992030Y-331355D01*
X991157Y-333397D01*
X990720Y-335147D01*
Y-336897D01*
X991157Y-338647D01*
X992249Y-340397D01*
X993559Y-341563D01*
X995087Y-341855D01*
X996615Y-341272D01*
X998144Y-339522D01*
G01X1008657Y-339814D02*
X1009749Y-340980D01*
X1011277Y-341855D01*
X1012587D01*
X1013897Y-341272D01*
X1014770Y-340397D01*
X1015207Y-339231D01*
X1014989Y-337480D01*
X1014115Y-336605D01*
X1010185Y-334855D01*
X1009312Y-332813D01*
X1009749Y-331355D01*
X1010622Y-330480D01*
X1011932Y-330189D01*
X1013242Y-330480D01*
X1014552Y-331355D01*
G01X1029432Y-330189D02*
Y-341855D01*
G01Y-325522D02*
X1028995Y-325230D01*
Y-324647D01*
X1029432Y-324355D01*
X1029869Y-324647D01*
Y-325230D01*
X1029432Y-325522D01*
G01X1043875Y-346230D02*
X1045404Y-347397D01*
X1047150Y-347688D01*
X1048678Y-347397D01*
X1049989Y-345939D01*
X1050862Y-343897D01*
Y-330189D01*
G01Y-332522D02*
X1049989Y-331355D01*
X1048678Y-330480D01*
X1047150Y-330189D01*
X1045404Y-330772D01*
X1044312Y-331938D01*
X1043438Y-333980D01*
X1043002Y-336022D01*
X1043220Y-337772D01*
X1044094Y-339814D01*
X1045404Y-341272D01*
X1047150Y-341855D01*
X1048460Y-341563D01*
X1049989Y-340397D01*
X1050862Y-339231D01*
G01X1060720Y-341855D02*
Y-330189D01*
G01Y-333105D02*
X1061594Y-331647D01*
X1062904Y-330480D01*
X1064650Y-330189D01*
X1066178Y-330480D01*
X1067489Y-331647D01*
X1068144Y-333688D01*
Y-341855D01*
G01X1078657Y-333980D02*
X1085644D01*
X1084989Y-331938D01*
X1083897Y-330772D01*
X1082369Y-330189D01*
X1080840Y-330480D01*
X1079530Y-331355D01*
X1078657Y-333397D01*
X1078220Y-335147D01*
Y-336897D01*
X1078657Y-338647D01*
X1079749Y-340397D01*
X1081059Y-341563D01*
X1082587Y-341855D01*
X1084115Y-341272D01*
X1085644Y-339522D01*
G01X1096375Y-341855D02*
Y-330189D01*
G01Y-332522D02*
X1097467Y-331355D01*
X1098559Y-330480D01*
X1100087Y-330189D01*
X1101178Y-330480D01*
X1102489Y-331355D01*
G01X1143132Y-369355D02*
X1141385Y-369938D01*
X1140075Y-371397D01*
X1139202Y-373146D01*
X1138547Y-375480D01*
X1138329Y-378105D01*
X1138547Y-380730D01*
X1139202Y-383064D01*
X1140075Y-384814D01*
X1141385Y-386272D01*
X1143132Y-386855D01*
X1144878Y-386272D01*
X1146189Y-384814D01*
X1147062Y-383064D01*
X1147717Y-380730D01*
X1147935Y-378105D01*
X1147717Y-375480D01*
X1147062Y-373146D01*
X1146189Y-371397D01*
X1144878Y-369938D01*
X1143132Y-369355D01*
G01X1156484Y-379564D02*
X1158012Y-377522D01*
X1159322Y-376355D01*
X1161069Y-375772D01*
X1162597Y-376355D01*
X1163689Y-377522D01*
X1164562Y-379272D01*
X1164780Y-381313D01*
X1164562Y-383064D01*
X1163689Y-384814D01*
X1162378Y-386272D01*
X1160850Y-386855D01*
X1159104Y-386272D01*
X1157575Y-384522D01*
X1156702Y-381897D01*
X1156484Y-378980D01*
X1156920Y-375189D01*
X1157575Y-373146D01*
X1158667Y-371105D01*
X1160195Y-369647D01*
X1161724Y-369355D01*
X1163252Y-369938D01*
X1164344Y-371397D01*
G01X1174202Y-387438D02*
X1182062Y-369355D01*
G01X1191484Y-372272D02*
X1192794Y-370522D01*
X1194322Y-369647D01*
X1196069Y-369355D01*
X1198252Y-369938D01*
X1199780Y-371397D01*
X1200217Y-373146D01*
X1199999Y-374897D01*
X1199125Y-376355D01*
X1194759Y-379272D01*
X1192794Y-381313D01*
X1191484Y-384231D01*
X1191047Y-386855D01*
X1200217D01*
G01X1213132D02*
Y-369355D01*
X1210512Y-372855D01*
G01Y-386855D02*
X1215752D01*
G01X1226702Y-387438D02*
X1234562Y-369355D01*
G01X1243984Y-372272D02*
X1245294Y-370522D01*
X1246822Y-369647D01*
X1248569Y-369355D01*
X1250752Y-369938D01*
X1252280Y-371397D01*
X1252717Y-373146D01*
X1252499Y-374897D01*
X1251625Y-376355D01*
X1247259Y-379272D01*
X1245294Y-381313D01*
X1243984Y-384231D01*
X1243547Y-386855D01*
X1252717D01*
G01X1265632Y-369355D02*
X1263885Y-369938D01*
X1262575Y-371397D01*
X1261702Y-373146D01*
X1261047Y-375480D01*
X1260829Y-378105D01*
X1261047Y-380730D01*
X1261702Y-383064D01*
X1262575Y-384814D01*
X1263885Y-386272D01*
X1265632Y-386855D01*
X1267378Y-386272D01*
X1268689Y-384814D01*
X1269562Y-383064D01*
X1270217Y-380730D01*
X1270435Y-378105D01*
X1270217Y-375480D01*
X1269562Y-373146D01*
X1268689Y-371397D01*
X1267378Y-369938D01*
X1265632Y-369355D01*
G01X1283132Y-386855D02*
Y-369355D01*
X1280512Y-372855D01*
G01Y-386855D02*
X1285752D01*
G01X1300195D02*
X1300632Y-383064D01*
X1301287Y-379855D01*
X1302160Y-376938D01*
X1303252Y-373730D01*
X1304999Y-369355D01*
X1296265D01*
G01X1190829Y-341855D02*
Y-324355D01*
X1195195D01*
X1196942Y-325230D01*
X1198252Y-326397D01*
X1199344Y-328146D01*
X1200217Y-330189D01*
X1200435Y-333105D01*
X1200217Y-336022D01*
X1199344Y-338064D01*
X1198252Y-339814D01*
X1196942Y-340980D01*
X1195195Y-341855D01*
X1190829D01*
G01X1217062D02*
Y-330189D01*
G01Y-332230D02*
X1216189Y-331064D01*
X1214878Y-330480D01*
X1213350Y-330189D01*
X1211822Y-330772D01*
X1210512Y-331938D01*
X1209638Y-333688D01*
X1209202Y-336022D01*
X1209638Y-338355D01*
X1210512Y-340105D01*
X1211822Y-341272D01*
X1213350Y-341855D01*
X1214878Y-341563D01*
X1216189Y-340689D01*
X1217062Y-339522D01*
G01X1230632Y-324355D02*
Y-341855D01*
G01X1227575Y-330189D02*
X1233689D01*
G01X1244857Y-333980D02*
X1251844D01*
X1251189Y-331938D01*
X1250097Y-330772D01*
X1248569Y-330189D01*
X1247040Y-330480D01*
X1245730Y-331355D01*
X1244857Y-333397D01*
X1244420Y-335147D01*
Y-336897D01*
X1244857Y-338647D01*
X1245949Y-340397D01*
X1247259Y-341563D01*
X1248787Y-341855D01*
X1250315Y-341272D01*
X1251844Y-339522D01*
G01X9517Y165167D02*
Y167667D01*
X10558D01*
X10892Y167542D01*
X11100Y167375D01*
X11183Y167042D01*
X11100Y166709D01*
X10850Y166500D01*
X10558Y166375D01*
X9517D01*
G01X10558D02*
X11183Y165167D01*
G01X12533Y165542D02*
X12783Y165334D01*
X13075Y165209D01*
X13450Y165167D01*
X13825Y165250D01*
X14117Y165417D01*
X14325Y165709D01*
X14367Y166042D01*
X14283Y166375D01*
X14075Y166584D01*
X13783Y166750D01*
X13492Y166792D01*
X13200Y166750D01*
X12825Y166584D01*
X12950Y167667D01*
X14075D01*
G01X15758Y167250D02*
X16008Y167500D01*
X16300Y167625D01*
X16633Y167667D01*
X17050Y167584D01*
X17342Y167375D01*
X17425Y167125D01*
X17383Y166875D01*
X17217Y166667D01*
X16383Y166250D01*
X16008Y165959D01*
X15758Y165542D01*
X15675Y165167D01*
X17425D01*
G01X18733Y165542D02*
X18983Y165334D01*
X19275Y165209D01*
X19650Y165167D01*
X20025Y165250D01*
X20317Y165417D01*
X20525Y165709D01*
X20567Y166042D01*
X20483Y166375D01*
X20275Y166584D01*
X19983Y166750D01*
X19692Y166792D01*
X19400Y166750D01*
X19025Y166584D01*
X19150Y167667D01*
X20275D01*
G01X14208Y151767D02*
X14083Y151517D01*
X14000Y151225D01*
Y150892D01*
X14125Y150517D01*
X14333Y150225D01*
X14583Y150017D01*
X15000Y149850D01*
X15375Y149808D01*
X15750Y149892D01*
X16000Y150017D01*
X16250Y150267D01*
X16417Y150558D01*
X16500Y150850D01*
Y151142D01*
X16417Y151433D01*
X16292Y151683D01*
X16125Y151892D01*
G01X16500Y153867D02*
X15958Y153950D01*
X15500Y154075D01*
X15083Y154242D01*
X14625Y154450D01*
X14000Y154783D01*
Y153117D01*
G01X16000Y156133D02*
X16292Y156383D01*
X16458Y156717D01*
X16500Y157092D01*
X16458Y157425D01*
X16250Y157758D01*
X16000Y157967D01*
X15750Y158008D01*
X15458Y157925D01*
X15250Y157633D01*
X15167Y157342D01*
Y156967D01*
G01Y157342D02*
X15042Y157592D01*
X14833Y157800D01*
X14583Y157883D01*
X14333Y157800D01*
X14125Y157592D01*
X14000Y157217D01*
X14042Y156842D01*
X14208Y156467D01*
G01X16500Y160067D02*
X15958Y160150D01*
X15500Y160275D01*
X15083Y160442D01*
X14625Y160650D01*
X14000Y160983D01*
Y159317D01*
G01X9717Y171800D02*
Y174300D01*
X10758D01*
X11092Y174175D01*
X11300Y174008D01*
X11383Y173675D01*
X11300Y173342D01*
X11050Y173133D01*
X10758Y173008D01*
X9717D01*
G01X10758D02*
X11383Y171800D01*
G01X12733Y172175D02*
X12983Y171967D01*
X13275Y171842D01*
X13650Y171800D01*
X14025Y171883D01*
X14317Y172050D01*
X14525Y172342D01*
X14567Y172675D01*
X14483Y173008D01*
X14275Y173217D01*
X13983Y173383D01*
X13692Y173425D01*
X13400Y173383D01*
X13025Y173217D01*
X13150Y174300D01*
X14275D01*
G01X15958Y173883D02*
X16208Y174133D01*
X16500Y174258D01*
X16833Y174300D01*
X17250Y174217D01*
X17542Y174008D01*
X17625Y173758D01*
X17583Y173508D01*
X17417Y173300D01*
X16583Y172883D01*
X16208Y172592D01*
X15958Y172175D01*
X15875Y171800D01*
X17625D01*
G01X19767D02*
X19850Y172342D01*
X19975Y172800D01*
X20142Y173217D01*
X20350Y173675D01*
X20683Y174300D01*
X19017D01*
G01X11017Y229000D02*
Y231500D01*
X12058D01*
X12392Y231375D01*
X12600Y231208D01*
X12683Y230875D01*
X12600Y230542D01*
X12350Y230333D01*
X12058Y230208D01*
X11017D01*
G01X12058D02*
X12683Y229000D01*
G01X14033Y229375D02*
X14283Y229167D01*
X14575Y229042D01*
X14950Y229000D01*
X15325Y229083D01*
X15617Y229250D01*
X15825Y229542D01*
X15867Y229875D01*
X15783Y230208D01*
X15575Y230417D01*
X15283Y230583D01*
X14992Y230625D01*
X14700Y230583D01*
X14325Y230417D01*
X14450Y231500D01*
X15575D01*
G01X18550Y229000D02*
Y231500D01*
X17008Y229708D01*
X19092D01*
G01X21150Y229000D02*
X21442Y229042D01*
X21775Y229167D01*
X21983Y229375D01*
X22067Y229667D01*
X21983Y229958D01*
X21733Y230208D01*
X21358Y230333D01*
X20942D01*
X20692Y230417D01*
X20483Y230625D01*
X20400Y230917D01*
X20525Y231208D01*
X20817Y231417D01*
X21150Y231500D01*
X21483Y231417D01*
X21775Y231208D01*
X21900Y230917D01*
X21817Y230625D01*
X21608Y230417D01*
X21358Y230333D01*
X20942D01*
X20567Y230208D01*
X20317Y229958D01*
X20233Y229667D01*
X20317Y229375D01*
X20525Y229167D01*
X20858Y229042D01*
X21150Y229000D01*
G01X16400Y200817D02*
X13900D01*
Y201858D01*
X14025Y202192D01*
X14192Y202400D01*
X14525Y202483D01*
X14858Y202400D01*
X15067Y202150D01*
X15192Y201858D01*
Y200817D01*
G01Y201858D02*
X16400Y202483D01*
G01X16025Y203833D02*
X16233Y204083D01*
X16358Y204375D01*
X16400Y204750D01*
X16317Y205125D01*
X16150Y205417D01*
X15858Y205625D01*
X15525Y205667D01*
X15192Y205583D01*
X14983Y205375D01*
X14817Y205083D01*
X14775Y204792D01*
X14817Y204500D01*
X14983Y204125D01*
X13900Y204250D01*
Y205375D01*
G01X15900Y206933D02*
X16192Y207183D01*
X16358Y207517D01*
X16400Y207892D01*
X16358Y208225D01*
X16150Y208558D01*
X15900Y208767D01*
X15650Y208808D01*
X15358Y208725D01*
X15150Y208433D01*
X15067Y208142D01*
Y207767D01*
G01Y208142D02*
X14942Y208392D01*
X14733Y208600D01*
X14483Y208683D01*
X14233Y208600D01*
X14025Y208392D01*
X13900Y208017D01*
X13942Y207642D01*
X14108Y207267D01*
G01X14317Y210158D02*
X14067Y210408D01*
X13942Y210700D01*
X13900Y211033D01*
X13983Y211450D01*
X14192Y211742D01*
X14442Y211825D01*
X14692Y211783D01*
X14900Y211617D01*
X15317Y210783D01*
X15608Y210408D01*
X16025Y210158D01*
X16400Y210075D01*
Y211825D01*
G01X11017Y225000D02*
Y227500D01*
X12058D01*
X12392Y227375D01*
X12600Y227208D01*
X12683Y226875D01*
X12600Y226542D01*
X12350Y226333D01*
X12058Y226208D01*
X11017D01*
G01X12058D02*
X12683Y225000D01*
G01X15450D02*
Y227500D01*
X13908Y225708D01*
X15992D01*
G01X18050Y225000D02*
X18342Y225042D01*
X18675Y225167D01*
X18883Y225375D01*
X18967Y225667D01*
X18883Y225958D01*
X18633Y226208D01*
X18258Y226333D01*
X17842D01*
X17592Y226417D01*
X17383Y226625D01*
X17300Y226917D01*
X17425Y227208D01*
X17717Y227417D01*
X18050Y227500D01*
X18383Y227417D01*
X18675Y227208D01*
X18800Y226917D01*
X18717Y226625D01*
X18508Y226417D01*
X18258Y226333D01*
X17842D01*
X17467Y226208D01*
X17217Y225958D01*
X17133Y225667D01*
X17217Y225375D01*
X17425Y225167D01*
X17758Y225042D01*
X18050Y225000D01*
G01X21067D02*
X21150Y225542D01*
X21275Y226000D01*
X21442Y226417D01*
X21650Y226875D01*
X21983Y227500D01*
X20317D01*
G01X11267Y218292D02*
X11017Y218417D01*
X10725Y218500D01*
X10392D01*
X10017Y218375D01*
X9725Y218167D01*
X9517Y217917D01*
X9350Y217500D01*
X9308Y217125D01*
X9392Y216750D01*
X9517Y216500D01*
X9767Y216250D01*
X10058Y216083D01*
X10350Y216000D01*
X10642D01*
X10933Y216083D01*
X11183Y216208D01*
X11392Y216375D01*
G01X12658Y217042D02*
X12950Y217333D01*
X13200Y217500D01*
X13533Y217583D01*
X13825Y217500D01*
X14033Y217333D01*
X14200Y217083D01*
X14242Y216792D01*
X14200Y216542D01*
X14033Y216292D01*
X13783Y216083D01*
X13492Y216000D01*
X13158Y216083D01*
X12867Y216333D01*
X12700Y216708D01*
X12658Y217125D01*
X12742Y217667D01*
X12867Y217958D01*
X13075Y218250D01*
X13367Y218458D01*
X13658Y218500D01*
X13950Y218417D01*
X14158Y218208D01*
G01X17050Y216000D02*
Y218500D01*
X15508Y216708D01*
X17592D01*
G01X19567Y216000D02*
X19650Y216542D01*
X19775Y217000D01*
X19942Y217417D01*
X20150Y217875D01*
X20483Y218500D01*
X18817D01*
G01X11267Y222792D02*
X11017Y222917D01*
X10725Y223000D01*
X10392D01*
X10017Y222875D01*
X9725Y222667D01*
X9517Y222417D01*
X9350Y222000D01*
X9308Y221625D01*
X9392Y221250D01*
X9517Y221000D01*
X9767Y220750D01*
X10058Y220583D01*
X10350Y220500D01*
X10642D01*
X10933Y220583D01*
X11183Y220708D01*
X11392Y220875D01*
G01X13450Y220500D02*
Y223000D01*
X12950Y222500D01*
G01Y220500D02*
X13950D01*
G01X16550Y223000D02*
X16217Y222917D01*
X15967Y222708D01*
X15800Y222458D01*
X15675Y222125D01*
X15633Y221750D01*
X15675Y221375D01*
X15800Y221042D01*
X15967Y220792D01*
X16217Y220583D01*
X16550Y220500D01*
X16883Y220583D01*
X17133Y220792D01*
X17300Y221042D01*
X17425Y221375D01*
X17467Y221750D01*
X17425Y222125D01*
X17300Y222458D01*
X17133Y222708D01*
X16883Y222917D01*
X16550Y223000D01*
G01X19650Y220500D02*
X19942Y220542D01*
X20275Y220667D01*
X20483Y220875D01*
X20567Y221167D01*
X20483Y221458D01*
X20233Y221708D01*
X19858Y221833D01*
X19442D01*
X19192Y221917D01*
X18983Y222125D01*
X18900Y222417D01*
X19025Y222708D01*
X19317Y222917D01*
X19650Y223000D01*
X19983Y222917D01*
X20275Y222708D01*
X20400Y222417D01*
X20317Y222125D01*
X20108Y221917D01*
X19858Y221833D01*
X19442D01*
X19067Y221708D01*
X18817Y221458D01*
X18733Y221167D01*
X18817Y220875D01*
X19025Y220667D01*
X19358Y220542D01*
X19650Y220500D01*
G01X15200Y299017D02*
X12700D01*
Y300058D01*
X12825Y300392D01*
X12992Y300600D01*
X13325Y300683D01*
X13658Y300600D01*
X13867Y300350D01*
X13992Y300058D01*
Y299017D01*
G01Y300058D02*
X15200Y300683D01*
G01X14700Y302033D02*
X14992Y302283D01*
X15158Y302617D01*
X15200Y302992D01*
X15158Y303325D01*
X14950Y303658D01*
X14700Y303867D01*
X14450Y303908D01*
X14158Y303825D01*
X13950Y303533D01*
X13867Y303242D01*
Y302867D01*
G01Y303242D02*
X13742Y303492D01*
X13533Y303700D01*
X13283Y303783D01*
X13033Y303700D01*
X12825Y303492D01*
X12700Y303117D01*
X12742Y302742D01*
X12908Y302367D01*
G01X14700Y305133D02*
X14992Y305383D01*
X15158Y305717D01*
X15200Y306092D01*
X15158Y306425D01*
X14950Y306758D01*
X14700Y306967D01*
X14450Y307008D01*
X14158Y306925D01*
X13950Y306633D01*
X13867Y306342D01*
Y305967D01*
G01Y306342D02*
X13742Y306592D01*
X13533Y306800D01*
X13283Y306883D01*
X13033Y306800D01*
X12825Y306592D01*
X12700Y306217D01*
X12742Y305842D01*
X12908Y305467D01*
G01X15200Y309067D02*
X14658Y309150D01*
X14200Y309275D01*
X13783Y309442D01*
X13325Y309650D01*
X12700Y309983D01*
Y308317D01*
G01X10217Y281200D02*
Y283700D01*
X11258D01*
X11592Y283575D01*
X11800Y283408D01*
X11883Y283075D01*
X11800Y282742D01*
X11550Y282533D01*
X11258Y282408D01*
X10217D01*
G01X11258D02*
X11883Y281200D01*
G01X13233Y281700D02*
X13483Y281408D01*
X13817Y281242D01*
X14192Y281200D01*
X14525Y281242D01*
X14858Y281450D01*
X15067Y281700D01*
X15108Y281950D01*
X15025Y282242D01*
X14733Y282450D01*
X14442Y282533D01*
X14067D01*
G01X14442D02*
X14692Y282658D01*
X14900Y282867D01*
X14983Y283117D01*
X14900Y283367D01*
X14692Y283575D01*
X14317Y283700D01*
X13942Y283658D01*
X13567Y283492D01*
G01X16333Y281575D02*
X16583Y281367D01*
X16875Y281242D01*
X17250Y281200D01*
X17625Y281283D01*
X17917Y281450D01*
X18125Y281742D01*
X18167Y282075D01*
X18083Y282408D01*
X17875Y282617D01*
X17583Y282783D01*
X17292Y282825D01*
X17000Y282783D01*
X16625Y282617D01*
X16750Y283700D01*
X17875D01*
G01X20267Y281200D02*
X20350Y281742D01*
X20475Y282200D01*
X20642Y282617D01*
X20850Y283075D01*
X21183Y283700D01*
X19517D01*
G01X10217Y294700D02*
Y297200D01*
X11258D01*
X11592Y297075D01*
X11800Y296908D01*
X11883Y296575D01*
X11800Y296242D01*
X11550Y296033D01*
X11258Y295908D01*
X10217D01*
G01X11258D02*
X11883Y294700D01*
G01X13233Y295200D02*
X13483Y294908D01*
X13817Y294742D01*
X14192Y294700D01*
X14525Y294742D01*
X14858Y294950D01*
X15067Y295200D01*
X15108Y295450D01*
X15025Y295742D01*
X14733Y295950D01*
X14442Y296033D01*
X14067D01*
G01X14442D02*
X14692Y296158D01*
X14900Y296367D01*
X14983Y296617D01*
X14900Y296867D01*
X14692Y297075D01*
X14317Y297200D01*
X13942Y297158D01*
X13567Y296992D01*
G01X16333Y295075D02*
X16583Y294867D01*
X16875Y294742D01*
X17250Y294700D01*
X17625Y294783D01*
X17917Y294950D01*
X18125Y295242D01*
X18167Y295575D01*
X18083Y295908D01*
X17875Y296117D01*
X17583Y296283D01*
X17292Y296325D01*
X17000Y296283D01*
X16625Y296117D01*
X16750Y297200D01*
X17875D01*
G01X20350Y294700D02*
X20642Y294742D01*
X20975Y294867D01*
X21183Y295075D01*
X21267Y295367D01*
X21183Y295658D01*
X20933Y295908D01*
X20558Y296033D01*
X20142D01*
X19892Y296117D01*
X19683Y296325D01*
X19600Y296617D01*
X19725Y296908D01*
X20017Y297117D01*
X20350Y297200D01*
X20683Y297117D01*
X20975Y296908D01*
X21100Y296617D01*
X21017Y296325D01*
X20808Y296117D01*
X20558Y296033D01*
X20142D01*
X19767Y295908D01*
X19517Y295658D01*
X19433Y295367D01*
X19517Y295075D01*
X19725Y294867D01*
X20058Y294742D01*
X20350Y294700D01*
G01X10217Y290200D02*
Y292700D01*
X11258D01*
X11592Y292575D01*
X11800Y292408D01*
X11883Y292075D01*
X11800Y291742D01*
X11550Y291533D01*
X11258Y291408D01*
X10217D01*
G01X11258D02*
X11883Y290200D01*
G01X13233Y290700D02*
X13483Y290408D01*
X13817Y290242D01*
X14192Y290200D01*
X14525Y290242D01*
X14858Y290450D01*
X15067Y290700D01*
X15108Y290950D01*
X15025Y291242D01*
X14733Y291450D01*
X14442Y291533D01*
X14067D01*
G01X14442D02*
X14692Y291658D01*
X14900Y291867D01*
X14983Y292117D01*
X14900Y292367D01*
X14692Y292575D01*
X14317Y292700D01*
X13942Y292658D01*
X13567Y292492D01*
G01X16458Y291242D02*
X16750Y291533D01*
X17000Y291700D01*
X17333Y291783D01*
X17625Y291700D01*
X17833Y291533D01*
X18000Y291283D01*
X18042Y290992D01*
X18000Y290742D01*
X17833Y290492D01*
X17583Y290283D01*
X17292Y290200D01*
X16958Y290283D01*
X16667Y290533D01*
X16500Y290908D01*
X16458Y291325D01*
X16542Y291867D01*
X16667Y292158D01*
X16875Y292450D01*
X17167Y292658D01*
X17458Y292700D01*
X17750Y292617D01*
X17958Y292408D01*
G01X20350Y292700D02*
X20017Y292617D01*
X19767Y292408D01*
X19600Y292158D01*
X19475Y291825D01*
X19433Y291450D01*
X19475Y291075D01*
X19600Y290742D01*
X19767Y290492D01*
X20017Y290283D01*
X20350Y290200D01*
X20683Y290283D01*
X20933Y290492D01*
X21100Y290742D01*
X21225Y291075D01*
X21267Y291450D01*
X21225Y291825D01*
X21100Y292158D01*
X20933Y292408D01*
X20683Y292617D01*
X20350Y292700D01*
G01X14100Y269217D02*
X11600D01*
Y270258D01*
X11725Y270592D01*
X11892Y270800D01*
X12225Y270883D01*
X12558Y270800D01*
X12767Y270550D01*
X12892Y270258D01*
Y269217D01*
G01Y270258D02*
X14100Y270883D01*
G01X13600Y272233D02*
X13892Y272483D01*
X14058Y272817D01*
X14100Y273192D01*
X14058Y273525D01*
X13850Y273858D01*
X13600Y274067D01*
X13350Y274108D01*
X13058Y274025D01*
X12850Y273733D01*
X12767Y273442D01*
Y273067D01*
G01Y273442D02*
X12642Y273692D01*
X12433Y273900D01*
X12183Y273983D01*
X11933Y273900D01*
X11725Y273692D01*
X11600Y273317D01*
X11642Y272942D01*
X11808Y272567D01*
G01X13058Y275458D02*
X12767Y275750D01*
X12600Y276000D01*
X12517Y276333D01*
X12600Y276625D01*
X12767Y276833D01*
X13017Y277000D01*
X13308Y277042D01*
X13558Y277000D01*
X13808Y276833D01*
X14017Y276583D01*
X14100Y276292D01*
X14017Y275958D01*
X13767Y275667D01*
X13392Y275500D01*
X12975Y275458D01*
X12433Y275542D01*
X12142Y275667D01*
X11850Y275875D01*
X11642Y276167D01*
X11600Y276458D01*
X11683Y276750D01*
X11892Y276958D01*
G01X14100Y279350D02*
X11600D01*
X12100Y278850D01*
G01X14100D02*
Y279850D01*
G01X10217Y285700D02*
Y288200D01*
X11258D01*
X11592Y288075D01*
X11800Y287908D01*
X11883Y287575D01*
X11800Y287242D01*
X11550Y287033D01*
X11258Y286908D01*
X10217D01*
G01X11258D02*
X11883Y285700D01*
G01X13233Y286200D02*
X13483Y285908D01*
X13817Y285742D01*
X14192Y285700D01*
X14525Y285742D01*
X14858Y285950D01*
X15067Y286200D01*
X15108Y286450D01*
X15025Y286742D01*
X14733Y286950D01*
X14442Y287033D01*
X14067D01*
G01X14442D02*
X14692Y287158D01*
X14900Y287367D01*
X14983Y287617D01*
X14900Y287867D01*
X14692Y288075D01*
X14317Y288200D01*
X13942Y288158D01*
X13567Y287992D01*
G01X16458Y286742D02*
X16750Y287033D01*
X17000Y287200D01*
X17333Y287283D01*
X17625Y287200D01*
X17833Y287033D01*
X18000Y286783D01*
X18042Y286492D01*
X18000Y286242D01*
X17833Y285992D01*
X17583Y285783D01*
X17292Y285700D01*
X16958Y285783D01*
X16667Y286033D01*
X16500Y286408D01*
X16458Y286825D01*
X16542Y287367D01*
X16667Y287658D01*
X16875Y287950D01*
X17167Y288158D01*
X17458Y288200D01*
X17750Y288117D01*
X17958Y287908D01*
G01X19433Y286200D02*
X19683Y285908D01*
X20017Y285742D01*
X20392Y285700D01*
X20725Y285742D01*
X21058Y285950D01*
X21267Y286200D01*
X21308Y286450D01*
X21225Y286742D01*
X20933Y286950D01*
X20642Y287033D01*
X20267D01*
G01X20642D02*
X20892Y287158D01*
X21100Y287367D01*
X21183Y287617D01*
X21100Y287867D01*
X20892Y288075D01*
X20517Y288200D01*
X20142Y288158D01*
X19767Y287992D01*
G01X11017Y325500D02*
Y328000D01*
X12058D01*
X12392Y327875D01*
X12600Y327708D01*
X12683Y327375D01*
X12600Y327042D01*
X12350Y326833D01*
X12058Y326708D01*
X11017D01*
G01X12058D02*
X12683Y325500D01*
G01X14033Y326000D02*
X14283Y325708D01*
X14617Y325542D01*
X14992Y325500D01*
X15325Y325542D01*
X15658Y325750D01*
X15867Y326000D01*
X15908Y326250D01*
X15825Y326542D01*
X15533Y326750D01*
X15242Y326833D01*
X14867D01*
G01X15242D02*
X15492Y326958D01*
X15700Y327167D01*
X15783Y327417D01*
X15700Y327667D01*
X15492Y327875D01*
X15117Y328000D01*
X14742Y327958D01*
X14367Y327792D01*
G01X17133Y326000D02*
X17383Y325708D01*
X17717Y325542D01*
X18092Y325500D01*
X18425Y325542D01*
X18758Y325750D01*
X18967Y326000D01*
X19008Y326250D01*
X18925Y326542D01*
X18633Y326750D01*
X18342Y326833D01*
X17967D01*
G01X18342D02*
X18592Y326958D01*
X18800Y327167D01*
X18883Y327417D01*
X18800Y327667D01*
X18592Y327875D01*
X18217Y328000D01*
X17842Y327958D01*
X17467Y327792D01*
G01X20233Y325875D02*
X20483Y325667D01*
X20775Y325542D01*
X21150Y325500D01*
X21525Y325583D01*
X21817Y325750D01*
X22025Y326042D01*
X22067Y326375D01*
X21983Y326708D01*
X21775Y326917D01*
X21483Y327083D01*
X21192Y327125D01*
X20900Y327083D01*
X20525Y326917D01*
X20650Y328000D01*
X21775D01*
G01X11017Y312000D02*
Y314500D01*
X12058D01*
X12392Y314375D01*
X12600Y314208D01*
X12683Y313875D01*
X12600Y313542D01*
X12350Y313333D01*
X12058Y313208D01*
X11017D01*
G01X12058D02*
X12683Y312000D01*
G01X14033Y312500D02*
X14283Y312208D01*
X14617Y312042D01*
X14992Y312000D01*
X15325Y312042D01*
X15658Y312250D01*
X15867Y312500D01*
X15908Y312750D01*
X15825Y313042D01*
X15533Y313250D01*
X15242Y313333D01*
X14867D01*
G01X15242D02*
X15492Y313458D01*
X15700Y313667D01*
X15783Y313917D01*
X15700Y314167D01*
X15492Y314375D01*
X15117Y314500D01*
X14742Y314458D01*
X14367Y314292D01*
G01X17133Y312500D02*
X17383Y312208D01*
X17717Y312042D01*
X18092Y312000D01*
X18425Y312042D01*
X18758Y312250D01*
X18967Y312500D01*
X19008Y312750D01*
X18925Y313042D01*
X18633Y313250D01*
X18342Y313333D01*
X17967D01*
G01X18342D02*
X18592Y313458D01*
X18800Y313667D01*
X18883Y313917D01*
X18800Y314167D01*
X18592Y314375D01*
X18217Y314500D01*
X17842Y314458D01*
X17467Y314292D01*
G01X20358Y313042D02*
X20650Y313333D01*
X20900Y313500D01*
X21233Y313583D01*
X21525Y313500D01*
X21733Y313333D01*
X21900Y313083D01*
X21942Y312792D01*
X21900Y312542D01*
X21733Y312292D01*
X21483Y312083D01*
X21192Y312000D01*
X20858Y312083D01*
X20567Y312333D01*
X20400Y312708D01*
X20358Y313125D01*
X20442Y313667D01*
X20567Y313958D01*
X20775Y314250D01*
X21067Y314458D01*
X21358Y314500D01*
X21650Y314417D01*
X21858Y314208D01*
G01X11017Y321000D02*
Y323500D01*
X12058D01*
X12392Y323375D01*
X12600Y323208D01*
X12683Y322875D01*
X12600Y322542D01*
X12350Y322333D01*
X12058Y322208D01*
X11017D01*
G01X12058D02*
X12683Y321000D01*
G01X14033Y321500D02*
X14283Y321208D01*
X14617Y321042D01*
X14992Y321000D01*
X15325Y321042D01*
X15658Y321250D01*
X15867Y321500D01*
X15908Y321750D01*
X15825Y322042D01*
X15533Y322250D01*
X15242Y322333D01*
X14867D01*
G01X15242D02*
X15492Y322458D01*
X15700Y322667D01*
X15783Y322917D01*
X15700Y323167D01*
X15492Y323375D01*
X15117Y323500D01*
X14742Y323458D01*
X14367Y323292D01*
G01X18550Y321000D02*
Y323500D01*
X17008Y321708D01*
X19092D01*
G01X21650Y321000D02*
Y323500D01*
X20108Y321708D01*
X22192D01*
G01X11017Y316500D02*
Y319000D01*
X12058D01*
X12392Y318875D01*
X12600Y318708D01*
X12683Y318375D01*
X12600Y318042D01*
X12350Y317833D01*
X12058Y317708D01*
X11017D01*
G01X12058D02*
X12683Y316500D01*
G01X14033Y317000D02*
X14283Y316708D01*
X14617Y316542D01*
X14992Y316500D01*
X15325Y316542D01*
X15658Y316750D01*
X15867Y317000D01*
X15908Y317250D01*
X15825Y317542D01*
X15533Y317750D01*
X15242Y317833D01*
X14867D01*
G01X15242D02*
X15492Y317958D01*
X15700Y318167D01*
X15783Y318417D01*
X15700Y318667D01*
X15492Y318875D01*
X15117Y319000D01*
X14742Y318958D01*
X14367Y318792D01*
G01X18550Y316500D02*
Y319000D01*
X17008Y317208D01*
X19092D01*
G01X20233Y316875D02*
X20483Y316667D01*
X20775Y316542D01*
X21150Y316500D01*
X21525Y316583D01*
X21817Y316750D01*
X22025Y317042D01*
X22067Y317375D01*
X21983Y317708D01*
X21775Y317917D01*
X21483Y318083D01*
X21192Y318125D01*
X20900Y318083D01*
X20525Y317917D01*
X20650Y319000D01*
X21775D01*
G01X15267Y338959D02*
X15017Y339084D01*
X14725Y339167D01*
X14392D01*
X14017Y339042D01*
X13725Y338834D01*
X13517Y338584D01*
X13350Y338167D01*
X13308Y337792D01*
X13392Y337417D01*
X13517Y337167D01*
X13767Y336917D01*
X14058Y336750D01*
X14350Y336667D01*
X14642D01*
X14933Y336750D01*
X15183Y336875D01*
X15392Y337042D01*
G01X16533D02*
X16783Y336834D01*
X17075Y336709D01*
X17450Y336667D01*
X17825Y336750D01*
X18117Y336917D01*
X18325Y337209D01*
X18367Y337542D01*
X18283Y337875D01*
X18075Y338084D01*
X17783Y338250D01*
X17492Y338292D01*
X17200Y338250D01*
X16825Y338084D01*
X16950Y339167D01*
X18075D01*
G01X21050Y336667D02*
Y339167D01*
X19508Y337375D01*
X21592D01*
G01X22733Y337042D02*
X22983Y336834D01*
X23275Y336709D01*
X23650Y336667D01*
X24025Y336750D01*
X24317Y336917D01*
X24525Y337209D01*
X24567Y337542D01*
X24483Y337875D01*
X24275Y338084D01*
X23983Y338250D01*
X23692Y338292D01*
X23400Y338250D01*
X23025Y338084D01*
X23150Y339167D01*
X24275D01*
G01X10933Y370217D02*
X8433D01*
Y371258D01*
X8558Y371592D01*
X8725Y371800D01*
X9058Y371883D01*
X9391Y371800D01*
X9600Y371550D01*
X9725Y371258D01*
Y370217D01*
G01Y371258D02*
X10933Y371883D01*
G01Y374650D02*
X8433D01*
X10225Y373108D01*
Y375192D01*
G01X8850Y376458D02*
X8600Y376708D01*
X8475Y377000D01*
X8433Y377333D01*
X8516Y377750D01*
X8725Y378042D01*
X8975Y378125D01*
X9225Y378083D01*
X9433Y377917D01*
X9850Y377083D01*
X10141Y376708D01*
X10558Y376458D01*
X10933Y376375D01*
Y378125D01*
G01X10558Y379433D02*
X10766Y379683D01*
X10891Y379975D01*
X10933Y380350D01*
X10850Y380725D01*
X10683Y381017D01*
X10391Y381225D01*
X10058Y381267D01*
X9725Y381183D01*
X9516Y380975D01*
X9350Y380683D01*
X9308Y380392D01*
X9350Y380100D01*
X9516Y379725D01*
X8433Y379850D01*
Y380975D01*
G01X7517Y366000D02*
Y368500D01*
X8558D01*
X8892Y368375D01*
X9100Y368208D01*
X9183Y367875D01*
X9100Y367542D01*
X8850Y367333D01*
X8558Y367208D01*
X7517D01*
G01X8558D02*
X9183Y366000D01*
G01X11950D02*
Y368500D01*
X10408Y366708D01*
X12492D01*
G01X14550Y366000D02*
Y368500D01*
X14050Y368000D01*
G01Y366000D02*
X15050D01*
G01X16733Y366375D02*
X16983Y366167D01*
X17275Y366042D01*
X17650Y366000D01*
X18025Y366083D01*
X18317Y366250D01*
X18525Y366542D01*
X18567Y366875D01*
X18483Y367208D01*
X18275Y367417D01*
X17983Y367583D01*
X17692Y367625D01*
X17400Y367583D01*
X17025Y367417D01*
X17150Y368500D01*
X18275D01*
G01X12308Y372119D02*
X12183Y371869D01*
X12100Y371577D01*
Y371244D01*
X12225Y370869D01*
X12433Y370577D01*
X12683Y370369D01*
X13100Y370202D01*
X13475Y370160D01*
X13850Y370244D01*
X14100Y370369D01*
X14350Y370619D01*
X14517Y370910D01*
X14600Y371202D01*
Y371494D01*
X14517Y371785D01*
X14392Y372035D01*
X14225Y372244D01*
G01Y373385D02*
X14433Y373635D01*
X14558Y373927D01*
X14600Y374302D01*
X14517Y374677D01*
X14350Y374969D01*
X14058Y375177D01*
X13725Y375219D01*
X13392Y375135D01*
X13183Y374927D01*
X13017Y374635D01*
X12975Y374344D01*
X13017Y374052D01*
X13183Y373677D01*
X12100Y373802D01*
Y374927D01*
G01X14600Y377902D02*
X12100D01*
X13892Y376360D01*
Y378444D01*
G01X14600Y380502D02*
X14558Y380794D01*
X14433Y381127D01*
X14225Y381335D01*
X13933Y381419D01*
X13642Y381335D01*
X13392Y381085D01*
X13267Y380710D01*
Y380294D01*
X13183Y380044D01*
X12975Y379835D01*
X12683Y379752D01*
X12392Y379877D01*
X12183Y380169D01*
X12100Y380502D01*
X12183Y380835D01*
X12392Y381127D01*
X12683Y381252D01*
X12975Y381169D01*
X13183Y380960D01*
X13267Y380710D01*
Y380294D01*
X13392Y379919D01*
X13642Y379669D01*
X13933Y379585D01*
X14225Y379669D01*
X14433Y379877D01*
X14558Y380210D01*
X14600Y380502D01*
G01X60517Y155000D02*
Y157500D01*
X61558D01*
X61892Y157375D01*
X62100Y157208D01*
X62183Y156875D01*
X62100Y156542D01*
X61850Y156333D01*
X61558Y156208D01*
X60517D01*
G01X61558D02*
X62183Y155000D01*
G01X63533Y155375D02*
X63783Y155167D01*
X64075Y155042D01*
X64450Y155000D01*
X64825Y155083D01*
X65117Y155250D01*
X65325Y155542D01*
X65367Y155875D01*
X65283Y156208D01*
X65075Y156417D01*
X64783Y156583D01*
X64492Y156625D01*
X64200Y156583D01*
X63825Y156417D01*
X63950Y157500D01*
X65075D01*
G01X66633Y155500D02*
X66883Y155208D01*
X67217Y155042D01*
X67592Y155000D01*
X67925Y155042D01*
X68258Y155250D01*
X68467Y155500D01*
X68508Y155750D01*
X68425Y156042D01*
X68133Y156250D01*
X67842Y156333D01*
X67467D01*
G01X67842D02*
X68092Y156458D01*
X68300Y156667D01*
X68383Y156917D01*
X68300Y157167D01*
X68092Y157375D01*
X67717Y157500D01*
X67342Y157458D01*
X66967Y157292D01*
G01X70650Y155000D02*
Y157500D01*
X70150Y157000D01*
G01Y155000D02*
X71150D01*
G01X58500Y150000D02*
Y154000D01*
X51100D01*
G01X25600Y167500D02*
Y163500D01*
X33000D01*
G01X62267Y175792D02*
X62017Y175917D01*
X61725Y176000D01*
X61392D01*
X61017Y175875D01*
X60725Y175667D01*
X60517Y175417D01*
X60350Y175000D01*
X60308Y174625D01*
X60392Y174250D01*
X60517Y174000D01*
X60767Y173750D01*
X61058Y173583D01*
X61350Y173500D01*
X61642D01*
X61933Y173583D01*
X62183Y173708D01*
X62392Y173875D01*
G01X63533D02*
X63783Y173667D01*
X64075Y173542D01*
X64450Y173500D01*
X64825Y173583D01*
X65117Y173750D01*
X65325Y174042D01*
X65367Y174375D01*
X65283Y174708D01*
X65075Y174917D01*
X64783Y175083D01*
X64492Y175125D01*
X64200Y175083D01*
X63825Y174917D01*
X63950Y176000D01*
X65075D01*
G01X66758Y175583D02*
X67008Y175833D01*
X67300Y175958D01*
X67633Y176000D01*
X68050Y175917D01*
X68342Y175708D01*
X68425Y175458D01*
X68383Y175208D01*
X68217Y175000D01*
X67383Y174583D01*
X67008Y174292D01*
X66758Y173875D01*
X66675Y173500D01*
X68425D01*
G01X69858Y175583D02*
X70108Y175833D01*
X70400Y175958D01*
X70733Y176000D01*
X71150Y175917D01*
X71442Y175708D01*
X71525Y175458D01*
X71483Y175208D01*
X71317Y175000D01*
X70483Y174583D01*
X70108Y174292D01*
X69858Y173875D01*
X69775Y173500D01*
X71525D01*
G01X78267Y175992D02*
X78017Y176117D01*
X77725Y176200D01*
X77392D01*
X77017Y176075D01*
X76725Y175867D01*
X76517Y175617D01*
X76350Y175200D01*
X76308Y174825D01*
X76392Y174450D01*
X76517Y174200D01*
X76767Y173950D01*
X77058Y173783D01*
X77350Y173700D01*
X77642D01*
X77933Y173783D01*
X78183Y173908D01*
X78392Y174075D01*
G01X79533D02*
X79783Y173867D01*
X80075Y173742D01*
X80450Y173700D01*
X80825Y173783D01*
X81117Y173950D01*
X81325Y174242D01*
X81367Y174575D01*
X81283Y174908D01*
X81075Y175117D01*
X80783Y175283D01*
X80492Y175325D01*
X80200Y175283D01*
X79825Y175117D01*
X79950Y176200D01*
X81075D01*
G01X83467Y173700D02*
X83550Y174242D01*
X83675Y174700D01*
X83842Y175117D01*
X84050Y175575D01*
X84383Y176200D01*
X82717D01*
G01X87150Y173700D02*
Y176200D01*
X85608Y174408D01*
X87692D01*
G01X64500Y161017D02*
X62000D01*
Y162058D01*
X62125Y162392D01*
X62292Y162600D01*
X62625Y162683D01*
X62958Y162600D01*
X63167Y162350D01*
X63292Y162058D01*
Y161017D01*
G01Y162058D02*
X64500Y162683D01*
G01X64125Y164033D02*
X64333Y164283D01*
X64458Y164575D01*
X64500Y164950D01*
X64417Y165325D01*
X64250Y165617D01*
X63958Y165825D01*
X63625Y165867D01*
X63292Y165783D01*
X63083Y165575D01*
X62917Y165283D01*
X62875Y164992D01*
X62917Y164700D01*
X63083Y164325D01*
X62000Y164450D01*
Y165575D01*
G01X62417Y167258D02*
X62167Y167508D01*
X62042Y167800D01*
X62000Y168133D01*
X62083Y168550D01*
X62292Y168842D01*
X62542Y168925D01*
X62792Y168883D01*
X63000Y168717D01*
X63417Y167883D01*
X63708Y167508D01*
X64125Y167258D01*
X64500Y167175D01*
Y168925D01*
G01X62000Y171150D02*
X62083Y170817D01*
X62292Y170567D01*
X62542Y170400D01*
X62875Y170275D01*
X63250Y170233D01*
X63625Y170275D01*
X63958Y170400D01*
X64208Y170567D01*
X64417Y170817D01*
X64500Y171150D01*
X64417Y171483D01*
X64208Y171733D01*
X63958Y171900D01*
X63625Y172025D01*
X63250Y172067D01*
X62875Y172025D01*
X62542Y171900D01*
X62292Y171733D01*
X62083Y171483D01*
X62000Y171150D01*
G01X50607Y166352D02*
X54607D01*
Y173752D01*
G01X68755Y161165D02*
X66255D01*
Y162206D01*
X66380Y162540D01*
X66547Y162748D01*
X66880Y162831D01*
X67213Y162748D01*
X67422Y162498D01*
X67547Y162206D01*
Y161165D01*
G01Y162206D02*
X68755Y162831D01*
G01X68380Y164181D02*
X68588Y164431D01*
X68713Y164723D01*
X68755Y165098D01*
X68672Y165473D01*
X68505Y165765D01*
X68213Y165973D01*
X67880Y166015D01*
X67547Y165931D01*
X67338Y165723D01*
X67172Y165431D01*
X67130Y165140D01*
X67172Y164848D01*
X67338Y164473D01*
X66255Y164598D01*
Y165723D01*
G01X68755Y168198D02*
X66255D01*
X66755Y167698D01*
G01X68755D02*
Y168698D01*
G01X68463Y170590D02*
X68672Y170881D01*
X68755Y171215D01*
X68672Y171548D01*
X68422Y171840D01*
X68047Y172048D01*
X67672Y172131D01*
X67213D01*
X66838Y172048D01*
X66505Y171840D01*
X66338Y171590D01*
X66255Y171298D01*
X66338Y170965D01*
X66505Y170715D01*
X66755Y170548D01*
X67088Y170465D01*
X67380Y170548D01*
X67672Y170756D01*
X67838Y171006D01*
X67880Y171298D01*
X67797Y171631D01*
X67588Y171881D01*
X67213Y172131D01*
G01X54607Y166352D02*
X58607D01*
Y173752D01*
G01X21400Y138500D02*
X21067Y138542D01*
X20775Y138708D01*
X20525Y138958D01*
X20358Y139250D01*
X20275Y139583D01*
Y139917D01*
X20358Y140250D01*
X20525Y140542D01*
X20775Y140792D01*
X21067Y140958D01*
X21400Y141000D01*
X21733Y140958D01*
X22025Y140792D01*
X22275Y140542D01*
X22442Y140250D01*
X22525Y139917D01*
Y139583D01*
X22442Y139250D01*
X22275Y138958D01*
X22025Y138708D01*
X21733Y138542D01*
X21400Y138500D01*
G01X21733Y139167D02*
X22233Y138500D01*
G01X23708Y140583D02*
X23958Y140833D01*
X24250Y140958D01*
X24583Y141000D01*
X25000Y140917D01*
X25292Y140708D01*
X25375Y140458D01*
X25333Y140208D01*
X25167Y140000D01*
X24333Y139583D01*
X23958Y139292D01*
X23708Y138875D01*
X23625Y138500D01*
X25375D01*
G01X26683Y139000D02*
X26933Y138708D01*
X27267Y138542D01*
X27642Y138500D01*
X27975Y138542D01*
X28308Y138750D01*
X28517Y139000D01*
X28558Y139250D01*
X28475Y139542D01*
X28183Y139750D01*
X27892Y139833D01*
X27517D01*
G01X27892D02*
X28142Y139958D01*
X28350Y140167D01*
X28433Y140417D01*
X28350Y140667D01*
X28142Y140875D01*
X27767Y141000D01*
X27392Y140958D01*
X27017Y140792D01*
G01X30850Y116700D02*
X52550D01*
G01X30850Y146700D02*
Y116700D01*
G01X52550Y146700D02*
X30850D01*
G01X52550Y116700D02*
Y146700D01*
G01X72983Y141500D02*
Y144000D01*
X73817D01*
X74150Y143875D01*
X74400Y143708D01*
X74608Y143458D01*
X74775Y143167D01*
X74817Y142750D01*
X74775Y142333D01*
X74608Y142042D01*
X74400Y141792D01*
X74150Y141625D01*
X73817Y141500D01*
X72983D01*
G01X76083Y142000D02*
X76333Y141708D01*
X76667Y141542D01*
X77042Y141500D01*
X77375Y141542D01*
X77708Y141750D01*
X77917Y142000D01*
X77958Y142250D01*
X77875Y142542D01*
X77583Y142750D01*
X77292Y142833D01*
X76917D01*
G01X77292D02*
X77542Y142958D01*
X77750Y143167D01*
X77833Y143417D01*
X77750Y143667D01*
X77542Y143875D01*
X77167Y144000D01*
X76792Y143958D01*
X76417Y143792D01*
G01X80017Y141500D02*
X80100Y142042D01*
X80225Y142500D01*
X80392Y142917D01*
X80600Y143375D01*
X80933Y144000D01*
X79267D01*
G01X81150Y138200D02*
X72050D01*
Y116400D01*
X81150D01*
Y138200D01*
G01X20500Y149917D02*
X18000D01*
Y150958D01*
X18125Y151292D01*
X18292Y151500D01*
X18625Y151583D01*
X18958Y151500D01*
X19167Y151250D01*
X19292Y150958D01*
Y149917D01*
G01Y150958D02*
X20500Y151583D01*
G01X20125Y152933D02*
X20333Y153183D01*
X20458Y153475D01*
X20500Y153850D01*
X20417Y154225D01*
X20250Y154517D01*
X19958Y154725D01*
X19625Y154767D01*
X19292Y154683D01*
X19083Y154475D01*
X18917Y154183D01*
X18875Y153892D01*
X18917Y153600D01*
X19083Y153225D01*
X18000Y153350D01*
Y154475D01*
G01X18417Y156158D02*
X18167Y156408D01*
X18042Y156700D01*
X18000Y157033D01*
X18083Y157450D01*
X18292Y157742D01*
X18542Y157825D01*
X18792Y157783D01*
X19000Y157617D01*
X19417Y156783D01*
X19708Y156408D01*
X20125Y156158D01*
X20500Y156075D01*
Y157825D01*
G01X19458Y159258D02*
X19167Y159550D01*
X19000Y159800D01*
X18917Y160133D01*
X19000Y160425D01*
X19167Y160633D01*
X19417Y160800D01*
X19708Y160842D01*
X19958Y160800D01*
X20208Y160633D01*
X20417Y160383D01*
X20500Y160092D01*
X20417Y159758D01*
X20167Y159467D01*
X19792Y159300D01*
X19375Y159258D01*
X18833Y159342D01*
X18542Y159467D01*
X18250Y159675D01*
X18042Y159967D01*
X18000Y160258D01*
X18083Y160550D01*
X18292Y160758D01*
G01X29500Y148800D02*
Y154000D01*
G01X36500Y148800D02*
Y156600D01*
G01X29500Y148800D02*
X36500D01*
G01X29500Y162200D02*
Y153500D01*
G01X36500Y162200D02*
X29500D01*
G01X36500Y155800D02*
Y162200D01*
G01X22600Y175000D02*
X27800D01*
G01X22600Y168000D02*
X30400D01*
G01X22600Y175000D02*
Y168000D01*
G01X36000Y175000D02*
X27300D01*
G01X36000Y168000D02*
Y175000D01*
G01X29600Y168000D02*
X36000D01*
G01X49987Y163531D02*
Y177531D01*
G01X36987Y163531D02*
X49987D01*
G01X36987Y177531D02*
Y163531D01*
G01X60567Y146500D02*
Y149000D01*
X61608D01*
X61942Y148875D01*
X62150Y148708D01*
X62233Y148375D01*
X62150Y148042D01*
X61900Y147833D01*
X61608Y147708D01*
X60567D01*
G01X61608D02*
X62233Y146500D01*
G01X64500D02*
Y149000D01*
X64000Y148500D01*
G01Y146500D02*
X65000D01*
G01X68100D02*
Y149000D01*
X66558Y147208D01*
X68642D01*
G01X69700Y127950D02*
X56700D01*
Y143450D01*
X69700D01*
Y127950D01*
G01X58541Y236486D02*
X54541D01*
Y229086D01*
G01X77500Y236500D02*
X73500D01*
Y229100D01*
G01X34000Y232517D02*
X31500D01*
Y233558D01*
X31625Y233892D01*
X31792Y234100D01*
X32125Y234183D01*
X32458Y234100D01*
X32667Y233850D01*
X32792Y233558D01*
Y232517D01*
G01Y233558D02*
X34000Y234183D01*
G01X32958Y235658D02*
X32667Y235950D01*
X32500Y236200D01*
X32417Y236533D01*
X32500Y236825D01*
X32667Y237033D01*
X32917Y237200D01*
X33208Y237242D01*
X33458Y237200D01*
X33708Y237033D01*
X33917Y236783D01*
X34000Y236492D01*
X33917Y236158D01*
X33667Y235867D01*
X33292Y235700D01*
X32875Y235658D01*
X32333Y235742D01*
X32042Y235867D01*
X31750Y236075D01*
X31542Y236367D01*
X31500Y236658D01*
X31583Y236950D01*
X31792Y237158D01*
G01X34000Y239550D02*
X33958Y239842D01*
X33833Y240175D01*
X33625Y240383D01*
X33333Y240467D01*
X33042Y240383D01*
X32792Y240133D01*
X32667Y239758D01*
Y239342D01*
X32583Y239092D01*
X32375Y238883D01*
X32083Y238800D01*
X31792Y238925D01*
X31583Y239217D01*
X31500Y239550D01*
X31583Y239883D01*
X31792Y240175D01*
X32083Y240300D01*
X32375Y240217D01*
X32583Y240008D01*
X32667Y239758D01*
Y239342D01*
X32792Y238967D01*
X33042Y238717D01*
X33333Y238633D01*
X33625Y238717D01*
X33833Y238925D01*
X33958Y239258D01*
X34000Y239550D01*
G01Y242650D02*
X33958Y242942D01*
X33833Y243275D01*
X33625Y243483D01*
X33333Y243567D01*
X33042Y243483D01*
X32792Y243233D01*
X32667Y242858D01*
Y242442D01*
X32583Y242192D01*
X32375Y241983D01*
X32083Y241900D01*
X31792Y242025D01*
X31583Y242317D01*
X31500Y242650D01*
X31583Y242983D01*
X31792Y243275D01*
X32083Y243400D01*
X32375Y243317D01*
X32583Y243108D01*
X32667Y242858D01*
Y242442D01*
X32792Y242067D01*
X33042Y241817D01*
X33333Y241733D01*
X33625Y241817D01*
X33833Y242025D01*
X33958Y242358D01*
X34000Y242650D01*
G01X35700Y228900D02*
X31700D01*
Y221500D01*
G01X78800Y188600D02*
X74800D01*
Y181200D01*
G01X24200Y229500D02*
Y225500D01*
X31600D01*
G01X20400Y200817D02*
X17900D01*
Y201858D01*
X18025Y202192D01*
X18192Y202400D01*
X18525Y202483D01*
X18858Y202400D01*
X19067Y202150D01*
X19192Y201858D01*
Y200817D01*
G01Y201858D02*
X20400Y202483D01*
G01X20025Y203833D02*
X20233Y204083D01*
X20358Y204375D01*
X20400Y204750D01*
X20317Y205125D01*
X20150Y205417D01*
X19858Y205625D01*
X19525Y205667D01*
X19192Y205583D01*
X18983Y205375D01*
X18817Y205083D01*
X18775Y204792D01*
X18817Y204500D01*
X18983Y204125D01*
X17900Y204250D01*
Y205375D01*
G01X20400Y208350D02*
X17900D01*
X19692Y206808D01*
Y208892D01*
G01X19900Y210033D02*
X20192Y210283D01*
X20358Y210617D01*
X20400Y210992D01*
X20358Y211325D01*
X20150Y211658D01*
X19900Y211867D01*
X19650Y211908D01*
X19358Y211825D01*
X19150Y211533D01*
X19067Y211242D01*
Y210867D01*
G01Y211242D02*
X18942Y211492D01*
X18733Y211700D01*
X18483Y211783D01*
X18233Y211700D01*
X18025Y211492D01*
X17900Y211117D01*
X17942Y210742D01*
X18108Y210367D01*
G01X31900Y209000D02*
X27900D01*
Y201600D01*
G01X70800Y181200D02*
X74800D01*
Y188600D01*
G01X23900Y201600D02*
X27900D01*
Y209000D01*
G01X63500Y229100D02*
X67500D01*
Y236500D01*
G01X43938Y230004D02*
X47938D01*
Y237404D01*
G01X39938Y230004D02*
X43938D01*
Y237404D01*
G01X72500Y236500D02*
X68500D01*
Y229100D01*
G01X24200Y225500D02*
Y221500D01*
X31600D01*
G01X54400Y236500D02*
X50400D01*
Y229100D01*
G01X26767Y199292D02*
X26517Y199417D01*
X26225Y199500D01*
X25892D01*
X25517Y199375D01*
X25225Y199167D01*
X25017Y198917D01*
X24850Y198500D01*
X24808Y198125D01*
X24892Y197750D01*
X25017Y197500D01*
X25267Y197250D01*
X25558Y197083D01*
X25850Y197000D01*
X26142D01*
X26433Y197083D01*
X26683Y197208D01*
X26892Y197375D01*
G01X28158Y198042D02*
X28450Y198333D01*
X28700Y198500D01*
X29033Y198583D01*
X29325Y198500D01*
X29533Y198333D01*
X29700Y198083D01*
X29742Y197792D01*
X29700Y197542D01*
X29533Y197292D01*
X29283Y197083D01*
X28992Y197000D01*
X28658Y197083D01*
X28367Y197333D01*
X28200Y197708D01*
X28158Y198125D01*
X28242Y198667D01*
X28367Y198958D01*
X28575Y199250D01*
X28867Y199458D01*
X29158Y199500D01*
X29450Y199417D01*
X29658Y199208D01*
G01X31133Y197375D02*
X31383Y197167D01*
X31675Y197042D01*
X32050Y197000D01*
X32425Y197083D01*
X32717Y197250D01*
X32925Y197542D01*
X32967Y197875D01*
X32883Y198208D01*
X32675Y198417D01*
X32383Y198583D01*
X32092Y198625D01*
X31800Y198583D01*
X31425Y198417D01*
X31550Y199500D01*
X32675D01*
G01X34233Y197375D02*
X34483Y197167D01*
X34775Y197042D01*
X35150Y197000D01*
X35525Y197083D01*
X35817Y197250D01*
X36025Y197542D01*
X36067Y197875D01*
X35983Y198208D01*
X35775Y198417D01*
X35483Y198583D01*
X35192Y198625D01*
X34900Y198583D01*
X34525Y198417D01*
X34650Y199500D01*
X35775D01*
G01X62100Y182400D02*
X66100D01*
Y189800D01*
G01X22905Y183934D02*
X20405D01*
Y184975D01*
X20530Y185309D01*
X20697Y185517D01*
X21030Y185600D01*
X21363Y185517D01*
X21572Y185267D01*
X21697Y184975D01*
Y183934D01*
G01Y184975D02*
X22905Y185600D01*
G01Y188367D02*
X20405D01*
X22197Y186825D01*
Y188909D01*
G01X22405Y190050D02*
X22697Y190300D01*
X22863Y190634D01*
X22905Y191009D01*
X22863Y191342D01*
X22655Y191675D01*
X22405Y191884D01*
X22155Y191925D01*
X21863Y191842D01*
X21655Y191550D01*
X21572Y191259D01*
Y190884D01*
G01Y191259D02*
X21447Y191509D01*
X21238Y191717D01*
X20988Y191800D01*
X20738Y191717D01*
X20530Y191509D01*
X20405Y191134D01*
X20447Y190759D01*
X20613Y190384D01*
G01X22530Y193150D02*
X22738Y193400D01*
X22863Y193692D01*
X22905Y194067D01*
X22822Y194442D01*
X22655Y194734D01*
X22363Y194942D01*
X22030Y194984D01*
X21697Y194900D01*
X21488Y194692D01*
X21322Y194400D01*
X21280Y194109D01*
X21322Y193817D01*
X21488Y193442D01*
X20405Y193567D01*
Y194692D01*
G01X34405Y189717D02*
X30405D01*
Y182317D01*
G01X26905Y183934D02*
X24405D01*
Y184975D01*
X24530Y185309D01*
X24697Y185517D01*
X25030Y185600D01*
X25363Y185517D01*
X25572Y185267D01*
X25697Y184975D01*
Y183934D01*
G01Y184975D02*
X26905Y185600D01*
G01Y188367D02*
X24405D01*
X26197Y186825D01*
Y188909D01*
G01X26405Y190050D02*
X26697Y190300D01*
X26863Y190634D01*
X26905Y191009D01*
X26863Y191342D01*
X26655Y191675D01*
X26405Y191884D01*
X26155Y191925D01*
X25863Y191842D01*
X25655Y191550D01*
X25572Y191259D01*
Y190884D01*
G01Y191259D02*
X25447Y191509D01*
X25238Y191717D01*
X24988Y191800D01*
X24738Y191717D01*
X24530Y191509D01*
X24405Y191134D01*
X24447Y190759D01*
X24613Y190384D01*
G01X25863Y193275D02*
X25572Y193567D01*
X25405Y193817D01*
X25322Y194150D01*
X25405Y194442D01*
X25572Y194650D01*
X25822Y194817D01*
X26113Y194859D01*
X26363Y194817D01*
X26613Y194650D01*
X26822Y194400D01*
X26905Y194109D01*
X26822Y193775D01*
X26572Y193484D01*
X26197Y193317D01*
X25780Y193275D01*
X25238Y193359D01*
X24947Y193484D01*
X24655Y193692D01*
X24447Y193984D01*
X24405Y194275D01*
X24488Y194567D01*
X24697Y194775D01*
G01X38405Y189717D02*
X34405D01*
Y182317D01*
G01X44500Y181500D02*
X48500D01*
Y188900D01*
G01Y181500D02*
X52500D01*
Y188900D01*
G01X38533Y227667D02*
Y225875D01*
X38700Y225500D01*
X39033Y225250D01*
X39450Y225167D01*
X39867Y225250D01*
X40200Y225500D01*
X40367Y225875D01*
Y227667D01*
G01X41633Y225542D02*
X41883Y225334D01*
X42175Y225209D01*
X42550Y225167D01*
X42925Y225250D01*
X43217Y225417D01*
X43425Y225709D01*
X43467Y226042D01*
X43383Y226375D01*
X43175Y226584D01*
X42883Y226750D01*
X42592Y226792D01*
X42300Y226750D01*
X41925Y226584D01*
X42050Y227667D01*
X43175D01*
G01X38950Y210687D02*
X41950D01*
G01X69850D02*
X67850D01*
G01X59820Y225650D02*
Y222650D01*
G01X57852Y193750D02*
Y196750D01*
G01X48012Y194750D02*
Y196750D01*
G01X49980Y224650D02*
Y222650D01*
G01X46050Y195850D02*
X41050D01*
Y200850D01*
G01X63750Y223550D02*
X68750D01*
Y218550D01*
G01X46050Y223550D02*
X41050D01*
Y218550D01*
G01X41900Y178300D02*
X41567Y178342D01*
X41275Y178508D01*
X41025Y178758D01*
X40858Y179050D01*
X40775Y179383D01*
Y179717D01*
X40858Y180050D01*
X41025Y180342D01*
X41275Y180592D01*
X41567Y180758D01*
X41900Y180800D01*
X42233Y180758D01*
X42525Y180592D01*
X42775Y180342D01*
X42942Y180050D01*
X43025Y179717D01*
Y179383D01*
X42942Y179050D01*
X42775Y178758D01*
X42525Y178508D01*
X42233Y178342D01*
X41900Y178300D01*
G01X42233Y178967D02*
X42733Y178300D01*
G01X44083Y178800D02*
X44333Y178508D01*
X44667Y178342D01*
X45042Y178300D01*
X45375Y178342D01*
X45708Y178550D01*
X45917Y178800D01*
X45958Y179050D01*
X45875Y179342D01*
X45583Y179550D01*
X45292Y179633D01*
X44917D01*
G01X45292D02*
X45542Y179758D01*
X45750Y179967D01*
X45833Y180217D01*
X45750Y180467D01*
X45542Y180675D01*
X45167Y180800D01*
X44792Y180758D01*
X44417Y180592D01*
G01X48017Y178300D02*
X48100Y178842D01*
X48225Y179300D01*
X48392Y179717D01*
X48600Y180175D01*
X48933Y180800D01*
X47267D01*
G01X49987Y177531D02*
X36987D01*
G01X52461Y239700D02*
X49961D01*
Y240741D01*
X50086Y241075D01*
X50253Y241283D01*
X50586Y241366D01*
X50919Y241283D01*
X51128Y241033D01*
X51253Y240741D01*
Y239700D01*
G01Y240741D02*
X52461Y241366D01*
G01X51419Y242841D02*
X51128Y243133D01*
X50961Y243383D01*
X50878Y243716D01*
X50961Y244008D01*
X51128Y244216D01*
X51378Y244383D01*
X51669Y244425D01*
X51919Y244383D01*
X52169Y244216D01*
X52378Y243966D01*
X52461Y243675D01*
X52378Y243341D01*
X52128Y243050D01*
X51753Y242883D01*
X51336Y242841D01*
X50794Y242925D01*
X50503Y243050D01*
X50211Y243258D01*
X50003Y243550D01*
X49961Y243841D01*
X50044Y244133D01*
X50253Y244341D01*
G01X52169Y246025D02*
X52378Y246316D01*
X52461Y246650D01*
X52378Y246983D01*
X52128Y247275D01*
X51753Y247483D01*
X51378Y247566D01*
X50919D01*
X50544Y247483D01*
X50211Y247275D01*
X50044Y247025D01*
X49961Y246733D01*
X50044Y246400D01*
X50211Y246150D01*
X50461Y245983D01*
X50794Y245900D01*
X51086Y245983D01*
X51378Y246191D01*
X51544Y246441D01*
X51586Y246733D01*
X51503Y247066D01*
X51294Y247316D01*
X50919Y247566D01*
G01X50378Y249041D02*
X50128Y249291D01*
X50003Y249583D01*
X49961Y249916D01*
X50044Y250333D01*
X50253Y250625D01*
X50503Y250708D01*
X50753Y250666D01*
X50961Y250500D01*
X51378Y249666D01*
X51669Y249291D01*
X52086Y249041D01*
X52461Y248958D01*
Y250708D01*
G01X19400Y299017D02*
X16900D01*
Y300058D01*
X17025Y300392D01*
X17192Y300600D01*
X17525Y300683D01*
X17858Y300600D01*
X18067Y300350D01*
X18192Y300058D01*
Y299017D01*
G01Y300058D02*
X19400Y300683D01*
G01X18900Y302033D02*
X19192Y302283D01*
X19358Y302617D01*
X19400Y302992D01*
X19358Y303325D01*
X19150Y303658D01*
X18900Y303867D01*
X18650Y303908D01*
X18358Y303825D01*
X18150Y303533D01*
X18067Y303242D01*
Y302867D01*
G01Y303242D02*
X17942Y303492D01*
X17733Y303700D01*
X17483Y303783D01*
X17233Y303700D01*
X17025Y303492D01*
X16900Y303117D01*
X16942Y302742D01*
X17108Y302367D01*
G01X19400Y306550D02*
X16900D01*
X18692Y305008D01*
Y307092D01*
G01X18358Y308358D02*
X18067Y308650D01*
X17900Y308900D01*
X17817Y309233D01*
X17900Y309525D01*
X18067Y309733D01*
X18317Y309900D01*
X18608Y309942D01*
X18858Y309900D01*
X19108Y309733D01*
X19317Y309483D01*
X19400Y309192D01*
X19317Y308858D01*
X19067Y308567D01*
X18692Y308400D01*
X18275Y308358D01*
X17733Y308442D01*
X17442Y308567D01*
X17150Y308775D01*
X16942Y309067D01*
X16900Y309358D01*
X16983Y309650D01*
X17192Y309858D01*
G01X72096Y283695D02*
Y279695D01*
X79496D01*
G01X72096Y278695D02*
Y274695D01*
X79496D01*
G01X72096Y288695D02*
Y284695D01*
X79496D01*
G01X25000Y285200D02*
Y281200D01*
X32400D01*
G01X25000Y298700D02*
Y294700D01*
X32400D01*
G01Y290200D02*
Y294200D01*
X25000D01*
G01X24600Y273500D02*
X28600D01*
Y280900D01*
G01X18200Y269217D02*
X15700D01*
Y270258D01*
X15825Y270592D01*
X15992Y270800D01*
X16325Y270883D01*
X16658Y270800D01*
X16867Y270550D01*
X16992Y270258D01*
Y269217D01*
G01Y270258D02*
X18200Y270883D01*
G01X17700Y272233D02*
X17992Y272483D01*
X18158Y272817D01*
X18200Y273192D01*
X18158Y273525D01*
X17950Y273858D01*
X17700Y274067D01*
X17450Y274108D01*
X17158Y274025D01*
X16950Y273733D01*
X16867Y273442D01*
Y273067D01*
G01Y273442D02*
X16742Y273692D01*
X16533Y273900D01*
X16283Y273983D01*
X16033Y273900D01*
X15825Y273692D01*
X15700Y273317D01*
X15742Y272942D01*
X15908Y272567D01*
G01X17158Y275458D02*
X16867Y275750D01*
X16700Y276000D01*
X16617Y276333D01*
X16700Y276625D01*
X16867Y276833D01*
X17117Y277000D01*
X17408Y277042D01*
X17658Y277000D01*
X17908Y276833D01*
X18117Y276583D01*
X18200Y276292D01*
X18117Y275958D01*
X17867Y275667D01*
X17492Y275500D01*
X17075Y275458D01*
X16533Y275542D01*
X16242Y275667D01*
X15950Y275875D01*
X15742Y276167D01*
X15700Y276458D01*
X15783Y276750D01*
X15992Y276958D01*
G01X16117Y278558D02*
X15867Y278808D01*
X15742Y279100D01*
X15700Y279433D01*
X15783Y279850D01*
X15992Y280142D01*
X16242Y280225D01*
X16492Y280183D01*
X16700Y280017D01*
X17117Y279183D01*
X17408Y278808D01*
X17825Y278558D01*
X18200Y278475D01*
Y280225D01*
G01X32700Y280900D02*
X28700D01*
Y273500D01*
G01X32400Y285700D02*
Y289700D01*
X25000D01*
G01X71334Y240017D02*
X68834D01*
Y241058D01*
X68959Y241392D01*
X69126Y241600D01*
X69459Y241683D01*
X69792Y241600D01*
X70001Y241350D01*
X70126Y241058D01*
Y240017D01*
G01Y241058D02*
X71334Y241683D01*
G01X70959Y243033D02*
X71167Y243283D01*
X71292Y243575D01*
X71334Y243950D01*
X71251Y244325D01*
X71084Y244617D01*
X70792Y244825D01*
X70459Y244867D01*
X70126Y244783D01*
X69917Y244575D01*
X69751Y244283D01*
X69709Y243992D01*
X69751Y243700D01*
X69917Y243325D01*
X68834Y243450D01*
Y244575D01*
G01X69251Y246258D02*
X69001Y246508D01*
X68876Y246800D01*
X68834Y247133D01*
X68917Y247550D01*
X69126Y247842D01*
X69376Y247925D01*
X69626Y247883D01*
X69834Y247717D01*
X70251Y246883D01*
X70542Y246508D01*
X70959Y246258D01*
X71334Y246175D01*
Y247925D01*
G01Y250650D02*
X68834D01*
X70626Y249108D01*
Y251192D01*
G01X44538Y241271D02*
X42038D01*
Y242312D01*
X42163Y242646D01*
X42330Y242854D01*
X42663Y242937D01*
X42996Y242854D01*
X43205Y242604D01*
X43330Y242312D01*
Y241271D01*
G01Y242312D02*
X44538Y242937D01*
G01Y245204D02*
X42038D01*
X42538Y244704D01*
G01X44538D02*
Y245704D01*
G01X44038Y247387D02*
X44330Y247637D01*
X44496Y247971D01*
X44538Y248346D01*
X44496Y248679D01*
X44288Y249012D01*
X44038Y249221D01*
X43788Y249262D01*
X43496Y249179D01*
X43288Y248887D01*
X43205Y248596D01*
Y248221D01*
G01Y248596D02*
X43080Y248846D01*
X42871Y249054D01*
X42621Y249137D01*
X42371Y249054D01*
X42163Y248846D01*
X42038Y248471D01*
X42080Y248096D01*
X42246Y247721D01*
G01X40538Y241271D02*
X38038D01*
Y242312D01*
X38163Y242646D01*
X38330Y242854D01*
X38663Y242937D01*
X38996Y242854D01*
X39205Y242604D01*
X39330Y242312D01*
Y241271D01*
G01Y242312D02*
X40538Y242937D01*
G01Y245204D02*
X38038D01*
X38538Y244704D01*
G01X40538D02*
Y245704D01*
G01X38455Y247512D02*
X38205Y247762D01*
X38080Y248054D01*
X38038Y248387D01*
X38121Y248804D01*
X38330Y249096D01*
X38580Y249179D01*
X38830Y249137D01*
X39038Y248971D01*
X39455Y248137D01*
X39746Y247762D01*
X40163Y247512D01*
X40538Y247429D01*
Y249179D01*
G01X63517Y254667D02*
Y257167D01*
X64558D01*
X64892Y257042D01*
X65100Y256875D01*
X65183Y256542D01*
X65100Y256209D01*
X64850Y256000D01*
X64558Y255875D01*
X63517D01*
G01X64558D02*
X65183Y254667D01*
G01X66658Y255709D02*
X66950Y256000D01*
X67200Y256167D01*
X67533Y256250D01*
X67825Y256167D01*
X68033Y256000D01*
X68200Y255750D01*
X68242Y255459D01*
X68200Y255209D01*
X68033Y254959D01*
X67783Y254750D01*
X67492Y254667D01*
X67158Y254750D01*
X66867Y255000D01*
X66700Y255375D01*
X66658Y255792D01*
X66742Y256334D01*
X66867Y256625D01*
X67075Y256917D01*
X67367Y257125D01*
X67658Y257167D01*
X67950Y257084D01*
X68158Y256875D01*
G01X69842Y254959D02*
X70133Y254750D01*
X70467Y254667D01*
X70800Y254750D01*
X71092Y255000D01*
X71300Y255375D01*
X71383Y255750D01*
Y256209D01*
X71300Y256584D01*
X71092Y256917D01*
X70842Y257084D01*
X70550Y257167D01*
X70217Y257084D01*
X69967Y256917D01*
X69800Y256667D01*
X69717Y256334D01*
X69800Y256042D01*
X70008Y255750D01*
X70258Y255584D01*
X70550Y255542D01*
X70883Y255625D01*
X71133Y255834D01*
X71383Y256209D01*
G01X73650Y254667D02*
Y257167D01*
X73150Y256667D01*
G01Y254667D02*
X74150D01*
G01X67267Y240333D02*
Y244333D01*
X59867D01*
G01X75334Y240017D02*
X72834D01*
Y241058D01*
X72959Y241392D01*
X73126Y241600D01*
X73459Y241683D01*
X73792Y241600D01*
X74001Y241350D01*
X74126Y241058D01*
Y240017D01*
G01Y241058D02*
X75334Y241683D01*
G01X74959Y243033D02*
X75167Y243283D01*
X75292Y243575D01*
X75334Y243950D01*
X75251Y244325D01*
X75084Y244617D01*
X74792Y244825D01*
X74459Y244867D01*
X74126Y244783D01*
X73917Y244575D01*
X73751Y244283D01*
X73709Y243992D01*
X73751Y243700D01*
X73917Y243325D01*
X72834Y243450D01*
Y244575D01*
G01X75334Y246967D02*
X74792Y247050D01*
X74334Y247175D01*
X73917Y247342D01*
X73459Y247550D01*
X72834Y247883D01*
Y246217D01*
G01X75042Y249442D02*
X75251Y249733D01*
X75334Y250067D01*
X75251Y250400D01*
X75001Y250692D01*
X74626Y250900D01*
X74251Y250983D01*
X73792D01*
X73417Y250900D01*
X73084Y250692D01*
X72917Y250442D01*
X72834Y250150D01*
X72917Y249817D01*
X73084Y249567D01*
X73334Y249400D01*
X73667Y249317D01*
X73959Y249400D01*
X74251Y249608D01*
X74417Y249858D01*
X74459Y250150D01*
X74376Y250483D01*
X74167Y250733D01*
X73792Y250983D01*
G01X49020Y260937D02*
Y263437D01*
X50061D01*
X50395Y263312D01*
X50603Y263145D01*
X50686Y262812D01*
X50603Y262479D01*
X50353Y262270D01*
X50061Y262145D01*
X49020D01*
G01X50061D02*
X50686Y260937D01*
G01X52161Y261979D02*
X52453Y262270D01*
X52703Y262437D01*
X53036Y262520D01*
X53328Y262437D01*
X53536Y262270D01*
X53703Y262020D01*
X53745Y261729D01*
X53703Y261479D01*
X53536Y261229D01*
X53286Y261020D01*
X52995Y260937D01*
X52661Y261020D01*
X52370Y261270D01*
X52203Y261645D01*
X52161Y262062D01*
X52245Y262604D01*
X52370Y262895D01*
X52578Y263187D01*
X52870Y263395D01*
X53161Y263437D01*
X53453Y263354D01*
X53661Y263145D01*
G01X56053Y263437D02*
X55720Y263354D01*
X55470Y263145D01*
X55303Y262895D01*
X55178Y262562D01*
X55136Y262187D01*
X55178Y261812D01*
X55303Y261479D01*
X55470Y261229D01*
X55720Y261020D01*
X56053Y260937D01*
X56386Y261020D01*
X56636Y261229D01*
X56803Y261479D01*
X56928Y261812D01*
X56970Y262187D01*
X56928Y262562D01*
X56803Y262895D01*
X56636Y263145D01*
X56386Y263354D01*
X56053Y263437D01*
G01X59153Y260937D02*
X59445Y260979D01*
X59778Y261104D01*
X59986Y261312D01*
X60070Y261604D01*
X59986Y261895D01*
X59736Y262145D01*
X59361Y262270D01*
X58945D01*
X58695Y262354D01*
X58486Y262562D01*
X58403Y262854D01*
X58528Y263145D01*
X58820Y263354D01*
X59153Y263437D01*
X59486Y263354D01*
X59778Y263145D01*
X59903Y262854D01*
X59820Y262562D01*
X59611Y262354D01*
X59361Y262270D01*
X58945D01*
X58570Y262145D01*
X58320Y261895D01*
X58236Y261604D01*
X58320Y261312D01*
X58528Y261104D01*
X58861Y260979D01*
X59153Y260937D01*
G01X39500Y263900D02*
Y259900D01*
X46900D01*
G01X49020Y264937D02*
Y267437D01*
X50061D01*
X50395Y267312D01*
X50603Y267145D01*
X50686Y266812D01*
X50603Y266479D01*
X50353Y266270D01*
X50061Y266145D01*
X49020D01*
G01X50061D02*
X50686Y264937D01*
G01X52161Y265979D02*
X52453Y266270D01*
X52703Y266437D01*
X53036Y266520D01*
X53328Y266437D01*
X53536Y266270D01*
X53703Y266020D01*
X53745Y265729D01*
X53703Y265479D01*
X53536Y265229D01*
X53286Y265020D01*
X52995Y264937D01*
X52661Y265020D01*
X52370Y265270D01*
X52203Y265645D01*
X52161Y266062D01*
X52245Y266604D01*
X52370Y266895D01*
X52578Y267187D01*
X52870Y267395D01*
X53161Y267437D01*
X53453Y267354D01*
X53661Y267145D01*
G01X56053Y267437D02*
X55720Y267354D01*
X55470Y267145D01*
X55303Y266895D01*
X55178Y266562D01*
X55136Y266187D01*
X55178Y265812D01*
X55303Y265479D01*
X55470Y265229D01*
X55720Y265020D01*
X56053Y264937D01*
X56386Y265020D01*
X56636Y265229D01*
X56803Y265479D01*
X56928Y265812D01*
X56970Y266187D01*
X56928Y266562D01*
X56803Y266895D01*
X56636Y267145D01*
X56386Y267354D01*
X56053Y267437D01*
G01X58445Y265229D02*
X58736Y265020D01*
X59070Y264937D01*
X59403Y265020D01*
X59695Y265270D01*
X59903Y265645D01*
X59986Y266020D01*
Y266479D01*
X59903Y266854D01*
X59695Y267187D01*
X59445Y267354D01*
X59153Y267437D01*
X58820Y267354D01*
X58570Y267187D01*
X58403Y266937D01*
X58320Y266604D01*
X58403Y266312D01*
X58611Y266020D01*
X58861Y265854D01*
X59153Y265812D01*
X59486Y265895D01*
X59736Y266104D01*
X59986Y266479D01*
G01X46900Y264100D02*
Y268100D01*
X39500D01*
G01X48461Y239700D02*
X45961D01*
Y240741D01*
X46086Y241075D01*
X46253Y241283D01*
X46586Y241366D01*
X46919Y241283D01*
X47128Y241033D01*
X47253Y240741D01*
Y239700D01*
G01Y240741D02*
X48461Y241366D01*
G01X47419Y242841D02*
X47128Y243133D01*
X46961Y243383D01*
X46878Y243716D01*
X46961Y244008D01*
X47128Y244216D01*
X47378Y244383D01*
X47669Y244425D01*
X47919Y244383D01*
X48169Y244216D01*
X48378Y243966D01*
X48461Y243675D01*
X48378Y243341D01*
X48128Y243050D01*
X47753Y242883D01*
X47336Y242841D01*
X46794Y242925D01*
X46503Y243050D01*
X46211Y243258D01*
X46003Y243550D01*
X45961Y243841D01*
X46044Y244133D01*
X46253Y244341D01*
G01X48169Y246025D02*
X48378Y246316D01*
X48461Y246650D01*
X48378Y246983D01*
X48128Y247275D01*
X47753Y247483D01*
X47378Y247566D01*
X46919D01*
X46544Y247483D01*
X46211Y247275D01*
X46044Y247025D01*
X45961Y246733D01*
X46044Y246400D01*
X46211Y246150D01*
X46461Y245983D01*
X46794Y245900D01*
X47086Y245983D01*
X47378Y246191D01*
X47544Y246441D01*
X47586Y246733D01*
X47503Y247066D01*
X47294Y247316D01*
X46919Y247566D01*
G01X47961Y248916D02*
X48253Y249166D01*
X48419Y249500D01*
X48461Y249875D01*
X48419Y250208D01*
X48211Y250541D01*
X47961Y250750D01*
X47711Y250791D01*
X47419Y250708D01*
X47211Y250416D01*
X47128Y250125D01*
Y249750D01*
G01Y250125D02*
X47003Y250375D01*
X46794Y250583D01*
X46544Y250666D01*
X46294Y250583D01*
X46086Y250375D01*
X45961Y250000D01*
X46003Y249625D01*
X46169Y249250D01*
G01X22702Y262828D02*
X22660Y262495D01*
X22494Y262203D01*
X22244Y261953D01*
X21952Y261786D01*
X21619Y261703D01*
X21285D01*
X20952Y261786D01*
X20660Y261953D01*
X20410Y262203D01*
X20244Y262495D01*
X20202Y262828D01*
X20244Y263161D01*
X20410Y263453D01*
X20660Y263703D01*
X20952Y263870D01*
X21285Y263953D01*
X21619D01*
X21952Y263870D01*
X22244Y263703D01*
X22494Y263453D01*
X22660Y263161D01*
X22702Y262828D01*
G01X22035Y263161D02*
X22702Y263661D01*
G01Y265928D02*
X20202D01*
X20702Y265428D01*
G01X22702D02*
Y266428D01*
G01Y269528D02*
X20202D01*
X21994Y267986D01*
Y270070D01*
G01X24900Y259300D02*
X38900D01*
G01X24900Y272300D02*
Y259300D01*
G01X38900Y272300D02*
X24900D01*
G01X38900Y259300D02*
Y272300D01*
G01X38983Y300000D02*
Y298208D01*
X39150Y297833D01*
X39483Y297583D01*
X39900Y297500D01*
X40317Y297583D01*
X40650Y297833D01*
X40817Y298208D01*
Y300000D01*
G01X42208Y299583D02*
X42458Y299833D01*
X42750Y299958D01*
X43083Y300000D01*
X43500Y299917D01*
X43792Y299708D01*
X43875Y299458D01*
X43833Y299208D01*
X43667Y299000D01*
X42833Y298583D01*
X42458Y298292D01*
X42208Y297875D01*
X42125Y297500D01*
X43875D01*
G01X45392Y297792D02*
X45683Y297583D01*
X46017Y297500D01*
X46350Y297583D01*
X46642Y297833D01*
X46850Y298208D01*
X46933Y298583D01*
Y299042D01*
X46850Y299417D01*
X46642Y299750D01*
X46392Y299917D01*
X46100Y300000D01*
X45767Y299917D01*
X45517Y299750D01*
X45350Y299500D01*
X45267Y299167D01*
X45350Y298875D01*
X45558Y298583D01*
X45808Y298417D01*
X46100Y298375D01*
X46433Y298458D01*
X46683Y298667D01*
X46933Y299042D01*
G01X54500Y295400D02*
X52700Y293300D01*
X50500Y295400D01*
G01X46900Y295500D02*
Y276300D01*
X58100D01*
Y295500D01*
X46900D01*
Y295100D01*
G01X65267Y260959D02*
X65017Y261084D01*
X64725Y261167D01*
X64392D01*
X64017Y261042D01*
X63725Y260834D01*
X63517Y260584D01*
X63350Y260167D01*
X63308Y259792D01*
X63392Y259417D01*
X63517Y259167D01*
X63767Y258917D01*
X64058Y258750D01*
X64350Y258667D01*
X64642D01*
X64933Y258750D01*
X65183Y258875D01*
X65392Y259042D01*
G01X67450Y258667D02*
Y261167D01*
X66950Y260667D01*
G01Y258667D02*
X67950D01*
G01X70550D02*
Y261167D01*
X70050Y260667D01*
G01Y258667D02*
X71050D01*
G01X72733Y259042D02*
X72983Y258834D01*
X73275Y258709D01*
X73650Y258667D01*
X74025Y258750D01*
X74317Y258917D01*
X74525Y259209D01*
X74567Y259542D01*
X74483Y259875D01*
X74275Y260084D01*
X73983Y260250D01*
X73692Y260292D01*
X73400Y260250D01*
X73025Y260084D01*
X73150Y261167D01*
X74275D01*
G01X25300Y325000D02*
Y321000D01*
X32700D01*
G01X25300Y311500D02*
Y307500D01*
X32700D01*
G01X25200Y299800D02*
X29200D01*
Y307200D01*
G01X71800Y316000D02*
Y312000D01*
X79200D01*
G01X32700Y316500D02*
Y320500D01*
X25300D01*
G01X32700Y312000D02*
Y316000D01*
X25300D01*
G01X33400Y307200D02*
X29400D01*
Y299800D01*
G01X72000Y311500D02*
Y307500D01*
X79400D01*
G01X72000Y306500D02*
Y302500D01*
X79400D01*
G01X65041Y337267D02*
X64916Y337017D01*
X64833Y336725D01*
Y336392D01*
X64958Y336017D01*
X65166Y335725D01*
X65416Y335517D01*
X65833Y335350D01*
X66208Y335308D01*
X66583Y335392D01*
X66833Y335517D01*
X67083Y335767D01*
X67250Y336058D01*
X67333Y336350D01*
Y336642D01*
X67250Y336933D01*
X67125Y337183D01*
X66958Y337392D01*
G01Y338533D02*
X67166Y338783D01*
X67291Y339075D01*
X67333Y339450D01*
X67250Y339825D01*
X67083Y340117D01*
X66791Y340325D01*
X66458Y340367D01*
X66125Y340283D01*
X65916Y340075D01*
X65750Y339783D01*
X65708Y339492D01*
X65750Y339200D01*
X65916Y338825D01*
X64833Y338950D01*
Y340075D01*
G01X67333Y343050D02*
X64833D01*
X66625Y341508D01*
Y343592D01*
G01X67333Y345650D02*
X64833D01*
X65333Y345150D01*
G01X67333D02*
Y346150D01*
G01X43541Y337267D02*
X43416Y337017D01*
X43333Y336725D01*
Y336392D01*
X43458Y336017D01*
X43666Y335725D01*
X43916Y335517D01*
X44333Y335350D01*
X44708Y335308D01*
X45083Y335392D01*
X45333Y335517D01*
X45583Y335767D01*
X45750Y336058D01*
X45833Y336350D01*
Y336642D01*
X45750Y336933D01*
X45625Y337183D01*
X45458Y337392D01*
G01Y338533D02*
X45666Y338783D01*
X45791Y339075D01*
X45833Y339450D01*
X45750Y339825D01*
X45583Y340117D01*
X45291Y340325D01*
X44958Y340367D01*
X44625Y340283D01*
X44416Y340075D01*
X44250Y339783D01*
X44208Y339492D01*
X44250Y339200D01*
X44416Y338825D01*
X43333Y338950D01*
Y340075D01*
G01X45458Y341633D02*
X45666Y341883D01*
X45791Y342175D01*
X45833Y342550D01*
X45750Y342925D01*
X45583Y343217D01*
X45291Y343425D01*
X44958Y343467D01*
X44625Y343383D01*
X44416Y343175D01*
X44250Y342883D01*
X44208Y342592D01*
X44250Y342300D01*
X44416Y341925D01*
X43333Y342050D01*
Y343175D01*
G01X45833Y345650D02*
X45791Y345942D01*
X45666Y346275D01*
X45458Y346483D01*
X45166Y346567D01*
X44875Y346483D01*
X44625Y346233D01*
X44500Y345858D01*
Y345442D01*
X44416Y345192D01*
X44208Y344983D01*
X43916Y344900D01*
X43625Y345025D01*
X43416Y345317D01*
X43333Y345650D01*
X43416Y345983D01*
X43625Y346275D01*
X43916Y346400D01*
X44208Y346317D01*
X44416Y346108D01*
X44500Y345858D01*
Y345442D01*
X44625Y345067D01*
X44875Y344817D01*
X45166Y344733D01*
X45458Y344817D01*
X45666Y345025D01*
X45791Y345358D01*
X45833Y345650D01*
G01X38483Y328500D02*
Y326708D01*
X38650Y326333D01*
X38983Y326083D01*
X39400Y326000D01*
X39817Y326083D01*
X40150Y326333D01*
X40317Y326708D01*
Y328500D01*
G01X41708Y328083D02*
X41958Y328333D01*
X42250Y328458D01*
X42583Y328500D01*
X43000Y328417D01*
X43292Y328208D01*
X43375Y327958D01*
X43333Y327708D01*
X43167Y327500D01*
X42333Y327083D01*
X41958Y326792D01*
X41708Y326375D01*
X41625Y326000D01*
X43375D01*
G01X45517D02*
X45600Y326542D01*
X45725Y327000D01*
X45892Y327417D01*
X46100Y327875D01*
X46433Y328500D01*
X44767D01*
G01X54404Y323122D02*
X52604Y321022D01*
X50404Y323122D01*
G01X46804Y323222D02*
Y304022D01*
X58004D01*
Y323222D01*
X46804D01*
Y322822D01*
G01X64505Y349790D02*
X66297D01*
X66672Y349957D01*
X66922Y350290D01*
X67005Y350707D01*
X66922Y351124D01*
X66672Y351457D01*
X66297Y351624D01*
X64505D01*
G01X66505Y352890D02*
X66797Y353140D01*
X66963Y353474D01*
X67005Y353849D01*
X66963Y354182D01*
X66755Y354515D01*
X66505Y354724D01*
X66255Y354765D01*
X65963Y354682D01*
X65755Y354390D01*
X65672Y354099D01*
Y353724D01*
G01Y354099D02*
X65547Y354349D01*
X65338Y354557D01*
X65088Y354640D01*
X64838Y354557D01*
X64630Y354349D01*
X64505Y353974D01*
X64547Y353599D01*
X64713Y353224D01*
G01X66630Y355990D02*
X66838Y356240D01*
X66963Y356532D01*
X67005Y356907D01*
X66922Y357282D01*
X66755Y357574D01*
X66463Y357782D01*
X66130Y357824D01*
X65797Y357740D01*
X65588Y357532D01*
X65422Y357240D01*
X65380Y356949D01*
X65422Y356657D01*
X65588Y356282D01*
X64505Y356407D01*
Y357532D01*
G01X79205Y348507D02*
X69005D01*
G01X68305Y353107D02*
X79205D01*
G01X68305D02*
Y341807D01*
G01X69505Y350807D02*
X68305Y352007D01*
G01X69505Y350807D02*
X68305Y349607D01*
G01X21834Y345983D02*
X23626D01*
X24001Y346150D01*
X24251Y346483D01*
X24334Y346900D01*
X24251Y347317D01*
X24001Y347650D01*
X23626Y347817D01*
X21834D01*
G01X23834Y349083D02*
X24126Y349333D01*
X24292Y349667D01*
X24334Y350042D01*
X24292Y350375D01*
X24084Y350708D01*
X23834Y350917D01*
X23584Y350958D01*
X23292Y350875D01*
X23084Y350583D01*
X23001Y350292D01*
Y349917D01*
G01Y350292D02*
X22876Y350542D01*
X22667Y350750D01*
X22417Y350833D01*
X22167Y350750D01*
X21959Y350542D01*
X21834Y350167D01*
X21876Y349792D01*
X22042Y349417D01*
G01X23292Y352308D02*
X23001Y352600D01*
X22834Y352850D01*
X22751Y353183D01*
X22834Y353475D01*
X23001Y353683D01*
X23251Y353850D01*
X23542Y353892D01*
X23792Y353850D01*
X24042Y353683D01*
X24251Y353433D01*
X24334Y353142D01*
X24251Y352808D01*
X24001Y352517D01*
X23626Y352350D01*
X23209Y352308D01*
X22667Y352392D01*
X22376Y352517D01*
X22084Y352725D01*
X21876Y353017D01*
X21834Y353308D01*
X21917Y353600D01*
X22126Y353808D01*
G01X36505Y348307D02*
X26305D01*
G01X36505Y352907D02*
Y348307D01*
G01X25605Y352907D02*
X36505D01*
G01X25605D02*
Y341607D01*
G01X26805Y350607D02*
X25605Y351807D01*
G01X26805Y350607D02*
X25605Y349407D01*
G01X42805Y349390D02*
X44597D01*
X44972Y349557D01*
X45222Y349890D01*
X45305Y350307D01*
X45222Y350724D01*
X44972Y351057D01*
X44597Y351224D01*
X42805D01*
G01X45305Y353907D02*
X42805D01*
X44597Y352365D01*
Y354449D01*
G01X42805Y356507D02*
X42888Y356174D01*
X43097Y355924D01*
X43347Y355757D01*
X43680Y355632D01*
X44055Y355590D01*
X44430Y355632D01*
X44763Y355757D01*
X45013Y355924D01*
X45222Y356174D01*
X45305Y356507D01*
X45222Y356840D01*
X45013Y357090D01*
X44763Y357257D01*
X44430Y357382D01*
X44055Y357424D01*
X43680Y357382D01*
X43347Y357257D01*
X43097Y357090D01*
X42888Y356840D01*
X42805Y356507D01*
G01X57505Y348107D02*
X47305D01*
G01X57505Y352707D02*
Y348107D01*
G01X46605Y352707D02*
X57505D01*
G01X46605D02*
Y341407D01*
G01X47805Y350407D02*
X46605Y351607D01*
G01X47805Y350407D02*
X46605Y349207D01*
G01X69433Y405167D02*
Y403375D01*
X69600Y403000D01*
X69933Y402750D01*
X70350Y402667D01*
X70767Y402750D01*
X71100Y403000D01*
X71267Y403375D01*
Y405167D01*
G01X73450Y402667D02*
Y405167D01*
X72950Y404667D01*
G01Y402667D02*
X73950D01*
G01X76550D02*
Y405167D01*
X76050Y404667D01*
G01Y402667D02*
X77050D01*
G01X78942Y402959D02*
X79233Y402750D01*
X79567Y402667D01*
X79900Y402750D01*
X80192Y403000D01*
X80400Y403375D01*
X80483Y403750D01*
Y404209D01*
X80400Y404584D01*
X80192Y404917D01*
X79942Y405084D01*
X79650Y405167D01*
X79317Y405084D01*
X79067Y404917D01*
X78900Y404667D01*
X78817Y404334D01*
X78900Y404042D01*
X79108Y403750D01*
X79358Y403584D01*
X79650Y403542D01*
X79983Y403625D01*
X80233Y403834D01*
X80483Y404209D01*
G01X67307Y400395D02*
X80707D01*
G01X67307Y390395D02*
Y400395D01*
G01X80707Y390395D02*
X67307D01*
G01X34433Y406167D02*
Y404375D01*
X34600Y404000D01*
X34933Y403750D01*
X35350Y403667D01*
X35767Y403750D01*
X36100Y404000D01*
X36267Y404375D01*
Y406167D01*
G01X38450Y403667D02*
Y406167D01*
X37950Y405667D01*
G01Y403667D02*
X38950D01*
G01X40758Y405750D02*
X41008Y406000D01*
X41300Y406125D01*
X41633Y406167D01*
X42050Y406084D01*
X42342Y405875D01*
X42425Y405625D01*
X42383Y405375D01*
X42217Y405167D01*
X41383Y404750D01*
X41008Y404459D01*
X40758Y404042D01*
X40675Y403667D01*
X42425D01*
G01X44650Y406167D02*
X44317Y406084D01*
X44067Y405875D01*
X43900Y405625D01*
X43775Y405292D01*
X43733Y404917D01*
X43775Y404542D01*
X43900Y404209D01*
X44067Y403959D01*
X44317Y403750D01*
X44650Y403667D01*
X44983Y403750D01*
X45233Y403959D01*
X45400Y404209D01*
X45525Y404542D01*
X45567Y404917D01*
X45525Y405292D01*
X45400Y405625D01*
X45233Y405875D01*
X44983Y406084D01*
X44650Y406167D01*
G01X46800Y391000D02*
X33400D01*
G01X46800Y401000D02*
Y391000D01*
G01X33400Y401000D02*
X46800D01*
G01X33400Y391000D02*
Y401000D01*
G01X21500Y385017D02*
X19000D01*
Y386058D01*
X19125Y386392D01*
X19292Y386600D01*
X19625Y386683D01*
X19958Y386600D01*
X20167Y386350D01*
X20292Y386058D01*
Y385017D01*
G01Y386058D02*
X21500Y386683D01*
G01X21125Y388033D02*
X21333Y388283D01*
X21458Y388575D01*
X21500Y388950D01*
X21417Y389325D01*
X21250Y389617D01*
X20958Y389825D01*
X20625Y389867D01*
X20292Y389783D01*
X20083Y389575D01*
X19917Y389283D01*
X19875Y388992D01*
X19917Y388700D01*
X20083Y388325D01*
X19000Y388450D01*
Y389575D01*
G01X21500Y391967D02*
X20958Y392050D01*
X20500Y392175D01*
X20083Y392342D01*
X19625Y392550D01*
X19000Y392883D01*
Y391217D01*
G01X19417Y394358D02*
X19167Y394608D01*
X19042Y394900D01*
X19000Y395233D01*
X19083Y395650D01*
X19292Y395942D01*
X19542Y396025D01*
X19792Y395983D01*
X20000Y395817D01*
X20417Y394983D01*
X20708Y394608D01*
X21125Y394358D01*
X21500Y394275D01*
Y396025D01*
G01X27700Y393900D02*
X23700D01*
Y386500D01*
G01X63500Y370100D02*
X67500D01*
Y377500D01*
G01X20000Y369652D02*
X24000D01*
Y377052D01*
G01X41000Y369533D02*
X45000D01*
Y376933D01*
G01X71100Y370100D02*
X75100D01*
Y377500D01*
G01X79200Y372500D02*
X75200D01*
Y365100D01*
G01X63350Y369751D02*
Y365751D01*
X70750D01*
G01X18400Y370369D02*
X15900D01*
Y371410D01*
X16025Y371744D01*
X16192Y371952D01*
X16525Y372035D01*
X16858Y371952D01*
X17067Y371702D01*
X17192Y371410D01*
Y370369D01*
G01Y371410D02*
X18400Y372035D01*
G01Y374802D02*
X15900D01*
X17692Y373260D01*
Y375344D01*
G01X18400Y377402D02*
X15900D01*
X16400Y376902D01*
G01X18400D02*
Y377902D01*
G01X16317Y379710D02*
X16067Y379960D01*
X15942Y380252D01*
X15900Y380585D01*
X15983Y381002D01*
X16192Y381294D01*
X16442Y381377D01*
X16692Y381335D01*
X16900Y381169D01*
X17317Y380335D01*
X17608Y379960D01*
X18025Y379710D01*
X18400Y379627D01*
Y381377D01*
G01X27900Y369652D02*
X31900D01*
Y377052D01*
G01X40200Y372300D02*
X36200D01*
Y364900D01*
G01X36100Y372300D02*
X32100D01*
Y364900D01*
G01X20650Y369552D02*
Y365552D01*
X28050D01*
G01X48700Y369533D02*
X52700D01*
Y376933D01*
G01X62400Y372100D02*
X58400D01*
Y364700D01*
G01X56800Y372100D02*
X52800D01*
Y364700D01*
G01X41700Y369400D02*
Y365400D01*
X49100D01*
G01X55617Y418650D02*
Y421150D01*
X56658D01*
X56992Y421025D01*
X57200Y420858D01*
X57283Y420525D01*
X57200Y420192D01*
X56950Y419983D01*
X56658Y419858D01*
X55617D01*
G01X56658D02*
X57283Y418650D01*
G01X58633Y419025D02*
X58883Y418817D01*
X59175Y418692D01*
X59550Y418650D01*
X59925Y418733D01*
X60217Y418900D01*
X60425Y419192D01*
X60467Y419525D01*
X60383Y419858D01*
X60175Y420067D01*
X59883Y420233D01*
X59592Y420275D01*
X59300Y420233D01*
X58925Y420067D01*
X59050Y421150D01*
X60175D01*
G01X61858Y420733D02*
X62108Y420983D01*
X62400Y421108D01*
X62733Y421150D01*
X63150Y421067D01*
X63442Y420858D01*
X63525Y420608D01*
X63483Y420358D01*
X63317Y420150D01*
X62483Y419733D01*
X62108Y419442D01*
X61858Y419025D01*
X61775Y418650D01*
X63525D01*
G01X65750D02*
X66042Y418692D01*
X66375Y418817D01*
X66583Y419025D01*
X66667Y419317D01*
X66583Y419608D01*
X66333Y419858D01*
X65958Y419983D01*
X65542D01*
X65292Y420067D01*
X65083Y420275D01*
X65000Y420567D01*
X65125Y420858D01*
X65417Y421067D01*
X65750Y421150D01*
X66083Y421067D01*
X66375Y420858D01*
X66500Y420567D01*
X66417Y420275D01*
X66208Y420067D01*
X65958Y419983D01*
X65542D01*
X65167Y419858D01*
X64917Y419608D01*
X64833Y419317D01*
X64917Y419025D01*
X65125Y418817D01*
X65458Y418692D01*
X65750Y418650D01*
G01X62800Y401150D02*
Y405150D01*
X55400D01*
G01X22000Y399017D02*
X19500D01*
Y400058D01*
X19625Y400392D01*
X19792Y400600D01*
X20125Y400683D01*
X20458Y400600D01*
X20667Y400350D01*
X20792Y400058D01*
Y399017D01*
G01Y400058D02*
X22000Y400683D01*
G01X21625Y402033D02*
X21833Y402283D01*
X21958Y402575D01*
X22000Y402950D01*
X21917Y403325D01*
X21750Y403617D01*
X21458Y403825D01*
X21125Y403867D01*
X20792Y403783D01*
X20583Y403575D01*
X20417Y403283D01*
X20375Y402992D01*
X20417Y402700D01*
X20583Y402325D01*
X19500Y402450D01*
Y403575D01*
G01X21500Y405133D02*
X21792Y405383D01*
X21958Y405717D01*
X22000Y406092D01*
X21958Y406425D01*
X21750Y406758D01*
X21500Y406967D01*
X21250Y407008D01*
X20958Y406925D01*
X20750Y406633D01*
X20667Y406342D01*
Y405967D01*
G01Y406342D02*
X20542Y406592D01*
X20333Y406800D01*
X20083Y406883D01*
X19833Y406800D01*
X19625Y406592D01*
X19500Y406217D01*
X19542Y405842D01*
X19708Y405467D01*
G01X22000Y409650D02*
X19500D01*
X21292Y408108D01*
Y410192D01*
G01X27700Y401400D02*
X23700D01*
Y394000D01*
G01X33223Y378737D02*
X30723D01*
Y379778D01*
X30848Y380112D01*
X31015Y380320D01*
X31348Y380403D01*
X31681Y380320D01*
X31890Y380070D01*
X32015Y379778D01*
Y378737D01*
G01Y379778D02*
X33223Y380403D01*
G01X32848Y381753D02*
X33056Y382003D01*
X33181Y382295D01*
X33223Y382670D01*
X33140Y383045D01*
X32973Y383337D01*
X32681Y383545D01*
X32348Y383587D01*
X32015Y383503D01*
X31806Y383295D01*
X31640Y383003D01*
X31598Y382712D01*
X31640Y382420D01*
X31806Y382045D01*
X30723Y382170D01*
Y383295D01*
G01X33223Y385770D02*
X33181Y386062D01*
X33056Y386395D01*
X32848Y386603D01*
X32556Y386687D01*
X32265Y386603D01*
X32015Y386353D01*
X31890Y385978D01*
Y385562D01*
X31806Y385312D01*
X31598Y385103D01*
X31306Y385020D01*
X31015Y385145D01*
X30806Y385437D01*
X30723Y385770D01*
X30806Y386103D01*
X31015Y386395D01*
X31306Y386520D01*
X31598Y386437D01*
X31806Y386228D01*
X31890Y385978D01*
Y385562D01*
X32015Y385187D01*
X32265Y384937D01*
X32556Y384853D01*
X32848Y384937D01*
X33056Y385145D01*
X33181Y385478D01*
X33223Y385770D01*
G01X32848Y387953D02*
X33056Y388203D01*
X33181Y388495D01*
X33223Y388870D01*
X33140Y389245D01*
X32973Y389537D01*
X32681Y389745D01*
X32348Y389787D01*
X32015Y389703D01*
X31806Y389495D01*
X31640Y389203D01*
X31598Y388912D01*
X31640Y388620D01*
X31806Y388245D01*
X30723Y388370D01*
Y389495D01*
G01X39500Y389400D02*
X35500D01*
Y382000D01*
G01X56797Y409654D02*
X56547Y409779D01*
X56255Y409862D01*
X55922D01*
X55547Y409737D01*
X55255Y409529D01*
X55047Y409279D01*
X54880Y408862D01*
X54838Y408487D01*
X54922Y408112D01*
X55047Y407862D01*
X55297Y407612D01*
X55588Y407445D01*
X55880Y407362D01*
X56172D01*
X56463Y407445D01*
X56713Y407570D01*
X56922Y407737D01*
G01X58897Y407362D02*
X58980Y407904D01*
X59105Y408362D01*
X59272Y408779D01*
X59480Y409237D01*
X59813Y409862D01*
X58147D01*
G01X61163Y407862D02*
X61413Y407570D01*
X61747Y407404D01*
X62122Y407362D01*
X62455Y407404D01*
X62788Y407612D01*
X62997Y407862D01*
X63038Y408112D01*
X62955Y408404D01*
X62663Y408612D01*
X62372Y408695D01*
X61997D01*
G01X62372D02*
X62622Y408820D01*
X62830Y409029D01*
X62913Y409279D01*
X62830Y409529D01*
X62622Y409737D01*
X62247Y409862D01*
X61872Y409820D01*
X61497Y409654D01*
G01X64388Y409445D02*
X64638Y409695D01*
X64930Y409820D01*
X65263Y409862D01*
X65680Y409779D01*
X65972Y409570D01*
X66055Y409320D01*
X66013Y409070D01*
X65847Y408862D01*
X65013Y408445D01*
X64638Y408154D01*
X64388Y407737D01*
X64305Y407362D01*
X66055D01*
G01X49042Y406267D02*
X48917Y406017D01*
X48834Y405725D01*
Y405392D01*
X48959Y405017D01*
X49167Y404725D01*
X49417Y404517D01*
X49834Y404350D01*
X50209Y404308D01*
X50584Y404392D01*
X50834Y404517D01*
X51084Y404767D01*
X51251Y405058D01*
X51334Y405350D01*
Y405642D01*
X51251Y405933D01*
X51126Y406183D01*
X50959Y406392D01*
G01X51334Y408367D02*
X50792Y408450D01*
X50334Y408575D01*
X49917Y408742D01*
X49459Y408950D01*
X48834Y409283D01*
Y407617D01*
G01X50834Y410633D02*
X51126Y410883D01*
X51292Y411217D01*
X51334Y411592D01*
X51292Y411925D01*
X51084Y412258D01*
X50834Y412467D01*
X50584Y412508D01*
X50292Y412425D01*
X50084Y412133D01*
X50001Y411842D01*
Y411467D01*
G01Y411842D02*
X49876Y412092D01*
X49667Y412300D01*
X49417Y412383D01*
X49167Y412300D01*
X48959Y412092D01*
X48834Y411717D01*
X48876Y411342D01*
X49042Y410967D01*
G01X50834Y413733D02*
X51126Y413983D01*
X51292Y414317D01*
X51334Y414692D01*
X51292Y415025D01*
X51084Y415358D01*
X50834Y415567D01*
X50584Y415608D01*
X50292Y415525D01*
X50084Y415233D01*
X50001Y414942D01*
Y414567D01*
G01Y414942D02*
X49876Y415192D01*
X49667Y415400D01*
X49417Y415483D01*
X49167Y415400D01*
X48959Y415192D01*
X48834Y414817D01*
X48876Y414442D01*
X49042Y414067D01*
G01X55667Y386259D02*
X55417Y386384D01*
X55125Y386467D01*
X54792D01*
X54417Y386342D01*
X54125Y386134D01*
X53917Y385884D01*
X53750Y385467D01*
X53708Y385092D01*
X53792Y384717D01*
X53917Y384467D01*
X54167Y384217D01*
X54458Y384050D01*
X54750Y383967D01*
X55042D01*
X55333Y384050D01*
X55583Y384175D01*
X55792Y384342D01*
G01X57767Y383967D02*
X57850Y384509D01*
X57975Y384967D01*
X58142Y385384D01*
X58350Y385842D01*
X58683Y386467D01*
X57017D01*
G01X60033Y384467D02*
X60283Y384175D01*
X60617Y384009D01*
X60992Y383967D01*
X61325Y384009D01*
X61658Y384217D01*
X61867Y384467D01*
X61908Y384717D01*
X61825Y385009D01*
X61533Y385217D01*
X61242Y385300D01*
X60867D01*
G01X61242D02*
X61492Y385425D01*
X61700Y385634D01*
X61783Y385884D01*
X61700Y386134D01*
X61492Y386342D01*
X61117Y386467D01*
X60742Y386425D01*
X60367Y386259D01*
G01X63258Y385009D02*
X63550Y385300D01*
X63800Y385467D01*
X64133Y385550D01*
X64425Y385467D01*
X64633Y385300D01*
X64800Y385050D01*
X64842Y384759D01*
X64800Y384509D01*
X64633Y384259D01*
X64383Y384050D01*
X64092Y383967D01*
X63758Y384050D01*
X63467Y384300D01*
X63300Y384675D01*
X63258Y385092D01*
X63342Y385634D01*
X63467Y385925D01*
X63675Y386217D01*
X63967Y386425D01*
X64258Y386467D01*
X64550Y386384D01*
X64758Y386175D01*
G01X57247Y417062D02*
X56997Y417187D01*
X56705Y417270D01*
X56372D01*
X55997Y417145D01*
X55705Y416937D01*
X55497Y416687D01*
X55330Y416270D01*
X55288Y415895D01*
X55372Y415520D01*
X55497Y415270D01*
X55747Y415020D01*
X56038Y414853D01*
X56330Y414770D01*
X56622D01*
X56913Y414853D01*
X57163Y414978D01*
X57372Y415145D01*
G01X59347Y414770D02*
X59430Y415312D01*
X59555Y415770D01*
X59722Y416187D01*
X59930Y416645D01*
X60263Y417270D01*
X58597D01*
G01X61613Y415270D02*
X61863Y414978D01*
X62197Y414812D01*
X62572Y414770D01*
X62905Y414812D01*
X63238Y415020D01*
X63447Y415270D01*
X63488Y415520D01*
X63405Y415812D01*
X63113Y416020D01*
X62822Y416103D01*
X62447D01*
G01X62822D02*
X63072Y416228D01*
X63280Y416437D01*
X63363Y416687D01*
X63280Y416937D01*
X63072Y417145D01*
X62697Y417270D01*
X62322Y417228D01*
X61947Y417062D01*
G01X65630Y414770D02*
X65922Y414812D01*
X66255Y414937D01*
X66463Y415145D01*
X66547Y415437D01*
X66463Y415728D01*
X66213Y415978D01*
X65838Y416103D01*
X65422D01*
X65172Y416187D01*
X64963Y416395D01*
X64880Y416687D01*
X65005Y416978D01*
X65297Y417187D01*
X65630Y417270D01*
X65963Y417187D01*
X66255Y416978D01*
X66380Y416687D01*
X66297Y416395D01*
X66088Y416187D01*
X65838Y416103D01*
X65422D01*
X65047Y415978D01*
X64797Y415728D01*
X64713Y415437D01*
X64797Y415145D01*
X65005Y414937D01*
X65338Y414812D01*
X65630Y414770D01*
G01X28554Y474076D02*
Y471576D01*
X30220D01*
G01X31612D02*
Y474076D01*
G01X33362D02*
Y471576D01*
G01Y472826D02*
X31612D01*
G01X35587Y471576D02*
X35254Y471618D01*
X34962Y471784D01*
X34712Y472034D01*
X34545Y472326D01*
X34462Y472659D01*
Y472993D01*
X34545Y473326D01*
X34712Y473618D01*
X34962Y473868D01*
X35254Y474034D01*
X35587Y474076D01*
X35920Y474034D01*
X36212Y473868D01*
X36462Y473618D01*
X36629Y473326D01*
X36712Y472993D01*
Y472659D01*
X36629Y472326D01*
X36462Y472034D01*
X36212Y471784D01*
X35920Y471618D01*
X35587Y471576D01*
G01X37854Y474076D02*
Y471576D01*
X39520D01*
G01X42620D02*
X40954D01*
Y474076D01*
X42620D01*
G01X41954Y472868D02*
X40954D01*
G01X44887Y471576D02*
Y474076D01*
X44387Y473576D01*
G01Y471576D02*
X45387D01*
G01X127100Y-8967D02*
X127633Y-9300D01*
X128233Y-9500D01*
X128767D01*
X129300Y-9300D01*
X129700Y-8967D01*
X129900Y-8500D01*
X129767Y-8033D01*
X129433Y-7633D01*
X128833Y-7367D01*
X128033Y-7233D01*
X127567Y-6967D01*
X127367Y-6500D01*
X127500Y-6033D01*
X127833Y-5700D01*
X128300Y-5500D01*
X128767D01*
X129233Y-5633D01*
X129633Y-5967D01*
G01X133100Y-9500D02*
Y-5500D01*
G01X137700Y-6833D02*
Y-9500D01*
G01Y-5767D02*
X137567Y-5700D01*
Y-5567D01*
X137700Y-5500D01*
X137833Y-5567D01*
Y-5700D01*
X137700Y-5767D01*
G01X142300Y-5500D02*
Y-9500D01*
G01X141367Y-6833D02*
X143233D01*
G01X101369Y0D02*
X167069D01*
Y63703D01*
X101369D01*
Y0D01*
G01X133817Y71292D02*
X133567Y71417D01*
X133275Y71500D01*
X132942D01*
X132567Y71375D01*
X132275Y71167D01*
X132067Y70917D01*
X131900Y70500D01*
X131858Y70125D01*
X131942Y69750D01*
X132067Y69500D01*
X132317Y69250D01*
X132608Y69083D01*
X132900Y69000D01*
X133192D01*
X133483Y69083D01*
X133733Y69208D01*
X133942Y69375D01*
G01X135042Y69000D02*
Y71500D01*
X136958Y69000D01*
Y71500D01*
G01X139100Y69000D02*
Y71500D01*
X138600Y71000D01*
G01Y69000D02*
X139600D01*
G01X126436Y58103D02*
Y62103D01*
X128036D01*
X128569Y61903D01*
X128969Y61436D01*
X129102Y60903D01*
X128969Y60370D01*
X128636Y59970D01*
X128036Y59770D01*
X126436D01*
G01X131436Y58103D02*
Y60770D01*
G01Y60236D02*
X131769Y60503D01*
X132102Y60703D01*
X132569Y60770D01*
X132902Y60703D01*
X133302Y60503D01*
G01X135969Y59903D02*
X138102D01*
X137902Y60370D01*
X137569Y60636D01*
X137102Y60770D01*
X136636Y60703D01*
X136236Y60503D01*
X135969Y60036D01*
X135836Y59636D01*
Y59236D01*
X135969Y58836D01*
X136302Y58436D01*
X136702Y58170D01*
X137169Y58103D01*
X137636Y58236D01*
X138102Y58636D01*
G01X140569Y58570D02*
X140902Y58303D01*
X141369Y58103D01*
X141769D01*
X142169Y58236D01*
X142436Y58436D01*
X142569Y58703D01*
X142502Y59103D01*
X142236Y59303D01*
X141036Y59703D01*
X140769Y60170D01*
X140902Y60503D01*
X141169Y60703D01*
X141569Y60770D01*
X141969Y60703D01*
X142369Y60503D01*
G01X145169Y58570D02*
X145502Y58303D01*
X145969Y58103D01*
X146369D01*
X146769Y58236D01*
X147036Y58436D01*
X147169Y58703D01*
X147102Y59103D01*
X146836Y59303D01*
X145636Y59703D01*
X145369Y60170D01*
X145502Y60503D01*
X145769Y60703D01*
X146169Y60770D01*
X146569Y60703D01*
X146969Y60503D01*
G01X154969Y58103D02*
Y61503D01*
X155102Y61836D01*
X155369Y62036D01*
X155769Y62103D01*
X156169Y61970D01*
X156369Y61636D01*
G01X155569Y60503D02*
X154236D01*
G01X159969Y60770D02*
Y58103D01*
G01Y61836D02*
X159836Y61903D01*
Y62036D01*
X159969Y62103D01*
X160102Y62036D01*
Y61903D01*
X159969Y61836D01*
G01X164569Y62103D02*
Y58103D01*
G01X163636Y60770D02*
X165502D01*
G01X106300Y162467D02*
X103800D01*
Y163508D01*
X103925Y163842D01*
X104092Y164050D01*
X104425Y164133D01*
X104758Y164050D01*
X104967Y163800D01*
X105092Y163508D01*
Y162467D01*
G01Y163508D02*
X106300Y164133D01*
G01Y166400D02*
X103800D01*
X104300Y165900D01*
G01X106300D02*
Y166900D01*
G01X105258Y168708D02*
X104967Y169000D01*
X104800Y169250D01*
X104717Y169583D01*
X104800Y169875D01*
X104967Y170083D01*
X105217Y170250D01*
X105508Y170292D01*
X105758Y170250D01*
X106008Y170083D01*
X106217Y169833D01*
X106300Y169542D01*
X106217Y169208D01*
X105967Y168917D01*
X105592Y168750D01*
X105175Y168708D01*
X104633Y168792D01*
X104342Y168917D01*
X104050Y169125D01*
X103842Y169417D01*
X103800Y169708D01*
X103883Y170000D01*
X104092Y170208D01*
G01X115200Y162667D02*
X112700D01*
Y163708D01*
X112825Y164042D01*
X112992Y164250D01*
X113325Y164333D01*
X113658Y164250D01*
X113867Y164000D01*
X113992Y163708D01*
Y162667D01*
G01Y163708D02*
X115200Y164333D01*
G01Y166600D02*
X112700D01*
X113200Y166100D01*
G01X115200D02*
Y167100D01*
G01X114825Y168783D02*
X115033Y169033D01*
X115158Y169325D01*
X115200Y169700D01*
X115117Y170075D01*
X114950Y170367D01*
X114658Y170575D01*
X114325Y170617D01*
X113992Y170533D01*
X113783Y170325D01*
X113617Y170033D01*
X113575Y169742D01*
X113617Y169450D01*
X113783Y169075D01*
X112700Y169200D01*
Y170325D01*
G01X120100Y158117D02*
X117600D01*
Y159158D01*
X117725Y159492D01*
X117892Y159700D01*
X118225Y159783D01*
X118558Y159700D01*
X118767Y159450D01*
X118892Y159158D01*
Y158117D01*
G01Y159158D02*
X120100Y159783D01*
G01X119725Y161133D02*
X119933Y161383D01*
X120058Y161675D01*
X120100Y162050D01*
X120017Y162425D01*
X119850Y162717D01*
X119558Y162925D01*
X119225Y162967D01*
X118892Y162883D01*
X118683Y162675D01*
X118517Y162383D01*
X118475Y162092D01*
X118517Y161800D01*
X118683Y161425D01*
X117600Y161550D01*
Y162675D01*
G01X119725Y164233D02*
X119933Y164483D01*
X120058Y164775D01*
X120100Y165150D01*
X120017Y165525D01*
X119850Y165817D01*
X119558Y166025D01*
X119225Y166067D01*
X118892Y165983D01*
X118683Y165775D01*
X118517Y165483D01*
X118475Y165192D01*
X118517Y164900D01*
X118683Y164525D01*
X117600Y164650D01*
Y165775D01*
G01X120100Y168250D02*
X117600D01*
X118100Y167750D01*
G01X120100D02*
Y168750D01*
G01X101800Y160917D02*
X99300D01*
Y161958D01*
X99425Y162292D01*
X99592Y162500D01*
X99925Y162583D01*
X100258Y162500D01*
X100467Y162250D01*
X100592Y161958D01*
Y160917D01*
G01Y161958D02*
X101800Y162583D01*
G01X101425Y163933D02*
X101633Y164183D01*
X101758Y164475D01*
X101800Y164850D01*
X101717Y165225D01*
X101550Y165517D01*
X101258Y165725D01*
X100925Y165767D01*
X100592Y165683D01*
X100383Y165475D01*
X100217Y165183D01*
X100175Y164892D01*
X100217Y164600D01*
X100383Y164225D01*
X99300Y164350D01*
Y165475D01*
G01X101425Y167033D02*
X101633Y167283D01*
X101758Y167575D01*
X101800Y167950D01*
X101717Y168325D01*
X101550Y168617D01*
X101258Y168825D01*
X100925Y168867D01*
X100592Y168783D01*
X100383Y168575D01*
X100217Y168283D01*
X100175Y167992D01*
X100217Y167700D01*
X100383Y167325D01*
X99300Y167450D01*
Y168575D01*
G01Y171050D02*
X99383Y170717D01*
X99592Y170467D01*
X99842Y170300D01*
X100175Y170175D01*
X100550Y170133D01*
X100925Y170175D01*
X101258Y170300D01*
X101508Y170467D01*
X101717Y170717D01*
X101800Y171050D01*
X101717Y171383D01*
X101508Y171633D01*
X101258Y171800D01*
X100925Y171925D01*
X100550Y171967D01*
X100175Y171925D01*
X99842Y171800D01*
X99592Y171633D01*
X99383Y171383D01*
X99300Y171050D01*
G01X93000Y161067D02*
X90500D01*
Y162108D01*
X90625Y162442D01*
X90792Y162650D01*
X91125Y162733D01*
X91458Y162650D01*
X91667Y162400D01*
X91792Y162108D01*
Y161067D01*
G01Y162108D02*
X93000Y162733D01*
G01Y165000D02*
X90500D01*
X91000Y164500D01*
G01X93000D02*
Y165500D01*
G01Y168100D02*
X90500D01*
X91000Y167600D01*
G01X93000D02*
Y168600D01*
G01X80500Y161217D02*
X78000D01*
Y162258D01*
X78125Y162592D01*
X78292Y162800D01*
X78625Y162883D01*
X78958Y162800D01*
X79167Y162550D01*
X79292Y162258D01*
Y161217D01*
G01Y162258D02*
X80500Y162883D01*
G01X80125Y164233D02*
X80333Y164483D01*
X80458Y164775D01*
X80500Y165150D01*
X80417Y165525D01*
X80250Y165817D01*
X79958Y166025D01*
X79625Y166067D01*
X79292Y165983D01*
X79083Y165775D01*
X78917Y165483D01*
X78875Y165192D01*
X78917Y164900D01*
X79083Y164525D01*
X78000Y164650D01*
Y165775D01*
G01X78417Y167458D02*
X78167Y167708D01*
X78042Y168000D01*
X78000Y168333D01*
X78083Y168750D01*
X78292Y169042D01*
X78542Y169125D01*
X78792Y169083D01*
X79000Y168917D01*
X79417Y168083D01*
X79708Y167708D01*
X80125Y167458D01*
X80500Y167375D01*
Y169125D01*
G01X80000Y170433D02*
X80292Y170683D01*
X80458Y171017D01*
X80500Y171392D01*
X80458Y171725D01*
X80250Y172058D01*
X80000Y172267D01*
X79750Y172308D01*
X79458Y172225D01*
X79250Y171933D01*
X79167Y171642D01*
Y171267D01*
G01Y171642D02*
X79042Y171892D01*
X78833Y172100D01*
X78583Y172183D01*
X78333Y172100D01*
X78125Y171892D01*
X78000Y171517D01*
X78042Y171142D01*
X78208Y170767D01*
G01X85000Y161217D02*
X82500D01*
Y162258D01*
X82625Y162592D01*
X82792Y162800D01*
X83125Y162883D01*
X83458Y162800D01*
X83667Y162550D01*
X83792Y162258D01*
Y161217D01*
G01Y162258D02*
X85000Y162883D01*
G01X84625Y164233D02*
X84833Y164483D01*
X84958Y164775D01*
X85000Y165150D01*
X84917Y165525D01*
X84750Y165817D01*
X84458Y166025D01*
X84125Y166067D01*
X83792Y165983D01*
X83583Y165775D01*
X83417Y165483D01*
X83375Y165192D01*
X83417Y164900D01*
X83583Y164525D01*
X82500Y164650D01*
Y165775D01*
G01X82917Y167458D02*
X82667Y167708D01*
X82542Y168000D01*
X82500Y168333D01*
X82583Y168750D01*
X82792Y169042D01*
X83042Y169125D01*
X83292Y169083D01*
X83500Y168917D01*
X83917Y168083D01*
X84208Y167708D01*
X84625Y167458D01*
X85000Y167375D01*
Y169125D01*
G01X82917Y170558D02*
X82667Y170808D01*
X82542Y171100D01*
X82500Y171433D01*
X82583Y171850D01*
X82792Y172142D01*
X83042Y172225D01*
X83292Y172183D01*
X83500Y172017D01*
X83917Y171183D01*
X84208Y170808D01*
X84625Y170558D01*
X85000Y170475D01*
Y172225D01*
G01X138108Y162767D02*
X137983Y162517D01*
X137900Y162225D01*
Y161892D01*
X138025Y161517D01*
X138233Y161225D01*
X138483Y161017D01*
X138900Y160850D01*
X139275Y160808D01*
X139650Y160892D01*
X139900Y161017D01*
X140150Y161267D01*
X140317Y161558D01*
X140400Y161850D01*
Y162142D01*
X140317Y162433D01*
X140192Y162683D01*
X140025Y162892D01*
G01X139358Y164158D02*
X139067Y164450D01*
X138900Y164700D01*
X138817Y165033D01*
X138900Y165325D01*
X139067Y165533D01*
X139317Y165700D01*
X139608Y165742D01*
X139858Y165700D01*
X140108Y165533D01*
X140317Y165283D01*
X140400Y164992D01*
X140317Y164658D01*
X140067Y164367D01*
X139692Y164200D01*
X139275Y164158D01*
X138733Y164242D01*
X138442Y164367D01*
X138150Y164575D01*
X137942Y164867D01*
X137900Y165158D01*
X137983Y165450D01*
X138192Y165658D01*
G01X139358Y167258D02*
X139067Y167550D01*
X138900Y167800D01*
X138817Y168133D01*
X138900Y168425D01*
X139067Y168633D01*
X139317Y168800D01*
X139608Y168842D01*
X139858Y168800D01*
X140108Y168633D01*
X140317Y168383D01*
X140400Y168092D01*
X140317Y167758D01*
X140067Y167467D01*
X139692Y167300D01*
X139275Y167258D01*
X138733Y167342D01*
X138442Y167467D01*
X138150Y167675D01*
X137942Y167967D01*
X137900Y168258D01*
X137983Y168550D01*
X138192Y168758D01*
G01X140400Y171150D02*
X140358Y171442D01*
X140233Y171775D01*
X140025Y171983D01*
X139733Y172067D01*
X139442Y171983D01*
X139192Y171733D01*
X139067Y171358D01*
Y170942D01*
X138983Y170692D01*
X138775Y170483D01*
X138483Y170400D01*
X138192Y170525D01*
X137983Y170817D01*
X137900Y171150D01*
X137983Y171483D01*
X138192Y171775D01*
X138483Y171900D01*
X138775Y171817D01*
X138983Y171608D01*
X139067Y171358D01*
Y170942D01*
X139192Y170567D01*
X139442Y170317D01*
X139733Y170233D01*
X140025Y170317D01*
X140233Y170525D01*
X140358Y170858D01*
X140400Y171150D01*
G01X88581Y142725D02*
X88456Y142475D01*
X88373Y142183D01*
Y141850D01*
X88498Y141475D01*
X88706Y141183D01*
X88956Y140975D01*
X89373Y140808D01*
X89748Y140766D01*
X90123Y140850D01*
X90373Y140975D01*
X90623Y141225D01*
X90790Y141516D01*
X90873Y141808D01*
Y142100D01*
X90790Y142391D01*
X90665Y142641D01*
X90498Y142850D01*
G01Y143991D02*
X90706Y144241D01*
X90831Y144533D01*
X90873Y144908D01*
X90790Y145283D01*
X90623Y145575D01*
X90331Y145783D01*
X89998Y145825D01*
X89665Y145741D01*
X89456Y145533D01*
X89290Y145241D01*
X89248Y144950D01*
X89290Y144658D01*
X89456Y144283D01*
X88373Y144408D01*
Y145533D01*
G01X89831Y147216D02*
X89540Y147508D01*
X89373Y147758D01*
X89290Y148091D01*
X89373Y148383D01*
X89540Y148591D01*
X89790Y148758D01*
X90081Y148800D01*
X90331Y148758D01*
X90581Y148591D01*
X90790Y148341D01*
X90873Y148050D01*
X90790Y147716D01*
X90540Y147425D01*
X90165Y147258D01*
X89748Y147216D01*
X89206Y147300D01*
X88915Y147425D01*
X88623Y147633D01*
X88415Y147925D01*
X88373Y148216D01*
X88456Y148508D01*
X88665Y148716D01*
G01X90498Y150191D02*
X90706Y150441D01*
X90831Y150733D01*
X90873Y151108D01*
X90790Y151483D01*
X90623Y151775D01*
X90331Y151983D01*
X89998Y152025D01*
X89665Y151941D01*
X89456Y151733D01*
X89290Y151441D01*
X89248Y151150D01*
X89290Y150858D01*
X89456Y150483D01*
X88373Y150608D01*
Y151733D01*
G01X104078Y142747D02*
X103953Y142497D01*
X103870Y142205D01*
Y141872D01*
X103995Y141497D01*
X104203Y141205D01*
X104453Y140997D01*
X104870Y140830D01*
X105245Y140788D01*
X105620Y140872D01*
X105870Y140997D01*
X106120Y141247D01*
X106287Y141538D01*
X106370Y141830D01*
Y142122D01*
X106287Y142413D01*
X106162Y142663D01*
X105995Y142872D01*
G01Y144013D02*
X106203Y144263D01*
X106328Y144555D01*
X106370Y144930D01*
X106287Y145305D01*
X106120Y145597D01*
X105828Y145805D01*
X105495Y145847D01*
X105162Y145763D01*
X104953Y145555D01*
X104787Y145263D01*
X104745Y144972D01*
X104787Y144680D01*
X104953Y144305D01*
X103870Y144430D01*
Y145555D01*
G01X105328Y147238D02*
X105037Y147530D01*
X104870Y147780D01*
X104787Y148113D01*
X104870Y148405D01*
X105037Y148613D01*
X105287Y148780D01*
X105578Y148822D01*
X105828Y148780D01*
X106078Y148613D01*
X106287Y148363D01*
X106370Y148072D01*
X106287Y147738D01*
X106037Y147447D01*
X105662Y147280D01*
X105245Y147238D01*
X104703Y147322D01*
X104412Y147447D01*
X104120Y147655D01*
X103912Y147947D01*
X103870Y148238D01*
X103953Y148530D01*
X104162Y148738D01*
G01X105328Y150338D02*
X105037Y150630D01*
X104870Y150880D01*
X104787Y151213D01*
X104870Y151505D01*
X105037Y151713D01*
X105287Y151880D01*
X105578Y151922D01*
X105828Y151880D01*
X106078Y151713D01*
X106287Y151463D01*
X106370Y151172D01*
X106287Y150838D01*
X106037Y150547D01*
X105662Y150380D01*
X105245Y150338D01*
X104703Y150422D01*
X104412Y150547D01*
X104120Y150755D01*
X103912Y151047D01*
X103870Y151338D01*
X103953Y151630D01*
X104162Y151838D01*
G01X96378Y142757D02*
X96253Y142507D01*
X96170Y142215D01*
Y141882D01*
X96295Y141507D01*
X96503Y141215D01*
X96753Y141007D01*
X97170Y140840D01*
X97545Y140798D01*
X97920Y140882D01*
X98170Y141007D01*
X98420Y141257D01*
X98587Y141548D01*
X98670Y141840D01*
Y142132D01*
X98587Y142423D01*
X98462Y142673D01*
X98295Y142882D01*
G01X98670Y144857D02*
X98128Y144940D01*
X97670Y145065D01*
X97253Y145232D01*
X96795Y145440D01*
X96170Y145773D01*
Y144107D01*
G01X98170Y147123D02*
X98462Y147373D01*
X98628Y147707D01*
X98670Y148082D01*
X98628Y148415D01*
X98420Y148748D01*
X98170Y148957D01*
X97920Y148998D01*
X97628Y148915D01*
X97420Y148623D01*
X97337Y148332D01*
Y147957D01*
G01Y148332D02*
X97212Y148582D01*
X97003Y148790D01*
X96753Y148873D01*
X96503Y148790D01*
X96295Y148582D01*
X96170Y148207D01*
X96212Y147832D01*
X96378Y147457D01*
G01X98378Y150432D02*
X98587Y150723D01*
X98670Y151057D01*
X98587Y151390D01*
X98337Y151682D01*
X97962Y151890D01*
X97587Y151973D01*
X97128D01*
X96753Y151890D01*
X96420Y151682D01*
X96253Y151432D01*
X96170Y151140D01*
X96253Y150807D01*
X96420Y150557D01*
X96670Y150390D01*
X97003Y150307D01*
X97295Y150390D01*
X97587Y150598D01*
X97753Y150848D01*
X97795Y151140D01*
X97712Y151473D01*
X97503Y151723D01*
X97128Y151973D01*
G01X95108Y162667D02*
X94983Y162417D01*
X94900Y162125D01*
Y161792D01*
X95025Y161417D01*
X95233Y161125D01*
X95483Y160917D01*
X95900Y160750D01*
X96275Y160708D01*
X96650Y160792D01*
X96900Y160917D01*
X97150Y161167D01*
X97317Y161458D01*
X97400Y161750D01*
Y162042D01*
X97317Y162333D01*
X97192Y162583D01*
X97025Y162792D01*
G01X96358Y164058D02*
X96067Y164350D01*
X95900Y164600D01*
X95817Y164933D01*
X95900Y165225D01*
X96067Y165433D01*
X96317Y165600D01*
X96608Y165642D01*
X96858Y165600D01*
X97108Y165433D01*
X97317Y165183D01*
X97400Y164892D01*
X97317Y164558D01*
X97067Y164267D01*
X96692Y164100D01*
X96275Y164058D01*
X95733Y164142D01*
X95442Y164267D01*
X95150Y164475D01*
X94942Y164767D01*
X94900Y165058D01*
X94983Y165350D01*
X95192Y165558D01*
G01X97025Y167033D02*
X97233Y167283D01*
X97358Y167575D01*
X97400Y167950D01*
X97317Y168325D01*
X97150Y168617D01*
X96858Y168825D01*
X96525Y168867D01*
X96192Y168783D01*
X95983Y168575D01*
X95817Y168283D01*
X95775Y167992D01*
X95817Y167700D01*
X95983Y167325D01*
X94900Y167450D01*
Y168575D01*
G01Y171050D02*
X94983Y170717D01*
X95192Y170467D01*
X95442Y170300D01*
X95775Y170175D01*
X96150Y170133D01*
X96525Y170175D01*
X96858Y170300D01*
X97108Y170467D01*
X97317Y170717D01*
X97400Y171050D01*
X97317Y171383D01*
X97108Y171633D01*
X96858Y171800D01*
X96525Y171925D01*
X96150Y171967D01*
X95775Y171925D01*
X95442Y171800D01*
X95192Y171633D01*
X94983Y171383D01*
X94900Y171050D01*
G01X108508Y162767D02*
X108383Y162517D01*
X108300Y162225D01*
Y161892D01*
X108425Y161517D01*
X108633Y161225D01*
X108883Y161017D01*
X109300Y160850D01*
X109675Y160808D01*
X110050Y160892D01*
X110300Y161017D01*
X110550Y161267D01*
X110717Y161558D01*
X110800Y161850D01*
Y162142D01*
X110717Y162433D01*
X110592Y162683D01*
X110425Y162892D01*
G01X109758Y164158D02*
X109467Y164450D01*
X109300Y164700D01*
X109217Y165033D01*
X109300Y165325D01*
X109467Y165533D01*
X109717Y165700D01*
X110008Y165742D01*
X110258Y165700D01*
X110508Y165533D01*
X110717Y165283D01*
X110800Y164992D01*
X110717Y164658D01*
X110467Y164367D01*
X110092Y164200D01*
X109675Y164158D01*
X109133Y164242D01*
X108842Y164367D01*
X108550Y164575D01*
X108342Y164867D01*
X108300Y165158D01*
X108383Y165450D01*
X108592Y165658D01*
G01X110800Y168550D02*
X108300D01*
X110092Y167008D01*
Y169092D01*
G01X110508Y170442D02*
X110717Y170733D01*
X110800Y171067D01*
X110717Y171400D01*
X110467Y171692D01*
X110092Y171900D01*
X109717Y171983D01*
X109258D01*
X108883Y171900D01*
X108550Y171692D01*
X108383Y171442D01*
X108300Y171150D01*
X108383Y170817D01*
X108550Y170567D01*
X108800Y170400D01*
X109133Y170317D01*
X109425Y170400D01*
X109717Y170608D01*
X109883Y170858D01*
X109925Y171150D01*
X109842Y171483D01*
X109633Y171733D01*
X109258Y171983D01*
G01X86708Y162767D02*
X86583Y162517D01*
X86500Y162225D01*
Y161892D01*
X86625Y161517D01*
X86833Y161225D01*
X87083Y161017D01*
X87500Y160850D01*
X87875Y160808D01*
X88250Y160892D01*
X88500Y161017D01*
X88750Y161267D01*
X88917Y161558D01*
X89000Y161850D01*
Y162142D01*
X88917Y162433D01*
X88792Y162683D01*
X88625Y162892D01*
G01X87958Y164158D02*
X87667Y164450D01*
X87500Y164700D01*
X87417Y165033D01*
X87500Y165325D01*
X87667Y165533D01*
X87917Y165700D01*
X88208Y165742D01*
X88458Y165700D01*
X88708Y165533D01*
X88917Y165283D01*
X89000Y164992D01*
X88917Y164658D01*
X88667Y164367D01*
X88292Y164200D01*
X87875Y164158D01*
X87333Y164242D01*
X87042Y164367D01*
X86750Y164575D01*
X86542Y164867D01*
X86500Y165158D01*
X86583Y165450D01*
X86792Y165658D01*
G01X89000Y168550D02*
X86500D01*
X88292Y167008D01*
Y169092D01*
G01X87958Y170358D02*
X87667Y170650D01*
X87500Y170900D01*
X87417Y171233D01*
X87500Y171525D01*
X87667Y171733D01*
X87917Y171900D01*
X88208Y171942D01*
X88458Y171900D01*
X88708Y171733D01*
X88917Y171483D01*
X89000Y171192D01*
X88917Y170858D01*
X88667Y170567D01*
X88292Y170400D01*
X87875Y170358D01*
X87333Y170442D01*
X87042Y170567D01*
X86750Y170775D01*
X86542Y171067D01*
X86500Y171358D01*
X86583Y171650D01*
X86792Y171858D01*
G01X98367Y216900D02*
Y219400D01*
X99408D01*
X99742Y219275D01*
X99950Y219108D01*
X100033Y218775D01*
X99950Y218442D01*
X99700Y218233D01*
X99408Y218108D01*
X98367D01*
G01X99408D02*
X100033Y216900D01*
G01X101508Y218983D02*
X101758Y219233D01*
X102050Y219358D01*
X102383Y219400D01*
X102800Y219317D01*
X103092Y219108D01*
X103175Y218858D01*
X103133Y218608D01*
X102967Y218400D01*
X102133Y217983D01*
X101758Y217692D01*
X101508Y217275D01*
X101425Y216900D01*
X103175D01*
G01X105400Y219400D02*
X105067Y219317D01*
X104817Y219108D01*
X104650Y218858D01*
X104525Y218525D01*
X104483Y218150D01*
X104525Y217775D01*
X104650Y217442D01*
X104817Y217192D01*
X105067Y216983D01*
X105400Y216900D01*
X105733Y216983D01*
X105983Y217192D01*
X106150Y217442D01*
X106275Y217775D01*
X106317Y218150D01*
X106275Y218525D01*
X106150Y218858D01*
X105983Y219108D01*
X105733Y219317D01*
X105400Y219400D01*
G01X82100Y219900D02*
Y215900D01*
X89500D01*
G01X87834Y234017D02*
X85334D01*
Y235058D01*
X85459Y235392D01*
X85626Y235600D01*
X85959Y235683D01*
X86292Y235600D01*
X86501Y235350D01*
X86626Y235058D01*
Y234017D01*
G01Y235058D02*
X87834Y235683D01*
G01X87459Y237033D02*
X87667Y237283D01*
X87792Y237575D01*
X87834Y237950D01*
X87751Y238325D01*
X87584Y238617D01*
X87292Y238825D01*
X86959Y238867D01*
X86626Y238783D01*
X86417Y238575D01*
X86251Y238283D01*
X86209Y237992D01*
X86251Y237700D01*
X86417Y237325D01*
X85334Y237450D01*
Y238575D01*
G01X85751Y240258D02*
X85501Y240508D01*
X85376Y240800D01*
X85334Y241133D01*
X85417Y241550D01*
X85626Y241842D01*
X85876Y241925D01*
X86126Y241883D01*
X86334Y241717D01*
X86751Y240883D01*
X87042Y240508D01*
X87459Y240258D01*
X87834Y240175D01*
Y241925D01*
G01Y244150D02*
X85334D01*
X85834Y243650D01*
G01X87834D02*
Y244650D01*
G01X85300Y221700D02*
X89300D01*
Y229100D01*
G01X98367Y190900D02*
Y193400D01*
X99408D01*
X99742Y193275D01*
X99950Y193108D01*
X100033Y192775D01*
X99950Y192442D01*
X99700Y192233D01*
X99408Y192108D01*
X98367D01*
G01X99408D02*
X100033Y190900D01*
G01X101508Y192983D02*
X101758Y193233D01*
X102050Y193358D01*
X102383Y193400D01*
X102800Y193317D01*
X103092Y193108D01*
X103175Y192858D01*
X103133Y192608D01*
X102967Y192400D01*
X102133Y191983D01*
X101758Y191692D01*
X101508Y191275D01*
X101425Y190900D01*
X103175D01*
G01X104608Y192983D02*
X104858Y193233D01*
X105150Y193358D01*
X105483Y193400D01*
X105900Y193317D01*
X106192Y193108D01*
X106275Y192858D01*
X106233Y192608D01*
X106067Y192400D01*
X105233Y191983D01*
X104858Y191692D01*
X104608Y191275D01*
X104525Y190900D01*
X106275D01*
G01X83600Y192900D02*
Y188900D01*
X91000D01*
G01X87700Y188800D02*
X83700D01*
Y181400D01*
G01X87800D02*
X91800D01*
Y188800D01*
G01X96767Y223459D02*
X96517Y223584D01*
X96225Y223667D01*
X95892D01*
X95517Y223542D01*
X95225Y223334D01*
X95017Y223084D01*
X94850Y222667D01*
X94808Y222292D01*
X94892Y221917D01*
X95017Y221667D01*
X95267Y221417D01*
X95558Y221250D01*
X95850Y221167D01*
X96142D01*
X96433Y221250D01*
X96683Y221375D01*
X96892Y221542D01*
G01X98158Y222209D02*
X98450Y222500D01*
X98700Y222667D01*
X99033Y222750D01*
X99325Y222667D01*
X99533Y222500D01*
X99700Y222250D01*
X99742Y221959D01*
X99700Y221709D01*
X99533Y221459D01*
X99283Y221250D01*
X98992Y221167D01*
X98658Y221250D01*
X98367Y221500D01*
X98200Y221875D01*
X98158Y222292D01*
X98242Y222834D01*
X98367Y223125D01*
X98575Y223417D01*
X98867Y223625D01*
X99158Y223667D01*
X99450Y223584D01*
X99658Y223375D01*
G01X102550Y221167D02*
Y223667D01*
X101008Y221875D01*
X103092D01*
G01X105150Y221167D02*
X105442Y221209D01*
X105775Y221334D01*
X105983Y221542D01*
X106067Y221834D01*
X105983Y222125D01*
X105733Y222375D01*
X105358Y222500D01*
X104942D01*
X104692Y222584D01*
X104483Y222792D01*
X104400Y223084D01*
X104525Y223375D01*
X104817Y223584D01*
X105150Y223667D01*
X105483Y223584D01*
X105775Y223375D01*
X105900Y223084D01*
X105817Y222792D01*
X105608Y222584D01*
X105358Y222500D01*
X104942D01*
X104567Y222375D01*
X104317Y222125D01*
X104233Y221834D01*
X104317Y221542D01*
X104525Y221334D01*
X104858Y221209D01*
X105150Y221167D01*
G01X81542Y236267D02*
X81417Y236017D01*
X81334Y235725D01*
Y235392D01*
X81459Y235017D01*
X81667Y234725D01*
X81917Y234517D01*
X82334Y234350D01*
X82709Y234308D01*
X83084Y234392D01*
X83334Y234517D01*
X83584Y234767D01*
X83751Y235058D01*
X83834Y235350D01*
Y235642D01*
X83751Y235933D01*
X83626Y236183D01*
X83459Y236392D01*
G01X82792Y237658D02*
X82501Y237950D01*
X82334Y238200D01*
X82251Y238533D01*
X82334Y238825D01*
X82501Y239033D01*
X82751Y239200D01*
X83042Y239242D01*
X83292Y239200D01*
X83542Y239033D01*
X83751Y238783D01*
X83834Y238492D01*
X83751Y238158D01*
X83501Y237867D01*
X83126Y237700D01*
X82709Y237658D01*
X82167Y237742D01*
X81876Y237867D01*
X81584Y238075D01*
X81376Y238367D01*
X81334Y238658D01*
X81417Y238950D01*
X81626Y239158D01*
G01X83459Y240633D02*
X83667Y240883D01*
X83792Y241175D01*
X83834Y241550D01*
X83751Y241925D01*
X83584Y242217D01*
X83292Y242425D01*
X82959Y242467D01*
X82626Y242383D01*
X82417Y242175D01*
X82251Y241883D01*
X82209Y241592D01*
X82251Y241300D01*
X82417Y240925D01*
X81334Y241050D01*
Y242175D01*
G01X83334Y243733D02*
X83626Y243983D01*
X83792Y244317D01*
X83834Y244692D01*
X83792Y245025D01*
X83584Y245358D01*
X83334Y245567D01*
X83084Y245608D01*
X82792Y245525D01*
X82584Y245233D01*
X82501Y244942D01*
Y244567D01*
G01Y244942D02*
X82376Y245192D01*
X82167Y245400D01*
X81917Y245483D01*
X81667Y245400D01*
X81459Y245192D01*
X81334Y244817D01*
X81376Y244442D01*
X81542Y244067D01*
G01X99767Y201792D02*
X99517Y201917D01*
X99225Y202000D01*
X98892D01*
X98517Y201875D01*
X98225Y201667D01*
X98017Y201417D01*
X97850Y201000D01*
X97808Y200625D01*
X97892Y200250D01*
X98017Y200000D01*
X98267Y199750D01*
X98558Y199583D01*
X98850Y199500D01*
X99142D01*
X99433Y199583D01*
X99683Y199708D01*
X99892Y199875D01*
G01X101158Y200542D02*
X101450Y200833D01*
X101700Y201000D01*
X102033Y201083D01*
X102325Y201000D01*
X102533Y200833D01*
X102700Y200583D01*
X102742Y200292D01*
X102700Y200042D01*
X102533Y199792D01*
X102283Y199583D01*
X101992Y199500D01*
X101658Y199583D01*
X101367Y199833D01*
X101200Y200208D01*
X101158Y200625D01*
X101242Y201167D01*
X101367Y201458D01*
X101575Y201750D01*
X101867Y201958D01*
X102158Y202000D01*
X102450Y201917D01*
X102658Y201708D01*
G01X104133Y199875D02*
X104383Y199667D01*
X104675Y199542D01*
X105050Y199500D01*
X105425Y199583D01*
X105717Y199750D01*
X105925Y200042D01*
X105967Y200375D01*
X105883Y200708D01*
X105675Y200917D01*
X105383Y201083D01*
X105092Y201125D01*
X104800Y201083D01*
X104425Y200917D01*
X104550Y202000D01*
X105675D01*
G01X107358Y201583D02*
X107608Y201833D01*
X107900Y201958D01*
X108233Y202000D01*
X108650Y201917D01*
X108942Y201708D01*
X109025Y201458D01*
X108983Y201208D01*
X108817Y201000D01*
X107983Y200583D01*
X107608Y200292D01*
X107358Y199875D01*
X107275Y199500D01*
X109025D01*
G01X100067Y210692D02*
X99817Y210817D01*
X99525Y210900D01*
X99192D01*
X98817Y210775D01*
X98525Y210567D01*
X98317Y210317D01*
X98150Y209900D01*
X98108Y209525D01*
X98192Y209150D01*
X98317Y208900D01*
X98567Y208650D01*
X98858Y208483D01*
X99150Y208400D01*
X99442D01*
X99733Y208483D01*
X99983Y208608D01*
X100192Y208775D01*
G01X101458Y209442D02*
X101750Y209733D01*
X102000Y209900D01*
X102333Y209983D01*
X102625Y209900D01*
X102833Y209733D01*
X103000Y209483D01*
X103042Y209192D01*
X103000Y208942D01*
X102833Y208692D01*
X102583Y208483D01*
X102292Y208400D01*
X101958Y208483D01*
X101667Y208733D01*
X101500Y209108D01*
X101458Y209525D01*
X101542Y210067D01*
X101667Y210358D01*
X101875Y210650D01*
X102167Y210858D01*
X102458Y210900D01*
X102750Y210817D01*
X102958Y210608D01*
G01X104433Y208775D02*
X104683Y208567D01*
X104975Y208442D01*
X105350Y208400D01*
X105725Y208483D01*
X106017Y208650D01*
X106225Y208942D01*
X106267Y209275D01*
X106183Y209608D01*
X105975Y209817D01*
X105683Y209983D01*
X105392Y210025D01*
X105100Y209983D01*
X104725Y209817D01*
X104850Y210900D01*
X105975D01*
G01X108450Y208400D02*
Y210900D01*
X107950Y210400D01*
G01Y208400D02*
X108950D01*
G01X99767Y206292D02*
X99517Y206417D01*
X99225Y206500D01*
X98892D01*
X98517Y206375D01*
X98225Y206167D01*
X98017Y205917D01*
X97850Y205500D01*
X97808Y205125D01*
X97892Y204750D01*
X98017Y204500D01*
X98267Y204250D01*
X98558Y204083D01*
X98850Y204000D01*
X99142D01*
X99433Y204083D01*
X99683Y204208D01*
X99892Y204375D01*
G01X101867Y204000D02*
X101950Y204542D01*
X102075Y205000D01*
X102242Y205417D01*
X102450Y205875D01*
X102783Y206500D01*
X101117D01*
G01X105050Y204000D02*
Y206500D01*
X104550Y206000D01*
G01Y204000D02*
X105550D01*
G01X108650D02*
Y206500D01*
X107108Y204708D01*
X109192D01*
G01X91834Y234067D02*
X89334D01*
Y235108D01*
X89459Y235442D01*
X89626Y235650D01*
X89959Y235733D01*
X90292Y235650D01*
X90501Y235400D01*
X90626Y235108D01*
Y234067D01*
G01Y235108D02*
X91834Y235733D01*
G01Y238000D02*
X89334D01*
X89834Y237500D01*
G01X91834D02*
Y238500D01*
G01X91542Y240392D02*
X91751Y240683D01*
X91834Y241017D01*
X91751Y241350D01*
X91501Y241642D01*
X91126Y241850D01*
X90751Y241933D01*
X90292D01*
X89917Y241850D01*
X89584Y241642D01*
X89417Y241392D01*
X89334Y241100D01*
X89417Y240767D01*
X89584Y240517D01*
X89834Y240350D01*
X90167Y240267D01*
X90459Y240350D01*
X90751Y240558D01*
X90917Y240808D01*
X90959Y241100D01*
X90876Y241433D01*
X90667Y241683D01*
X90292Y241933D01*
G01X93300Y229100D02*
X89300D01*
Y221700D01*
G01X98367Y194900D02*
Y197400D01*
X99408D01*
X99742Y197275D01*
X99950Y197108D01*
X100033Y196775D01*
X99950Y196442D01*
X99700Y196233D01*
X99408Y196108D01*
X98367D01*
G01X99408D02*
X100033Y194900D01*
G01X102300D02*
Y197400D01*
X101800Y196900D01*
G01Y194900D02*
X102800D01*
G01X105400D02*
X105692Y194942D01*
X106025Y195067D01*
X106233Y195275D01*
X106317Y195567D01*
X106233Y195858D01*
X105983Y196108D01*
X105608Y196233D01*
X105192D01*
X104942Y196317D01*
X104733Y196525D01*
X104650Y196817D01*
X104775Y197108D01*
X105067Y197317D01*
X105400Y197400D01*
X105733Y197317D01*
X106025Y197108D01*
X106150Y196817D01*
X106067Y196525D01*
X105858Y196317D01*
X105608Y196233D01*
X105192D01*
X104817Y196108D01*
X104567Y195858D01*
X104483Y195567D01*
X104567Y195275D01*
X104775Y195067D01*
X105108Y194942D01*
X105400Y194900D01*
G01X91000Y192900D02*
Y196900D01*
X83600D01*
G01X98367Y212800D02*
Y215300D01*
X99408D01*
X99742Y215175D01*
X99950Y215008D01*
X100033Y214675D01*
X99950Y214342D01*
X99700Y214133D01*
X99408Y214008D01*
X98367D01*
G01X99408D02*
X100033Y212800D01*
G01X102300D02*
Y215300D01*
X101800Y214800D01*
G01Y212800D02*
X102800D01*
G01X105317D02*
X105400Y213342D01*
X105525Y213800D01*
X105692Y214217D01*
X105900Y214675D01*
X106233Y215300D01*
X104567D01*
G01X89500Y211800D02*
Y215800D01*
X82100D01*
G01X122467Y192666D02*
Y190166D01*
X124133D01*
G01X125483Y190666D02*
X125733Y190374D01*
X126067Y190208D01*
X126442Y190166D01*
X126775Y190208D01*
X127108Y190416D01*
X127317Y190666D01*
X127358Y190916D01*
X127275Y191208D01*
X126983Y191416D01*
X126692Y191499D01*
X126317D01*
G01X126692D02*
X126942Y191624D01*
X127150Y191833D01*
X127233Y192083D01*
X127150Y192333D01*
X126942Y192541D01*
X126567Y192666D01*
X126192Y192624D01*
X125817Y192458D01*
G01X129500Y192666D02*
X129167Y192583D01*
X128917Y192374D01*
X128750Y192124D01*
X128625Y191791D01*
X128583Y191416D01*
X128625Y191041D01*
X128750Y190708D01*
X128917Y190458D01*
X129167Y190249D01*
X129500Y190166D01*
X129833Y190249D01*
X130083Y190458D01*
X130250Y190708D01*
X130375Y191041D01*
X130417Y191416D01*
X130375Y191791D01*
X130250Y192124D01*
X130083Y192374D01*
X129833Y192583D01*
X129500Y192666D01*
G01X122300Y178300D02*
X144900D01*
G01X122300Y188500D02*
Y178300D01*
G01X144900Y188500D02*
X122300D01*
G01Y178300D02*
X144900D01*
G01X122300Y188500D02*
Y178300D01*
G01X144900Y188500D02*
X122300D01*
G01X83313Y280195D02*
Y282695D01*
X84354D01*
X84688Y282570D01*
X84896Y282403D01*
X84979Y282070D01*
X84896Y281737D01*
X84646Y281528D01*
X84354Y281403D01*
X83313D01*
G01X84354D02*
X84979Y280195D01*
G01X86329Y280695D02*
X86579Y280403D01*
X86913Y280237D01*
X87288Y280195D01*
X87621Y280237D01*
X87954Y280445D01*
X88163Y280695D01*
X88204Y280945D01*
X88121Y281237D01*
X87829Y281445D01*
X87538Y281528D01*
X87163D01*
G01X87538D02*
X87788Y281653D01*
X87996Y281862D01*
X88079Y282112D01*
X87996Y282362D01*
X87788Y282570D01*
X87413Y282695D01*
X87038Y282653D01*
X86663Y282487D01*
G01X89429Y280570D02*
X89679Y280362D01*
X89971Y280237D01*
X90346Y280195D01*
X90721Y280278D01*
X91013Y280445D01*
X91221Y280737D01*
X91263Y281070D01*
X91179Y281403D01*
X90971Y281612D01*
X90679Y281778D01*
X90388Y281820D01*
X90096Y281778D01*
X89721Y281612D01*
X89846Y282695D01*
X90971D01*
G01X93946Y280195D02*
Y282695D01*
X92404Y280903D01*
X94488D01*
G01X83313Y275195D02*
Y277695D01*
X84354D01*
X84688Y277570D01*
X84896Y277403D01*
X84979Y277070D01*
X84896Y276737D01*
X84646Y276528D01*
X84354Y276403D01*
X83313D01*
G01X84354D02*
X84979Y275195D01*
G01X86329Y275695D02*
X86579Y275403D01*
X86913Y275237D01*
X87288Y275195D01*
X87621Y275237D01*
X87954Y275445D01*
X88163Y275695D01*
X88204Y275945D01*
X88121Y276237D01*
X87829Y276445D01*
X87538Y276528D01*
X87163D01*
G01X87538D02*
X87788Y276653D01*
X87996Y276862D01*
X88079Y277112D01*
X87996Y277362D01*
X87788Y277570D01*
X87413Y277695D01*
X87038Y277653D01*
X86663Y277487D01*
G01X89429Y275570D02*
X89679Y275362D01*
X89971Y275237D01*
X90346Y275195D01*
X90721Y275278D01*
X91013Y275445D01*
X91221Y275737D01*
X91263Y276070D01*
X91179Y276403D01*
X90971Y276612D01*
X90679Y276778D01*
X90388Y276820D01*
X90096Y276778D01*
X89721Y276612D01*
X89846Y277695D01*
X90971D01*
G01X92529Y275570D02*
X92779Y275362D01*
X93071Y275237D01*
X93446Y275195D01*
X93821Y275278D01*
X94113Y275445D01*
X94321Y275737D01*
X94363Y276070D01*
X94279Y276403D01*
X94071Y276612D01*
X93779Y276778D01*
X93488Y276820D01*
X93196Y276778D01*
X92821Y276612D01*
X92946Y277695D01*
X94071D01*
G01X83313Y285195D02*
Y287695D01*
X84354D01*
X84688Y287570D01*
X84896Y287403D01*
X84979Y287070D01*
X84896Y286737D01*
X84646Y286528D01*
X84354Y286403D01*
X83313D01*
G01X84354D02*
X84979Y285195D01*
G01X86329Y285695D02*
X86579Y285403D01*
X86913Y285237D01*
X87288Y285195D01*
X87621Y285237D01*
X87954Y285445D01*
X88163Y285695D01*
X88204Y285945D01*
X88121Y286237D01*
X87829Y286445D01*
X87538Y286528D01*
X87163D01*
G01X87538D02*
X87788Y286653D01*
X87996Y286862D01*
X88079Y287112D01*
X87996Y287362D01*
X87788Y287570D01*
X87413Y287695D01*
X87038Y287653D01*
X86663Y287487D01*
G01X89429Y285570D02*
X89679Y285362D01*
X89971Y285237D01*
X90346Y285195D01*
X90721Y285278D01*
X91013Y285445D01*
X91221Y285737D01*
X91263Y286070D01*
X91179Y286403D01*
X90971Y286612D01*
X90679Y286778D01*
X90388Y286820D01*
X90096Y286778D01*
X89721Y286612D01*
X89846Y287695D01*
X90971D01*
G01X92654Y286237D02*
X92946Y286528D01*
X93196Y286695D01*
X93529Y286778D01*
X93821Y286695D01*
X94029Y286528D01*
X94196Y286278D01*
X94238Y285987D01*
X94196Y285737D01*
X94029Y285487D01*
X93779Y285278D01*
X93488Y285195D01*
X93154Y285278D01*
X92863Y285528D01*
X92696Y285903D01*
X92654Y286320D01*
X92738Y286862D01*
X92863Y287153D01*
X93071Y287445D01*
X93363Y287653D01*
X93654Y287695D01*
X93946Y287612D01*
X94154Y287403D01*
G01X79334Y240017D02*
X76834D01*
Y241058D01*
X76959Y241392D01*
X77126Y241600D01*
X77459Y241683D01*
X77792Y241600D01*
X78001Y241350D01*
X78126Y241058D01*
Y240017D01*
G01Y241058D02*
X79334Y241683D01*
G01X78959Y243033D02*
X79167Y243283D01*
X79292Y243575D01*
X79334Y243950D01*
X79251Y244325D01*
X79084Y244617D01*
X78792Y244825D01*
X78459Y244867D01*
X78126Y244783D01*
X77917Y244575D01*
X77751Y244283D01*
X77709Y243992D01*
X77751Y243700D01*
X77917Y243325D01*
X76834Y243450D01*
Y244575D01*
G01X78834Y246133D02*
X79126Y246383D01*
X79292Y246717D01*
X79334Y247092D01*
X79292Y247425D01*
X79084Y247758D01*
X78834Y247967D01*
X78584Y248008D01*
X78292Y247925D01*
X78084Y247633D01*
X78001Y247342D01*
Y246967D01*
G01Y247342D02*
X77876Y247592D01*
X77667Y247800D01*
X77417Y247883D01*
X77167Y247800D01*
X76959Y247592D01*
X76834Y247217D01*
X76876Y246842D01*
X77042Y246467D01*
G01X78292Y249358D02*
X78001Y249650D01*
X77834Y249900D01*
X77751Y250233D01*
X77834Y250525D01*
X78001Y250733D01*
X78251Y250900D01*
X78542Y250942D01*
X78792Y250900D01*
X79042Y250733D01*
X79251Y250483D01*
X79334Y250192D01*
X79251Y249858D01*
X79001Y249567D01*
X78626Y249400D01*
X78209Y249358D01*
X77667Y249442D01*
X77376Y249567D01*
X77084Y249775D01*
X76876Y250067D01*
X76834Y250358D01*
X76917Y250650D01*
X77126Y250858D01*
G01X85167Y292492D02*
X84917Y292617D01*
X84625Y292700D01*
X84292D01*
X83917Y292575D01*
X83625Y292367D01*
X83417Y292117D01*
X83250Y291700D01*
X83208Y291325D01*
X83292Y290950D01*
X83417Y290700D01*
X83667Y290450D01*
X83958Y290283D01*
X84250Y290200D01*
X84542D01*
X84833Y290283D01*
X85083Y290408D01*
X85292Y290575D01*
G01X86433D02*
X86683Y290367D01*
X86975Y290242D01*
X87350Y290200D01*
X87725Y290283D01*
X88017Y290450D01*
X88225Y290742D01*
X88267Y291075D01*
X88183Y291408D01*
X87975Y291617D01*
X87683Y291783D01*
X87392Y291825D01*
X87100Y291783D01*
X86725Y291617D01*
X86850Y292700D01*
X87975D01*
G01X89533Y290700D02*
X89783Y290408D01*
X90117Y290242D01*
X90492Y290200D01*
X90825Y290242D01*
X91158Y290450D01*
X91367Y290700D01*
X91408Y290950D01*
X91325Y291242D01*
X91033Y291450D01*
X90742Y291533D01*
X90367D01*
G01X90742D02*
X90992Y291658D01*
X91200Y291867D01*
X91283Y292117D01*
X91200Y292367D01*
X90992Y292575D01*
X90617Y292700D01*
X90242Y292658D01*
X89867Y292492D01*
G01X93550Y292700D02*
X93217Y292617D01*
X92967Y292408D01*
X92800Y292158D01*
X92675Y291825D01*
X92633Y291450D01*
X92675Y291075D01*
X92800Y290742D01*
X92967Y290492D01*
X93217Y290283D01*
X93550Y290200D01*
X93883Y290283D01*
X94133Y290492D01*
X94300Y290742D01*
X94425Y291075D01*
X94467Y291450D01*
X94425Y291825D01*
X94300Y292158D01*
X94133Y292408D01*
X93883Y292617D01*
X93550Y292700D01*
G01X83017Y312000D02*
Y314500D01*
X84058D01*
X84392Y314375D01*
X84600Y314208D01*
X84683Y313875D01*
X84600Y313542D01*
X84350Y313333D01*
X84058Y313208D01*
X83017D01*
G01X84058D02*
X84683Y312000D01*
G01X86033Y312500D02*
X86283Y312208D01*
X86617Y312042D01*
X86992Y312000D01*
X87325Y312042D01*
X87658Y312250D01*
X87867Y312500D01*
X87908Y312750D01*
X87825Y313042D01*
X87533Y313250D01*
X87242Y313333D01*
X86867D01*
G01X87242D02*
X87492Y313458D01*
X87700Y313667D01*
X87783Y313917D01*
X87700Y314167D01*
X87492Y314375D01*
X87117Y314500D01*
X86742Y314458D01*
X86367Y314292D01*
G01X90550Y312000D02*
Y314500D01*
X89008Y312708D01*
X91092D01*
G01X93150Y312000D02*
Y314500D01*
X92650Y314000D01*
G01Y312000D02*
X93650D01*
G01X83217Y307500D02*
Y310000D01*
X84258D01*
X84592Y309875D01*
X84800Y309708D01*
X84883Y309375D01*
X84800Y309042D01*
X84550Y308833D01*
X84258Y308708D01*
X83217D01*
G01X84258D02*
X84883Y307500D01*
G01X86233Y308000D02*
X86483Y307708D01*
X86817Y307542D01*
X87192Y307500D01*
X87525Y307542D01*
X87858Y307750D01*
X88067Y308000D01*
X88108Y308250D01*
X88025Y308542D01*
X87733Y308750D01*
X87442Y308833D01*
X87067D01*
G01X87442D02*
X87692Y308958D01*
X87900Y309167D01*
X87983Y309417D01*
X87900Y309667D01*
X87692Y309875D01*
X87317Y310000D01*
X86942Y309958D01*
X86567Y309792D01*
G01X90750Y307500D02*
Y310000D01*
X89208Y308208D01*
X91292D01*
G01X93267Y307500D02*
X93350Y308042D01*
X93475Y308500D01*
X93642Y308917D01*
X93850Y309375D01*
X94183Y310000D01*
X92517D01*
G01X83217Y302500D02*
Y305000D01*
X84258D01*
X84592Y304875D01*
X84800Y304708D01*
X84883Y304375D01*
X84800Y304042D01*
X84550Y303833D01*
X84258Y303708D01*
X83217D01*
G01X84258D02*
X84883Y302500D01*
G01X86233Y303000D02*
X86483Y302708D01*
X86817Y302542D01*
X87192Y302500D01*
X87525Y302542D01*
X87858Y302750D01*
X88067Y303000D01*
X88108Y303250D01*
X88025Y303542D01*
X87733Y303750D01*
X87442Y303833D01*
X87067D01*
G01X87442D02*
X87692Y303958D01*
X87900Y304167D01*
X87983Y304417D01*
X87900Y304667D01*
X87692Y304875D01*
X87317Y305000D01*
X86942Y304958D01*
X86567Y304792D01*
G01X89333Y302875D02*
X89583Y302667D01*
X89875Y302542D01*
X90250Y302500D01*
X90625Y302583D01*
X90917Y302750D01*
X91125Y303042D01*
X91167Y303375D01*
X91083Y303708D01*
X90875Y303917D01*
X90583Y304083D01*
X90292Y304125D01*
X90000Y304083D01*
X89625Y303917D01*
X89750Y305000D01*
X90875D01*
G01X93350Y302500D02*
Y305000D01*
X92850Y304500D01*
G01Y302500D02*
X93850D01*
G01X135067Y361251D02*
Y363751D01*
X136108D01*
X136442Y363626D01*
X136650Y363459D01*
X136733Y363126D01*
X136650Y362793D01*
X136400Y362584D01*
X136108Y362459D01*
X135067D01*
G01X136108D02*
X136733Y361251D01*
G01X139500D02*
Y363751D01*
X137958Y361959D01*
X140042D01*
G01X142100Y361251D02*
Y363751D01*
X141600Y363251D01*
G01Y361251D02*
X142600D01*
G01X145200Y363751D02*
X144867Y363668D01*
X144617Y363459D01*
X144450Y363209D01*
X144325Y362876D01*
X144283Y362501D01*
X144325Y362126D01*
X144450Y361793D01*
X144617Y361543D01*
X144867Y361334D01*
X145200Y361251D01*
X145533Y361334D01*
X145783Y361543D01*
X145950Y361793D01*
X146075Y362126D01*
X146117Y362501D01*
X146075Y362876D01*
X145950Y363209D01*
X145783Y363459D01*
X145533Y363668D01*
X145200Y363751D01*
G01X133500Y361517D02*
X131000D01*
Y362558D01*
X131125Y362892D01*
X131292Y363100D01*
X131625Y363183D01*
X131958Y363100D01*
X132167Y362850D01*
X132292Y362558D01*
Y361517D01*
G01Y362558D02*
X133500Y363183D01*
G01Y365950D02*
X131000D01*
X132792Y364408D01*
Y366492D01*
G01X133000Y367633D02*
X133292Y367883D01*
X133458Y368217D01*
X133500Y368592D01*
X133458Y368925D01*
X133250Y369258D01*
X133000Y369467D01*
X132750Y369508D01*
X132458Y369425D01*
X132250Y369133D01*
X132167Y368842D01*
Y368467D01*
G01Y368842D02*
X132042Y369092D01*
X131833Y369300D01*
X131583Y369383D01*
X131333Y369300D01*
X131125Y369092D01*
X131000Y368717D01*
X131042Y368342D01*
X131208Y367967D01*
G01X133500Y371650D02*
X131000D01*
X131500Y371150D01*
G01X133500D02*
Y372150D01*
G01X129500Y361517D02*
X127000D01*
Y362558D01*
X127125Y362892D01*
X127292Y363100D01*
X127625Y363183D01*
X127958Y363100D01*
X128167Y362850D01*
X128292Y362558D01*
Y361517D01*
G01Y362558D02*
X129500Y363183D01*
G01Y365950D02*
X127000D01*
X128792Y364408D01*
Y366492D01*
G01X129000Y367633D02*
X129292Y367883D01*
X129458Y368217D01*
X129500Y368592D01*
X129458Y368925D01*
X129250Y369258D01*
X129000Y369467D01*
X128750Y369508D01*
X128458Y369425D01*
X128250Y369133D01*
X128167Y368842D01*
Y368467D01*
G01Y368842D02*
X128042Y369092D01*
X127833Y369300D01*
X127583Y369383D01*
X127333Y369300D01*
X127125Y369092D01*
X127000Y368717D01*
X127042Y368342D01*
X127208Y367967D01*
G01X127417Y370858D02*
X127167Y371108D01*
X127042Y371400D01*
X127000Y371733D01*
X127083Y372150D01*
X127292Y372442D01*
X127542Y372525D01*
X127792Y372483D01*
X128000Y372317D01*
X128417Y371483D01*
X128708Y371108D01*
X129125Y370858D01*
X129500Y370775D01*
Y372525D01*
G01X114067Y361467D02*
Y363967D01*
X115108D01*
X115442Y363842D01*
X115650Y363675D01*
X115733Y363342D01*
X115650Y363009D01*
X115400Y362800D01*
X115108Y362675D01*
X114067D01*
G01X115108D02*
X115733Y361467D01*
G01X118500D02*
Y363967D01*
X116958Y362175D01*
X119042D01*
G01X120183Y361967D02*
X120433Y361675D01*
X120767Y361509D01*
X121142Y361467D01*
X121475Y361509D01*
X121808Y361717D01*
X122017Y361967D01*
X122058Y362217D01*
X121975Y362509D01*
X121683Y362717D01*
X121392Y362800D01*
X121017D01*
G01X121392D02*
X121642Y362925D01*
X121850Y363134D01*
X121933Y363384D01*
X121850Y363634D01*
X121642Y363842D01*
X121267Y363967D01*
X120892Y363925D01*
X120517Y363759D01*
G01X124700Y361467D02*
Y363967D01*
X123158Y362175D01*
X125242D01*
G01X84367Y318992D02*
X84117Y319117D01*
X83825Y319200D01*
X83492D01*
X83117Y319075D01*
X82825Y318867D01*
X82617Y318617D01*
X82450Y318200D01*
X82408Y317825D01*
X82492Y317450D01*
X82617Y317200D01*
X82867Y316950D01*
X83158Y316783D01*
X83450Y316700D01*
X83742D01*
X84033Y316783D01*
X84283Y316908D01*
X84492Y317075D01*
G01X85633D02*
X85883Y316867D01*
X86175Y316742D01*
X86550Y316700D01*
X86925Y316783D01*
X87217Y316950D01*
X87425Y317242D01*
X87467Y317575D01*
X87383Y317908D01*
X87175Y318117D01*
X86883Y318283D01*
X86592Y318325D01*
X86300Y318283D01*
X85925Y318117D01*
X86050Y319200D01*
X87175D01*
G01X88858Y318783D02*
X89108Y319033D01*
X89400Y319158D01*
X89733Y319200D01*
X90150Y319117D01*
X90442Y318908D01*
X90525Y318658D01*
X90483Y318408D01*
X90317Y318200D01*
X89483Y317783D01*
X89108Y317492D01*
X88858Y317075D01*
X88775Y316700D01*
X90525D01*
G01X92750D02*
X93042Y316742D01*
X93375Y316867D01*
X93583Y317075D01*
X93667Y317367D01*
X93583Y317658D01*
X93333Y317908D01*
X92958Y318033D01*
X92542D01*
X92292Y318117D01*
X92083Y318325D01*
X92000Y318617D01*
X92125Y318908D01*
X92417Y319117D01*
X92750Y319200D01*
X93083Y319117D01*
X93375Y318908D01*
X93500Y318617D01*
X93417Y318325D01*
X93208Y318117D01*
X92958Y318033D01*
X92542D01*
X92167Y317908D01*
X91917Y317658D01*
X91833Y317367D01*
X91917Y317075D01*
X92125Y316867D01*
X92458Y316742D01*
X92750Y316700D01*
G01X84067Y323492D02*
X83817Y323617D01*
X83525Y323700D01*
X83192D01*
X82817Y323575D01*
X82525Y323367D01*
X82317Y323117D01*
X82150Y322700D01*
X82108Y322325D01*
X82192Y321950D01*
X82317Y321700D01*
X82567Y321450D01*
X82858Y321283D01*
X83150Y321200D01*
X83442D01*
X83733Y321283D01*
X83983Y321408D01*
X84192Y321575D01*
G01X85333D02*
X85583Y321367D01*
X85875Y321242D01*
X86250Y321200D01*
X86625Y321283D01*
X86917Y321450D01*
X87125Y321742D01*
X87167Y322075D01*
X87083Y322408D01*
X86875Y322617D01*
X86583Y322783D01*
X86292Y322825D01*
X86000Y322783D01*
X85625Y322617D01*
X85750Y323700D01*
X86875D01*
G01X88558Y323283D02*
X88808Y323533D01*
X89100Y323658D01*
X89433Y323700D01*
X89850Y323617D01*
X90142Y323408D01*
X90225Y323158D01*
X90183Y322908D01*
X90017Y322700D01*
X89183Y322283D01*
X88808Y321992D01*
X88558Y321575D01*
X88475Y321200D01*
X90225D01*
G01X91742Y321492D02*
X92033Y321283D01*
X92367Y321200D01*
X92700Y321283D01*
X92992Y321533D01*
X93200Y321908D01*
X93283Y322283D01*
Y322742D01*
X93200Y323117D01*
X92992Y323450D01*
X92742Y323617D01*
X92450Y323700D01*
X92117Y323617D01*
X91867Y323450D01*
X91700Y323200D01*
X91617Y322867D01*
X91700Y322575D01*
X91908Y322283D01*
X92158Y322117D01*
X92450Y322075D01*
X92783Y322158D01*
X93033Y322367D01*
X93283Y322742D01*
G01X86041Y337767D02*
X85916Y337517D01*
X85833Y337225D01*
Y336892D01*
X85958Y336517D01*
X86166Y336225D01*
X86416Y336017D01*
X86833Y335850D01*
X87208Y335808D01*
X87583Y335892D01*
X87833Y336017D01*
X88083Y336267D01*
X88250Y336558D01*
X88333Y336850D01*
Y337142D01*
X88250Y337433D01*
X88125Y337683D01*
X87958Y337892D01*
G01Y339033D02*
X88166Y339283D01*
X88291Y339575D01*
X88333Y339950D01*
X88250Y340325D01*
X88083Y340617D01*
X87791Y340825D01*
X87458Y340867D01*
X87125Y340783D01*
X86916Y340575D01*
X86750Y340283D01*
X86708Y339992D01*
X86750Y339700D01*
X86916Y339325D01*
X85833Y339450D01*
Y340575D01*
G01X88333Y342967D02*
X87791Y343050D01*
X87333Y343175D01*
X86916Y343342D01*
X86458Y343550D01*
X85833Y343883D01*
Y342217D01*
G01X88333Y346150D02*
X85833D01*
X86333Y345650D01*
G01X88333D02*
Y346650D01*
G01X79205Y353107D02*
Y348507D01*
G01X85600Y349583D02*
X87392D01*
X87767Y349750D01*
X88017Y350083D01*
X88100Y350500D01*
X88017Y350917D01*
X87767Y351250D01*
X87392Y351417D01*
X85600D01*
G01X88100Y354100D02*
X85600D01*
X87392Y352558D01*
Y354642D01*
G01X87058Y355908D02*
X86767Y356200D01*
X86600Y356450D01*
X86517Y356783D01*
X86600Y357075D01*
X86767Y357283D01*
X87017Y357450D01*
X87308Y357492D01*
X87558Y357450D01*
X87808Y357283D01*
X88017Y357033D01*
X88100Y356742D01*
X88017Y356408D01*
X87767Y356117D01*
X87392Y355950D01*
X86975Y355908D01*
X86433Y355992D01*
X86142Y356117D01*
X85850Y356325D01*
X85642Y356617D01*
X85600Y356908D01*
X85683Y357200D01*
X85892Y357408D01*
G01X100300Y348300D02*
X90100D01*
G01X100300Y352900D02*
Y348300D01*
G01X89400Y352900D02*
X100300D01*
G01X89400D02*
Y341600D01*
G01X90600Y350600D02*
X89400Y351800D01*
G01X90600Y350600D02*
X89400Y349400D01*
G01X80707Y400395D02*
Y390395D01*
G01X95000Y399517D02*
X92500D01*
Y400558D01*
X92625Y400892D01*
X92792Y401100D01*
X93125Y401183D01*
X93458Y401100D01*
X93667Y400850D01*
X93792Y400558D01*
Y399517D01*
G01Y400558D02*
X95000Y401183D01*
G01X94625Y402533D02*
X94833Y402783D01*
X94958Y403075D01*
X95000Y403450D01*
X94917Y403825D01*
X94750Y404117D01*
X94458Y404325D01*
X94125Y404367D01*
X93792Y404283D01*
X93583Y404075D01*
X93417Y403783D01*
X93375Y403492D01*
X93417Y403200D01*
X93583Y402825D01*
X92500Y402950D01*
Y404075D01*
G01X94625Y405633D02*
X94833Y405883D01*
X94958Y406175D01*
X95000Y406550D01*
X94917Y406925D01*
X94750Y407217D01*
X94458Y407425D01*
X94125Y407467D01*
X93792Y407383D01*
X93583Y407175D01*
X93417Y406883D01*
X93375Y406592D01*
X93417Y406300D01*
X93583Y405925D01*
X92500Y406050D01*
Y407175D01*
G01X95000Y409650D02*
X94958Y409942D01*
X94833Y410275D01*
X94625Y410483D01*
X94333Y410567D01*
X94042Y410483D01*
X93792Y410233D01*
X93667Y409858D01*
Y409442D01*
X93583Y409192D01*
X93375Y408983D01*
X93083Y408900D01*
X92792Y409025D01*
X92583Y409317D01*
X92500Y409650D01*
X92583Y409983D01*
X92792Y410275D01*
X93083Y410400D01*
X93375Y410317D01*
X93583Y410108D01*
X93667Y409858D01*
Y409442D01*
X93792Y409067D01*
X94042Y408817D01*
X94333Y408733D01*
X94625Y408817D01*
X94833Y409025D01*
X94958Y409358D01*
X95000Y409650D01*
G01X95700Y396600D02*
X91700D01*
Y389200D01*
G01X137634Y365917D02*
X135134D01*
Y366958D01*
X135259Y367292D01*
X135426Y367500D01*
X135759Y367583D01*
X136092Y367500D01*
X136301Y367250D01*
X136426Y366958D01*
Y365917D01*
G01Y366958D02*
X137634Y367583D01*
G01Y370350D02*
X135134D01*
X136926Y368808D01*
Y370892D01*
G01X137634Y372950D02*
X135134D01*
X135634Y372450D01*
G01X137634D02*
Y373450D01*
G01Y376050D02*
X135134D01*
X135634Y375550D01*
G01X137634D02*
Y376550D01*
G01X83795Y369726D02*
X87795D01*
Y377126D01*
G01X116633Y365817D02*
X114133D01*
Y366858D01*
X114258Y367192D01*
X114425Y367400D01*
X114758Y367483D01*
X115091Y367400D01*
X115300Y367150D01*
X115425Y366858D01*
Y365817D01*
G01Y366858D02*
X116633Y367483D01*
G01Y370250D02*
X114133D01*
X115925Y368708D01*
Y370792D01*
G01X114550Y372058D02*
X114300Y372308D01*
X114175Y372600D01*
X114133Y372933D01*
X114216Y373350D01*
X114425Y373642D01*
X114675Y373725D01*
X114925Y373683D01*
X115133Y373517D01*
X115550Y372683D01*
X115841Y372308D01*
X116258Y372058D01*
X116633Y371975D01*
Y373725D01*
G01X115591Y375158D02*
X115300Y375450D01*
X115133Y375700D01*
X115050Y376033D01*
X115133Y376325D01*
X115300Y376533D01*
X115550Y376700D01*
X115841Y376742D01*
X116091Y376700D01*
X116341Y376533D01*
X116550Y376283D01*
X116633Y375992D01*
X116550Y375658D01*
X116300Y375367D01*
X115925Y375200D01*
X115508Y375158D01*
X114966Y375242D01*
X114675Y375367D01*
X114383Y375575D01*
X114175Y375867D01*
X114133Y376158D01*
X114216Y376450D01*
X114425Y376658D01*
G01X83300Y372500D02*
X79300D01*
Y365100D01*
G01X112500Y366017D02*
X110000D01*
Y367058D01*
X110125Y367392D01*
X110292Y367600D01*
X110625Y367683D01*
X110958Y367600D01*
X111167Y367350D01*
X111292Y367058D01*
Y366017D01*
G01Y367058D02*
X112500Y367683D01*
G01Y370450D02*
X110000D01*
X111792Y368908D01*
Y370992D01*
G01X112500Y373050D02*
X110000D01*
X110500Y372550D01*
G01X112500D02*
Y373550D01*
G01X112000Y375233D02*
X112292Y375483D01*
X112458Y375817D01*
X112500Y376192D01*
X112458Y376525D01*
X112250Y376858D01*
X112000Y377067D01*
X111750Y377108D01*
X111458Y377025D01*
X111250Y376733D01*
X111167Y376442D01*
Y376067D01*
G01Y376442D02*
X111042Y376692D01*
X110833Y376900D01*
X110583Y376983D01*
X110333Y376900D01*
X110125Y376692D01*
X110000Y376317D01*
X110042Y375942D01*
X110208Y375567D01*
G01X109000Y366017D02*
X106500D01*
Y367058D01*
X106625Y367392D01*
X106792Y367600D01*
X107125Y367683D01*
X107458Y367600D01*
X107667Y367350D01*
X107792Y367058D01*
Y366017D01*
G01Y367058D02*
X109000Y367683D01*
G01Y370450D02*
X106500D01*
X108292Y368908D01*
Y370992D01*
G01X109000Y373050D02*
X106500D01*
X107000Y372550D01*
G01X109000D02*
Y373550D01*
G01Y376650D02*
X106500D01*
X108292Y375108D01*
Y377192D01*
G01X124200Y365750D02*
X121700D01*
Y366791D01*
X121825Y367125D01*
X121992Y367333D01*
X122325Y367416D01*
X122658Y367333D01*
X122867Y367083D01*
X122992Y366791D01*
Y365750D01*
G01Y366791D02*
X124200Y367416D01*
G01Y370183D02*
X121700D01*
X123492Y368641D01*
Y370725D01*
G01X123700Y371866D02*
X123992Y372116D01*
X124158Y372450D01*
X124200Y372825D01*
X124158Y373158D01*
X123950Y373491D01*
X123700Y373700D01*
X123450Y373741D01*
X123158Y373658D01*
X122950Y373366D01*
X122867Y373075D01*
Y372700D01*
G01Y373075D02*
X122742Y373325D01*
X122533Y373533D01*
X122283Y373616D01*
X122033Y373533D01*
X121825Y373325D01*
X121700Y372950D01*
X121742Y372575D01*
X121908Y372200D01*
G01X121700Y375883D02*
X121783Y375550D01*
X121992Y375300D01*
X122242Y375133D01*
X122575Y375008D01*
X122950Y374966D01*
X123325Y375008D01*
X123658Y375133D01*
X123908Y375300D01*
X124117Y375550D01*
X124200Y375883D01*
X124117Y376216D01*
X123908Y376466D01*
X123658Y376633D01*
X123325Y376758D01*
X122950Y376800D01*
X122575Y376758D01*
X122242Y376633D01*
X121992Y376466D01*
X121783Y376216D01*
X121700Y375883D01*
G01X84445Y369626D02*
Y365626D01*
X91845D01*
G01X100295Y372293D02*
X96295D01*
Y364893D01*
G01X91695Y369726D02*
X95695D01*
Y377126D01*
G01X104395Y372293D02*
X100395D01*
Y364893D01*
G01X91000Y399517D02*
X88500D01*
Y400558D01*
X88625Y400892D01*
X88792Y401100D01*
X89125Y401183D01*
X89458Y401100D01*
X89667Y400850D01*
X89792Y400558D01*
Y399517D01*
G01Y400558D02*
X91000Y401183D01*
G01X90625Y402533D02*
X90833Y402783D01*
X90958Y403075D01*
X91000Y403450D01*
X90917Y403825D01*
X90750Y404117D01*
X90458Y404325D01*
X90125Y404367D01*
X89792Y404283D01*
X89583Y404075D01*
X89417Y403783D01*
X89375Y403492D01*
X89417Y403200D01*
X89583Y402825D01*
X88500Y402950D01*
Y404075D01*
G01X90500Y405633D02*
X90792Y405883D01*
X90958Y406217D01*
X91000Y406592D01*
X90958Y406925D01*
X90750Y407258D01*
X90500Y407467D01*
X90250Y407508D01*
X89958Y407425D01*
X89750Y407133D01*
X89667Y406842D01*
Y406467D01*
G01Y406842D02*
X89542Y407092D01*
X89333Y407300D01*
X89083Y407383D01*
X88833Y407300D01*
X88625Y407092D01*
X88500Y406717D01*
X88542Y406342D01*
X88708Y405967D01*
G01X90500Y408733D02*
X90792Y408983D01*
X90958Y409317D01*
X91000Y409692D01*
X90958Y410025D01*
X90750Y410358D01*
X90500Y410567D01*
X90250Y410608D01*
X89958Y410525D01*
X89750Y410233D01*
X89667Y409942D01*
Y409567D01*
G01Y409942D02*
X89542Y410192D01*
X89333Y410400D01*
X89083Y410483D01*
X88833Y410400D01*
X88625Y410192D01*
X88500Y409817D01*
X88542Y409442D01*
X88708Y409067D01*
G01X87600Y389200D02*
X91600D01*
Y396600D01*
G01X118108Y367500D02*
X117983Y367250D01*
X117900Y366958D01*
Y366625D01*
X118025Y366250D01*
X118233Y365958D01*
X118483Y365750D01*
X118900Y365583D01*
X119275Y365541D01*
X119650Y365625D01*
X119900Y365750D01*
X120150Y366000D01*
X120317Y366291D01*
X120400Y366583D01*
Y366875D01*
X120317Y367166D01*
X120192Y367416D01*
X120025Y367625D01*
G01Y368766D02*
X120233Y369016D01*
X120358Y369308D01*
X120400Y369683D01*
X120317Y370058D01*
X120150Y370350D01*
X119858Y370558D01*
X119525Y370600D01*
X119192Y370516D01*
X118983Y370308D01*
X118817Y370016D01*
X118775Y369725D01*
X118817Y369433D01*
X118983Y369058D01*
X117900Y369183D01*
Y370308D01*
G01X119358Y371991D02*
X119067Y372283D01*
X118900Y372533D01*
X118817Y372866D01*
X118900Y373158D01*
X119067Y373366D01*
X119317Y373533D01*
X119608Y373575D01*
X119858Y373533D01*
X120108Y373366D01*
X120317Y373116D01*
X120400Y372825D01*
X120317Y372491D01*
X120067Y372200D01*
X119692Y372033D01*
X119275Y371991D01*
X118733Y372075D01*
X118442Y372200D01*
X118150Y372408D01*
X117942Y372700D01*
X117900Y372991D01*
X117983Y373283D01*
X118192Y373491D01*
G01X117900Y375883D02*
X117983Y375550D01*
X118192Y375300D01*
X118442Y375133D01*
X118775Y375008D01*
X119150Y374966D01*
X119525Y375008D01*
X119858Y375133D01*
X120108Y375300D01*
X120317Y375550D01*
X120400Y375883D01*
X120317Y376216D01*
X120108Y376466D01*
X119858Y376633D01*
X119525Y376758D01*
X119150Y376800D01*
X118775Y376758D01*
X118442Y376633D01*
X118192Y376466D01*
X117983Y376216D01*
X117900Y375883D01*
G01X107867Y453292D02*
X107617Y453417D01*
X107325Y453500D01*
X106992D01*
X106617Y453375D01*
X106325Y453167D01*
X106117Y452917D01*
X105950Y452500D01*
X105908Y452125D01*
X105992Y451750D01*
X106117Y451500D01*
X106367Y451250D01*
X106658Y451083D01*
X106950Y451000D01*
X107242D01*
X107533Y451083D01*
X107783Y451208D01*
X107992Y451375D01*
G01X109133D02*
X109383Y451167D01*
X109675Y451042D01*
X110050Y451000D01*
X110425Y451083D01*
X110717Y451250D01*
X110925Y451542D01*
X110967Y451875D01*
X110883Y452208D01*
X110675Y452417D01*
X110383Y452583D01*
X110092Y452625D01*
X109800Y452583D01*
X109425Y452417D01*
X109550Y453500D01*
X110675D01*
G01X112358Y453083D02*
X112608Y453333D01*
X112900Y453458D01*
X113233Y453500D01*
X113650Y453417D01*
X113942Y453208D01*
X114025Y452958D01*
X113983Y452708D01*
X113817Y452500D01*
X112983Y452083D01*
X112608Y451792D01*
X112358Y451375D01*
X112275Y451000D01*
X114025D01*
G01X115333Y451500D02*
X115583Y451208D01*
X115917Y451042D01*
X116292Y451000D01*
X116625Y451042D01*
X116958Y451250D01*
X117167Y451500D01*
X117208Y451750D01*
X117125Y452042D01*
X116833Y452250D01*
X116542Y452333D01*
X116167D01*
G01X116542D02*
X116792Y452458D01*
X117000Y452667D01*
X117083Y452917D01*
X117000Y453167D01*
X116792Y453375D01*
X116417Y453500D01*
X116042Y453458D01*
X115667Y453292D01*
G01X84310Y468441D02*
X86110D01*
Y472441D01*
X84310D01*
G01X151910Y487241D02*
X84310D01*
Y457641D01*
X151910D01*
Y487241D01*
G01X138183Y491700D02*
Y494200D01*
X139017D01*
X139350Y494075D01*
X139600Y493908D01*
X139808Y493658D01*
X139975Y493367D01*
X140017Y492950D01*
X139975Y492533D01*
X139808Y492242D01*
X139600Y491992D01*
X139350Y491825D01*
X139017Y491700D01*
X138183D01*
G01X142533Y493033D02*
X142700Y493158D01*
X142825Y493367D01*
X142908Y493658D01*
X142825Y493908D01*
X142658Y494075D01*
X142367Y494200D01*
X141242D01*
Y491700D01*
X142617D01*
X142908Y491867D01*
X143075Y492117D01*
X143158Y492408D01*
X143075Y492700D01*
X142825Y492950D01*
X142533Y493033D01*
X141242D01*
G01X145300Y491700D02*
Y494200D01*
X144800Y493700D01*
G01Y491700D02*
X145800D01*
G01X143817Y103000D02*
Y105500D01*
X144858D01*
X145192Y105375D01*
X145400Y105208D01*
X145483Y104875D01*
X145400Y104542D01*
X145150Y104333D01*
X144858Y104208D01*
X143817D01*
G01X144858D02*
X145483Y103000D01*
G01X148250D02*
Y105500D01*
X146708Y103708D01*
X148792D01*
G01X150850Y105500D02*
X150517Y105417D01*
X150267Y105208D01*
X150100Y104958D01*
X149975Y104625D01*
X149933Y104250D01*
X149975Y103875D01*
X150100Y103542D01*
X150267Y103292D01*
X150517Y103083D01*
X150850Y103000D01*
X151183Y103083D01*
X151433Y103292D01*
X151600Y103542D01*
X151725Y103875D01*
X151767Y104250D01*
X151725Y104625D01*
X151600Y104958D01*
X151433Y105208D01*
X151183Y105417D01*
X150850Y105500D01*
G01X153158Y104042D02*
X153450Y104333D01*
X153700Y104500D01*
X154033Y104583D01*
X154325Y104500D01*
X154533Y104333D01*
X154700Y104083D01*
X154742Y103792D01*
X154700Y103542D01*
X154533Y103292D01*
X154283Y103083D01*
X153992Y103000D01*
X153658Y103083D01*
X153367Y103333D01*
X153200Y103708D01*
X153158Y104125D01*
X153242Y104667D01*
X153367Y104958D01*
X153575Y105250D01*
X153867Y105458D01*
X154158Y105500D01*
X154450Y105417D01*
X154658Y105208D01*
G01X158570Y106310D02*
Y102310D01*
X165970D01*
G01X199139Y112695D02*
X203139D01*
Y120095D01*
G01X184817Y93667D02*
Y96167D01*
X185858D01*
X186192Y96042D01*
X186400Y95875D01*
X186483Y95542D01*
X186400Y95209D01*
X186150Y95000D01*
X185858Y94875D01*
X184817D01*
G01X185858D02*
X186483Y93667D01*
G01X189250D02*
Y96167D01*
X187708Y94375D01*
X189792D01*
G01X191767Y93667D02*
X191850Y94209D01*
X191975Y94667D01*
X192142Y95084D01*
X192350Y95542D01*
X192683Y96167D01*
X191017D01*
G01X194867Y93667D02*
X194950Y94209D01*
X195075Y94667D01*
X195242Y95084D01*
X195450Y95542D01*
X195783Y96167D01*
X194117D01*
G01X181600Y112000D02*
Y108000D01*
X189000D01*
G01X172037Y93980D02*
Y96480D01*
X173078D01*
X173412Y96355D01*
X173620Y96188D01*
X173703Y95855D01*
X173620Y95522D01*
X173370Y95313D01*
X173078Y95188D01*
X172037D01*
G01X173078D02*
X173703Y93980D01*
G01X175053Y94480D02*
X175303Y94188D01*
X175637Y94022D01*
X176012Y93980D01*
X176345Y94022D01*
X176678Y94230D01*
X176887Y94480D01*
X176928Y94730D01*
X176845Y95022D01*
X176553Y95230D01*
X176262Y95313D01*
X175887D01*
G01X176262D02*
X176512Y95438D01*
X176720Y95647D01*
X176803Y95897D01*
X176720Y96147D01*
X176512Y96355D01*
X176137Y96480D01*
X175762Y96438D01*
X175387Y96272D01*
G01X178362Y94272D02*
X178653Y94063D01*
X178987Y93980D01*
X179320Y94063D01*
X179612Y94313D01*
X179820Y94688D01*
X179903Y95063D01*
Y95522D01*
X179820Y95897D01*
X179612Y96230D01*
X179362Y96397D01*
X179070Y96480D01*
X178737Y96397D01*
X178487Y96230D01*
X178320Y95980D01*
X178237Y95647D01*
X178320Y95355D01*
X178528Y95063D01*
X178778Y94897D01*
X179070Y94855D01*
X179403Y94938D01*
X179653Y95147D01*
X179903Y95522D01*
G01X181462Y94272D02*
X181753Y94063D01*
X182087Y93980D01*
X182420Y94063D01*
X182712Y94313D01*
X182920Y94688D01*
X183003Y95063D01*
Y95522D01*
X182920Y95897D01*
X182712Y96230D01*
X182462Y96397D01*
X182170Y96480D01*
X181837Y96397D01*
X181587Y96230D01*
X181420Y95980D01*
X181337Y95647D01*
X181420Y95355D01*
X181628Y95063D01*
X181878Y94897D01*
X182170Y94855D01*
X182503Y94938D01*
X182753Y95147D01*
X183003Y95522D01*
G01X174100Y112000D02*
Y108000D01*
X181500D01*
G01X166037Y98480D02*
Y100980D01*
X167078D01*
X167412Y100855D01*
X167620Y100688D01*
X167703Y100355D01*
X167620Y100022D01*
X167370Y99813D01*
X167078Y99688D01*
X166037D01*
G01X167078D02*
X167703Y98480D01*
G01X169053Y98980D02*
X169303Y98688D01*
X169637Y98522D01*
X170012Y98480D01*
X170345Y98522D01*
X170678Y98730D01*
X170887Y98980D01*
X170928Y99230D01*
X170845Y99522D01*
X170553Y99730D01*
X170262Y99813D01*
X169887D01*
G01X170262D02*
X170512Y99938D01*
X170720Y100147D01*
X170803Y100397D01*
X170720Y100647D01*
X170512Y100855D01*
X170137Y100980D01*
X169762Y100938D01*
X169387Y100772D01*
G01X172362Y98772D02*
X172653Y98563D01*
X172987Y98480D01*
X173320Y98563D01*
X173612Y98813D01*
X173820Y99188D01*
X173903Y99563D01*
Y100022D01*
X173820Y100397D01*
X173612Y100730D01*
X173362Y100897D01*
X173070Y100980D01*
X172737Y100897D01*
X172487Y100730D01*
X172320Y100480D01*
X172237Y100147D01*
X172320Y99855D01*
X172528Y99563D01*
X172778Y99397D01*
X173070Y99355D01*
X173403Y99438D01*
X173653Y99647D01*
X173903Y100022D01*
G01X176170Y98480D02*
X176462Y98522D01*
X176795Y98647D01*
X177003Y98855D01*
X177087Y99147D01*
X177003Y99438D01*
X176753Y99688D01*
X176378Y99813D01*
X175962D01*
X175712Y99897D01*
X175503Y100105D01*
X175420Y100397D01*
X175545Y100688D01*
X175837Y100897D01*
X176170Y100980D01*
X176503Y100897D01*
X176795Y100688D01*
X176920Y100397D01*
X176837Y100105D01*
X176628Y99897D01*
X176378Y99813D01*
X175962D01*
X175587Y99688D01*
X175337Y99438D01*
X175253Y99147D01*
X175337Y98855D01*
X175545Y98647D01*
X175878Y98522D01*
X176170Y98480D01*
G01X168100Y116500D02*
Y112500D01*
X175500D01*
G01X139817Y112167D02*
Y114667D01*
X140858D01*
X141192Y114542D01*
X141400Y114375D01*
X141483Y114042D01*
X141400Y113709D01*
X141150Y113500D01*
X140858Y113375D01*
X139817D01*
G01X140858D02*
X141483Y112167D01*
G01X142833Y112667D02*
X143083Y112375D01*
X143417Y112209D01*
X143792Y112167D01*
X144125Y112209D01*
X144458Y112417D01*
X144667Y112667D01*
X144708Y112917D01*
X144625Y113209D01*
X144333Y113417D01*
X144042Y113500D01*
X143667D01*
G01X144042D02*
X144292Y113625D01*
X144500Y113834D01*
X144583Y114084D01*
X144500Y114334D01*
X144292Y114542D01*
X143917Y114667D01*
X143542Y114625D01*
X143167Y114459D01*
G01X146142Y112459D02*
X146433Y112250D01*
X146767Y112167D01*
X147100Y112250D01*
X147392Y112500D01*
X147600Y112875D01*
X147683Y113250D01*
Y113709D01*
X147600Y114084D01*
X147392Y114417D01*
X147142Y114584D01*
X146850Y114667D01*
X146517Y114584D01*
X146267Y114417D01*
X146100Y114167D01*
X146017Y113834D01*
X146100Y113542D01*
X146308Y113250D01*
X146558Y113084D01*
X146850Y113042D01*
X147183Y113125D01*
X147433Y113334D01*
X147683Y113709D01*
G01X149867Y112167D02*
X149950Y112709D01*
X150075Y113167D01*
X150242Y113584D01*
X150450Y114042D01*
X150783Y114667D01*
X149117D01*
G01X165500Y111400D02*
Y115400D01*
X158100D01*
G01X143817Y107000D02*
Y109500D01*
X144858D01*
X145192Y109375D01*
X145400Y109208D01*
X145483Y108875D01*
X145400Y108542D01*
X145150Y108333D01*
X144858Y108208D01*
X143817D01*
G01X144858D02*
X145483Y107000D01*
G01X146833Y107500D02*
X147083Y107208D01*
X147417Y107042D01*
X147792Y107000D01*
X148125Y107042D01*
X148458Y107250D01*
X148667Y107500D01*
X148708Y107750D01*
X148625Y108042D01*
X148333Y108250D01*
X148042Y108333D01*
X147667D01*
G01X148042D02*
X148292Y108458D01*
X148500Y108667D01*
X148583Y108917D01*
X148500Y109167D01*
X148292Y109375D01*
X147917Y109500D01*
X147542Y109458D01*
X147167Y109292D01*
G01X150850Y107000D02*
X151142Y107042D01*
X151475Y107167D01*
X151683Y107375D01*
X151767Y107667D01*
X151683Y107958D01*
X151433Y108208D01*
X151058Y108333D01*
X150642D01*
X150392Y108417D01*
X150183Y108625D01*
X150100Y108917D01*
X150225Y109208D01*
X150517Y109417D01*
X150850Y109500D01*
X151183Y109417D01*
X151475Y109208D01*
X151600Y108917D01*
X151517Y108625D01*
X151308Y108417D01*
X151058Y108333D01*
X150642D01*
X150267Y108208D01*
X150017Y107958D01*
X149933Y107667D01*
X150017Y107375D01*
X150225Y107167D01*
X150558Y107042D01*
X150850Y107000D01*
G01X153158Y108042D02*
X153450Y108333D01*
X153700Y108500D01*
X154033Y108583D01*
X154325Y108500D01*
X154533Y108333D01*
X154700Y108083D01*
X154742Y107792D01*
X154700Y107542D01*
X154533Y107292D01*
X154283Y107083D01*
X153992Y107000D01*
X153658Y107083D01*
X153367Y107333D01*
X153200Y107708D01*
X153158Y108125D01*
X153242Y108667D01*
X153367Y108958D01*
X153575Y109250D01*
X153867Y109458D01*
X154158Y109500D01*
X154450Y109417D01*
X154658Y109208D01*
G01X158100Y111050D02*
Y107050D01*
X165500D01*
G01X193008Y101267D02*
X192883Y101017D01*
X192800Y100725D01*
Y100392D01*
X192925Y100017D01*
X193133Y99725D01*
X193383Y99517D01*
X193800Y99350D01*
X194175Y99308D01*
X194550Y99392D01*
X194800Y99517D01*
X195050Y99767D01*
X195217Y100058D01*
X195300Y100350D01*
Y100642D01*
X195217Y100933D01*
X195092Y101183D01*
X194925Y101392D01*
G01X194258Y102658D02*
X193967Y102950D01*
X193800Y103200D01*
X193717Y103533D01*
X193800Y103825D01*
X193967Y104033D01*
X194217Y104200D01*
X194508Y104242D01*
X194758Y104200D01*
X195008Y104033D01*
X195217Y103783D01*
X195300Y103492D01*
X195217Y103158D01*
X194967Y102867D01*
X194592Y102700D01*
X194175Y102658D01*
X193633Y102742D01*
X193342Y102867D01*
X193050Y103075D01*
X192842Y103367D01*
X192800Y103658D01*
X192883Y103950D01*
X193092Y104158D01*
G01X195300Y106550D02*
X192800D01*
X193300Y106050D01*
G01X195300D02*
Y107050D01*
G01X194800Y108733D02*
X195092Y108983D01*
X195258Y109317D01*
X195300Y109692D01*
X195258Y110025D01*
X195050Y110358D01*
X194800Y110567D01*
X194550Y110608D01*
X194258Y110525D01*
X194050Y110233D01*
X193967Y109942D01*
Y109567D01*
G01Y109942D02*
X193842Y110192D01*
X193633Y110400D01*
X193383Y110483D01*
X193133Y110400D01*
X192925Y110192D01*
X192800Y109817D01*
X192842Y109442D01*
X193008Y109067D01*
G01X180787Y100772D02*
X180537Y100897D01*
X180245Y100980D01*
X179912D01*
X179537Y100855D01*
X179245Y100647D01*
X179037Y100397D01*
X178870Y99980D01*
X178828Y99605D01*
X178912Y99230D01*
X179037Y98980D01*
X179287Y98730D01*
X179578Y98563D01*
X179870Y98480D01*
X180162D01*
X180453Y98563D01*
X180703Y98688D01*
X180912Y98855D01*
G01X182178Y99522D02*
X182470Y99813D01*
X182720Y99980D01*
X183053Y100063D01*
X183345Y99980D01*
X183553Y99813D01*
X183720Y99563D01*
X183762Y99272D01*
X183720Y99022D01*
X183553Y98772D01*
X183303Y98563D01*
X183012Y98480D01*
X182678Y98563D01*
X182387Y98813D01*
X182220Y99188D01*
X182178Y99605D01*
X182262Y100147D01*
X182387Y100438D01*
X182595Y100730D01*
X182887Y100938D01*
X183178Y100980D01*
X183470Y100897D01*
X183678Y100688D01*
G01X186070Y98480D02*
Y100980D01*
X185570Y100480D01*
G01Y98480D02*
X186570D01*
G01X188378Y100563D02*
X188628Y100813D01*
X188920Y100938D01*
X189253Y100980D01*
X189670Y100897D01*
X189962Y100688D01*
X190045Y100438D01*
X190003Y100188D01*
X189837Y99980D01*
X189003Y99563D01*
X188628Y99272D01*
X188378Y98855D01*
X188295Y98480D01*
X190045D01*
G01X198980Y105336D02*
X198730Y105461D01*
X198438Y105544D01*
X198105D01*
X197730Y105419D01*
X197438Y105211D01*
X197230Y104961D01*
X197063Y104544D01*
X197021Y104169D01*
X197105Y103794D01*
X197230Y103544D01*
X197480Y103294D01*
X197771Y103127D01*
X198063Y103044D01*
X198355D01*
X198646Y103127D01*
X198896Y103252D01*
X199105Y103419D01*
G01X200371Y104086D02*
X200663Y104377D01*
X200913Y104544D01*
X201246Y104627D01*
X201538Y104544D01*
X201746Y104377D01*
X201913Y104127D01*
X201955Y103836D01*
X201913Y103586D01*
X201746Y103336D01*
X201496Y103127D01*
X201205Y103044D01*
X200871Y103127D01*
X200580Y103377D01*
X200413Y103752D01*
X200371Y104169D01*
X200455Y104711D01*
X200580Y105002D01*
X200788Y105294D01*
X201080Y105502D01*
X201371Y105544D01*
X201663Y105461D01*
X201871Y105252D01*
G01X204263Y103044D02*
Y105544D01*
X203763Y105044D01*
G01Y103044D02*
X204763D01*
G01X206446Y103419D02*
X206696Y103211D01*
X206988Y103086D01*
X207363Y103044D01*
X207738Y103127D01*
X208030Y103294D01*
X208238Y103586D01*
X208280Y103919D01*
X208196Y104252D01*
X207988Y104461D01*
X207696Y104627D01*
X207405Y104669D01*
X207113Y104627D01*
X206738Y104461D01*
X206863Y105544D01*
X207988D01*
G01X197130Y99144D02*
Y101644D01*
X198171D01*
X198505Y101519D01*
X198713Y101352D01*
X198796Y101019D01*
X198713Y100686D01*
X198463Y100477D01*
X198171Y100352D01*
X197130D01*
G01X198171D02*
X198796Y99144D01*
G01X201563D02*
Y101644D01*
X200021Y99852D01*
X202105D01*
G01X204080Y99144D02*
X204163Y99686D01*
X204288Y100144D01*
X204455Y100561D01*
X204663Y101019D01*
X204996Y101644D01*
X203330D01*
G01X207763Y99144D02*
Y101644D01*
X206221Y99852D01*
X208305D01*
G01X191413Y116644D02*
Y112644D01*
X198813D01*
G01X170567Y91959D02*
X170317Y92084D01*
X170025Y92167D01*
X169692D01*
X169317Y92042D01*
X169025Y91834D01*
X168817Y91584D01*
X168650Y91167D01*
X168608Y90792D01*
X168692Y90417D01*
X168817Y90167D01*
X169067Y89917D01*
X169358Y89750D01*
X169650Y89667D01*
X169942D01*
X170233Y89750D01*
X170483Y89875D01*
X170692Y90042D01*
G01X171958Y90709D02*
X172250Y91000D01*
X172500Y91167D01*
X172833Y91250D01*
X173125Y91167D01*
X173333Y91000D01*
X173500Y90750D01*
X173542Y90459D01*
X173500Y90209D01*
X173333Y89959D01*
X173083Y89750D01*
X172792Y89667D01*
X172458Y89750D01*
X172167Y90000D01*
X172000Y90375D01*
X171958Y90792D01*
X172042Y91334D01*
X172167Y91625D01*
X172375Y91917D01*
X172667Y92125D01*
X172958Y92167D01*
X173250Y92084D01*
X173458Y91875D01*
G01X175767Y89667D02*
X175850Y90209D01*
X175975Y90667D01*
X176142Y91084D01*
X176350Y91542D01*
X176683Y92167D01*
X175017D01*
G01X178033Y90167D02*
X178283Y89875D01*
X178617Y89709D01*
X178992Y89667D01*
X179325Y89709D01*
X179658Y89917D01*
X179867Y90167D01*
X179908Y90417D01*
X179825Y90709D01*
X179533Y90917D01*
X179242Y91000D01*
X178867D01*
G01X179242D02*
X179492Y91125D01*
X179700Y91334D01*
X179783Y91584D01*
X179700Y91834D01*
X179492Y92042D01*
X179117Y92167D01*
X178742Y92125D01*
X178367Y91959D01*
G01X201800Y125517D02*
X199300D01*
Y126558D01*
X199425Y126892D01*
X199592Y127100D01*
X199925Y127183D01*
X200258Y127100D01*
X200467Y126850D01*
X200592Y126558D01*
Y125517D01*
G01Y126558D02*
X201800Y127183D01*
G01Y129950D02*
X199300D01*
X201092Y128408D01*
Y130492D01*
G01X199300Y132550D02*
X199383Y132217D01*
X199592Y131967D01*
X199842Y131800D01*
X200175Y131675D01*
X200550Y131633D01*
X200925Y131675D01*
X201258Y131800D01*
X201508Y131967D01*
X201717Y132217D01*
X201800Y132550D01*
X201717Y132883D01*
X201508Y133133D01*
X201258Y133300D01*
X200925Y133425D01*
X200550Y133467D01*
X200175Y133425D01*
X199842Y133300D01*
X199592Y133133D01*
X199383Y132883D01*
X199300Y132550D01*
G01X201800Y135650D02*
X199300D01*
X199800Y135150D01*
G01X201800D02*
Y136150D01*
G01X193161Y126117D02*
X197161D01*
Y133517D01*
G01X141817Y121500D02*
Y124000D01*
X142858D01*
X143192Y123875D01*
X143400Y123708D01*
X143483Y123375D01*
X143400Y123042D01*
X143150Y122833D01*
X142858Y122708D01*
X141817D01*
G01X142858D02*
X143483Y121500D01*
G01X146250D02*
Y124000D01*
X144708Y122208D01*
X146792D01*
G01X148850Y124000D02*
X148517Y123917D01*
X148267Y123708D01*
X148100Y123458D01*
X147975Y123125D01*
X147933Y122750D01*
X147975Y122375D01*
X148100Y122042D01*
X148267Y121792D01*
X148517Y121583D01*
X148850Y121500D01*
X149183Y121583D01*
X149433Y121792D01*
X149600Y122042D01*
X149725Y122375D01*
X149767Y122750D01*
X149725Y123125D01*
X149600Y123458D01*
X149433Y123708D01*
X149183Y123917D01*
X148850Y124000D01*
G01X151950D02*
X151617Y123917D01*
X151367Y123708D01*
X151200Y123458D01*
X151075Y123125D01*
X151033Y122750D01*
X151075Y122375D01*
X151200Y122042D01*
X151367Y121792D01*
X151617Y121583D01*
X151950Y121500D01*
X152283Y121583D01*
X152533Y121792D01*
X152700Y122042D01*
X152825Y122375D01*
X152867Y122750D01*
X152825Y123125D01*
X152700Y123458D01*
X152533Y123708D01*
X152283Y123917D01*
X151950Y124000D01*
G01X162000Y120000D02*
Y124000D01*
X154600D01*
G01X158134Y139517D02*
X155634D01*
Y140558D01*
X155759Y140892D01*
X155926Y141100D01*
X156259Y141183D01*
X156592Y141100D01*
X156801Y140850D01*
X156926Y140558D01*
Y139517D01*
G01Y140558D02*
X158134Y141183D01*
G01X157634Y142533D02*
X157926Y142783D01*
X158092Y143117D01*
X158134Y143492D01*
X158092Y143825D01*
X157884Y144158D01*
X157634Y144367D01*
X157384Y144408D01*
X157092Y144325D01*
X156884Y144033D01*
X156801Y143742D01*
Y143367D01*
G01Y143742D02*
X156676Y143992D01*
X156467Y144200D01*
X156217Y144283D01*
X155967Y144200D01*
X155759Y143992D01*
X155634Y143617D01*
X155676Y143242D01*
X155842Y142867D01*
G01X158134Y146550D02*
X158092Y146842D01*
X157967Y147175D01*
X157759Y147383D01*
X157467Y147467D01*
X157176Y147383D01*
X156926Y147133D01*
X156801Y146758D01*
Y146342D01*
X156717Y146092D01*
X156509Y145883D01*
X156217Y145800D01*
X155926Y145925D01*
X155717Y146217D01*
X155634Y146550D01*
X155717Y146883D01*
X155926Y147175D01*
X156217Y147300D01*
X156509Y147217D01*
X156717Y147008D01*
X156801Y146758D01*
Y146342D01*
X156926Y145967D01*
X157176Y145717D01*
X157467Y145633D01*
X157759Y145717D01*
X157967Y145925D01*
X158092Y146258D01*
X158134Y146550D01*
G01X157634Y148733D02*
X157926Y148983D01*
X158092Y149317D01*
X158134Y149692D01*
X158092Y150025D01*
X157884Y150358D01*
X157634Y150567D01*
X157384Y150608D01*
X157092Y150525D01*
X156884Y150233D01*
X156801Y149942D01*
Y149567D01*
G01Y149942D02*
X156676Y150192D01*
X156467Y150400D01*
X156217Y150483D01*
X155967Y150400D01*
X155759Y150192D01*
X155634Y149817D01*
X155676Y149442D01*
X155842Y149067D01*
G01X154700Y130800D02*
X158700D01*
Y138200D01*
G01X144867Y116667D02*
Y119167D01*
X145908D01*
X146242Y119042D01*
X146450Y118875D01*
X146533Y118542D01*
X146450Y118209D01*
X146200Y118000D01*
X145908Y117875D01*
X144867D01*
G01X145908D02*
X146533Y116667D01*
G01X148092Y116959D02*
X148383Y116750D01*
X148717Y116667D01*
X149050Y116750D01*
X149342Y117000D01*
X149550Y117375D01*
X149633Y117750D01*
Y118209D01*
X149550Y118584D01*
X149342Y118917D01*
X149092Y119084D01*
X148800Y119167D01*
X148467Y119084D01*
X148217Y118917D01*
X148050Y118667D01*
X147967Y118334D01*
X148050Y118042D01*
X148258Y117750D01*
X148508Y117584D01*
X148800Y117542D01*
X149133Y117625D01*
X149383Y117834D01*
X149633Y118209D01*
G01X151900Y116667D02*
Y119167D01*
X151400Y118667D01*
G01Y116667D02*
X152400D01*
G01X165500Y115700D02*
Y119700D01*
X158100D01*
G01X159842Y148267D02*
X159717Y148017D01*
X159634Y147725D01*
Y147392D01*
X159759Y147017D01*
X159967Y146725D01*
X160217Y146517D01*
X160634Y146350D01*
X161009Y146308D01*
X161384Y146392D01*
X161634Y146517D01*
X161884Y146767D01*
X162051Y147058D01*
X162134Y147350D01*
Y147642D01*
X162051Y147933D01*
X161926Y148183D01*
X161759Y148392D01*
G01X161092Y149658D02*
X160801Y149950D01*
X160634Y150200D01*
X160551Y150533D01*
X160634Y150825D01*
X160801Y151033D01*
X161051Y151200D01*
X161342Y151242D01*
X161592Y151200D01*
X161842Y151033D01*
X162051Y150783D01*
X162134Y150492D01*
X162051Y150158D01*
X161801Y149867D01*
X161426Y149700D01*
X161009Y149658D01*
X160467Y149742D01*
X160176Y149867D01*
X159884Y150075D01*
X159676Y150367D01*
X159634Y150658D01*
X159717Y150950D01*
X159926Y151158D01*
G01X159634Y153550D02*
X159717Y153217D01*
X159926Y152967D01*
X160176Y152800D01*
X160509Y152675D01*
X160884Y152633D01*
X161259Y152675D01*
X161592Y152800D01*
X161842Y152967D01*
X162051Y153217D01*
X162134Y153550D01*
X162051Y153883D01*
X161842Y154133D01*
X161592Y154300D01*
X161259Y154425D01*
X160884Y154467D01*
X160509Y154425D01*
X160176Y154300D01*
X159926Y154133D01*
X159717Y153883D01*
X159634Y153550D01*
G01X162134Y157150D02*
X159634D01*
X161426Y155608D01*
Y157692D01*
G01X176300Y144517D02*
X173800D01*
Y145558D01*
X173925Y145892D01*
X174092Y146100D01*
X174425Y146183D01*
X174758Y146100D01*
X174967Y145850D01*
X175092Y145558D01*
Y144517D01*
G01Y145558D02*
X176300Y146183D01*
G01Y148950D02*
X173800D01*
X175592Y147408D01*
Y149492D01*
G01X176300Y152050D02*
X173800D01*
X175592Y150508D01*
Y152592D01*
G01X173800Y154650D02*
X173883Y154317D01*
X174092Y154067D01*
X174342Y153900D01*
X174675Y153775D01*
X175050Y153733D01*
X175425Y153775D01*
X175758Y153900D01*
X176008Y154067D01*
X176217Y154317D01*
X176300Y154650D01*
X176217Y154983D01*
X176008Y155233D01*
X175758Y155400D01*
X175425Y155525D01*
X175050Y155567D01*
X174675Y155525D01*
X174342Y155400D01*
X174092Y155233D01*
X173883Y154983D01*
X173800Y154650D01*
G01X192117Y156200D02*
Y158700D01*
X193158D01*
X193492Y158575D01*
X193700Y158408D01*
X193783Y158075D01*
X193700Y157742D01*
X193450Y157533D01*
X193158Y157408D01*
X192117D01*
G01X193158D02*
X193783Y156200D01*
G01X196550D02*
Y158700D01*
X195008Y156908D01*
X197092D01*
G01X199150Y156200D02*
X199442Y156242D01*
X199775Y156367D01*
X199983Y156575D01*
X200067Y156867D01*
X199983Y157158D01*
X199733Y157408D01*
X199358Y157533D01*
X198942D01*
X198692Y157617D01*
X198483Y157825D01*
X198400Y158117D01*
X198525Y158408D01*
X198817Y158617D01*
X199150Y158700D01*
X199483Y158617D01*
X199775Y158408D01*
X199900Y158117D01*
X199817Y157825D01*
X199608Y157617D01*
X199358Y157533D01*
X198942D01*
X198567Y157408D01*
X198317Y157158D01*
X198233Y156867D01*
X198317Y156575D01*
X198525Y156367D01*
X198858Y156242D01*
X199150Y156200D01*
G01X201458Y158283D02*
X201708Y158533D01*
X202000Y158658D01*
X202333Y158700D01*
X202750Y158617D01*
X203042Y158408D01*
X203125Y158158D01*
X203083Y157908D01*
X202917Y157700D01*
X202083Y157283D01*
X201708Y156992D01*
X201458Y156575D01*
X201375Y156200D01*
X203125D01*
G01X182234Y159517D02*
X179734D01*
Y160558D01*
X179859Y160892D01*
X180026Y161100D01*
X180359Y161183D01*
X180692Y161100D01*
X180901Y160850D01*
X181026Y160558D01*
Y159517D01*
G01Y160558D02*
X182234Y161183D01*
G01Y163950D02*
X179734D01*
X181526Y162408D01*
Y164492D01*
G01X182234Y166550D02*
X182192Y166842D01*
X182067Y167175D01*
X181859Y167383D01*
X181567Y167467D01*
X181276Y167383D01*
X181026Y167133D01*
X180901Y166758D01*
Y166342D01*
X180817Y166092D01*
X180609Y165883D01*
X180317Y165800D01*
X180026Y165925D01*
X179817Y166217D01*
X179734Y166550D01*
X179817Y166883D01*
X180026Y167175D01*
X180317Y167300D01*
X180609Y167217D01*
X180817Y167008D01*
X180901Y166758D01*
Y166342D01*
X181026Y165967D01*
X181276Y165717D01*
X181567Y165633D01*
X181859Y165717D01*
X182067Y165925D01*
X182192Y166258D01*
X182234Y166550D01*
G01Y169650D02*
X179734D01*
X180234Y169150D01*
G01X182234D02*
Y170150D01*
G01X142108Y162767D02*
X141983Y162517D01*
X141900Y162225D01*
Y161892D01*
X142025Y161517D01*
X142233Y161225D01*
X142483Y161017D01*
X142900Y160850D01*
X143275Y160808D01*
X143650Y160892D01*
X143900Y161017D01*
X144150Y161267D01*
X144317Y161558D01*
X144400Y161850D01*
Y162142D01*
X144317Y162433D01*
X144192Y162683D01*
X144025Y162892D01*
G01X143358Y164158D02*
X143067Y164450D01*
X142900Y164700D01*
X142817Y165033D01*
X142900Y165325D01*
X143067Y165533D01*
X143317Y165700D01*
X143608Y165742D01*
X143858Y165700D01*
X144108Y165533D01*
X144317Y165283D01*
X144400Y164992D01*
X144317Y164658D01*
X144067Y164367D01*
X143692Y164200D01*
X143275Y164158D01*
X142733Y164242D01*
X142442Y164367D01*
X142150Y164575D01*
X141942Y164867D01*
X141900Y165158D01*
X141983Y165450D01*
X142192Y165658D01*
G01X143358Y167258D02*
X143067Y167550D01*
X142900Y167800D01*
X142817Y168133D01*
X142900Y168425D01*
X143067Y168633D01*
X143317Y168800D01*
X143608Y168842D01*
X143858Y168800D01*
X144108Y168633D01*
X144317Y168383D01*
X144400Y168092D01*
X144317Y167758D01*
X144067Y167467D01*
X143692Y167300D01*
X143275Y167258D01*
X142733Y167342D01*
X142442Y167467D01*
X142150Y167675D01*
X141942Y167967D01*
X141900Y168258D01*
X141983Y168550D01*
X142192Y168758D01*
G01X144400Y171067D02*
X143858Y171150D01*
X143400Y171275D01*
X142983Y171442D01*
X142525Y171650D01*
X141900Y171983D01*
Y170317D01*
G01X146108Y162767D02*
X145983Y162517D01*
X145900Y162225D01*
Y161892D01*
X146025Y161517D01*
X146233Y161225D01*
X146483Y161017D01*
X146900Y160850D01*
X147275Y160808D01*
X147650Y160892D01*
X147900Y161017D01*
X148150Y161267D01*
X148317Y161558D01*
X148400Y161850D01*
Y162142D01*
X148317Y162433D01*
X148192Y162683D01*
X148025Y162892D01*
G01X147358Y164158D02*
X147067Y164450D01*
X146900Y164700D01*
X146817Y165033D01*
X146900Y165325D01*
X147067Y165533D01*
X147317Y165700D01*
X147608Y165742D01*
X147858Y165700D01*
X148108Y165533D01*
X148317Y165283D01*
X148400Y164992D01*
X148317Y164658D01*
X148067Y164367D01*
X147692Y164200D01*
X147275Y164158D01*
X146733Y164242D01*
X146442Y164367D01*
X146150Y164575D01*
X145942Y164867D01*
X145900Y165158D01*
X145983Y165450D01*
X146192Y165658D01*
G01X147358Y167258D02*
X147067Y167550D01*
X146900Y167800D01*
X146817Y168133D01*
X146900Y168425D01*
X147067Y168633D01*
X147317Y168800D01*
X147608Y168842D01*
X147858Y168800D01*
X148108Y168633D01*
X148317Y168383D01*
X148400Y168092D01*
X148317Y167758D01*
X148067Y167467D01*
X147692Y167300D01*
X147275Y167258D01*
X146733Y167342D01*
X146442Y167467D01*
X146150Y167675D01*
X145942Y167967D01*
X145900Y168258D01*
X145983Y168550D01*
X146192Y168758D01*
G01X147358Y170358D02*
X147067Y170650D01*
X146900Y170900D01*
X146817Y171233D01*
X146900Y171525D01*
X147067Y171733D01*
X147317Y171900D01*
X147608Y171942D01*
X147858Y171900D01*
X148108Y171733D01*
X148317Y171483D01*
X148400Y171192D01*
X148317Y170858D01*
X148067Y170567D01*
X147692Y170400D01*
X147275Y170358D01*
X146733Y170442D01*
X146442Y170567D01*
X146150Y170775D01*
X145942Y171067D01*
X145900Y171358D01*
X145983Y171650D01*
X146192Y171858D01*
G01X199067Y148792D02*
X198817Y148917D01*
X198525Y149000D01*
X198192D01*
X197817Y148875D01*
X197525Y148667D01*
X197317Y148417D01*
X197150Y148000D01*
X197108Y147625D01*
X197192Y147250D01*
X197317Y147000D01*
X197567Y146750D01*
X197858Y146583D01*
X198150Y146500D01*
X198442D01*
X198733Y146583D01*
X198983Y146708D01*
X199192Y146875D01*
G01X200458Y147542D02*
X200750Y147833D01*
X201000Y148000D01*
X201333Y148083D01*
X201625Y148000D01*
X201833Y147833D01*
X202000Y147583D01*
X202042Y147292D01*
X202000Y147042D01*
X201833Y146792D01*
X201583Y146583D01*
X201292Y146500D01*
X200958Y146583D01*
X200667Y146833D01*
X200500Y147208D01*
X200458Y147625D01*
X200542Y148167D01*
X200667Y148458D01*
X200875Y148750D01*
X201167Y148958D01*
X201458Y149000D01*
X201750Y148917D01*
X201958Y148708D01*
G01X204350Y146500D02*
Y149000D01*
X203850Y148500D01*
G01Y146500D02*
X204850D01*
G01X206658Y147542D02*
X206950Y147833D01*
X207200Y148000D01*
X207533Y148083D01*
X207825Y148000D01*
X208033Y147833D01*
X208200Y147583D01*
X208242Y147292D01*
X208200Y147042D01*
X208033Y146792D01*
X207783Y146583D01*
X207492Y146500D01*
X207158Y146583D01*
X206867Y146833D01*
X206700Y147208D01*
X206658Y147625D01*
X206742Y148167D01*
X206867Y148458D01*
X207075Y148750D01*
X207367Y148958D01*
X207658Y149000D01*
X207950Y148917D01*
X208158Y148708D01*
G01X144567Y142459D02*
X144317Y142584D01*
X144025Y142667D01*
X143692D01*
X143317Y142542D01*
X143025Y142334D01*
X142817Y142084D01*
X142650Y141667D01*
X142608Y141292D01*
X142692Y140917D01*
X142817Y140667D01*
X143067Y140417D01*
X143358Y140250D01*
X143650Y140167D01*
X143942D01*
X144233Y140250D01*
X144483Y140375D01*
X144692Y140542D01*
G01X146667Y140167D02*
X146750Y140709D01*
X146875Y141167D01*
X147042Y141584D01*
X147250Y142042D01*
X147583Y142667D01*
X145917D01*
G01X149850Y140167D02*
Y142667D01*
X149350Y142167D01*
G01Y140167D02*
X150350D01*
G01X152158Y142250D02*
X152408Y142500D01*
X152700Y142625D01*
X153033Y142667D01*
X153450Y142584D01*
X153742Y142375D01*
X153825Y142125D01*
X153783Y141875D01*
X153617Y141667D01*
X152783Y141250D01*
X152408Y140959D01*
X152158Y140542D01*
X152075Y140167D01*
X153825D01*
G01X181100Y174950D02*
Y170950D01*
X185100D01*
G01X197817Y142000D02*
Y144500D01*
X198817D01*
X199150Y144375D01*
X199400Y144083D01*
X199483Y143750D01*
X199400Y143417D01*
X199192Y143167D01*
X198817Y143042D01*
X197817D01*
G01X200875Y142333D02*
X201208Y142125D01*
X201583Y142000D01*
X201917D01*
X202250Y142125D01*
X202500Y142333D01*
X202625Y142625D01*
X202542Y142917D01*
X202333Y143167D01*
X201958Y143333D01*
X201458Y143417D01*
X201167Y143583D01*
X201042Y143875D01*
X201125Y144167D01*
X201333Y144375D01*
X201625Y144500D01*
X201917D01*
X202208Y144417D01*
X202458Y144208D01*
G01X204017Y142000D02*
Y144500D01*
X205017D01*
X205350Y144375D01*
X205600Y144083D01*
X205683Y143750D01*
X205600Y143417D01*
X205392Y143167D01*
X205017Y143042D01*
X204017D01*
G01X207950Y142000D02*
Y144500D01*
X207450Y144000D01*
G01Y142000D02*
X208450D01*
G01X160133Y134533D02*
X161925D01*
X162300Y134700D01*
X162550Y135033D01*
X162633Y135450D01*
X162550Y135867D01*
X162300Y136200D01*
X161925Y136367D01*
X160133D01*
G01X162633Y138550D02*
X162591Y138842D01*
X162466Y139175D01*
X162258Y139383D01*
X161966Y139467D01*
X161675Y139383D01*
X161425Y139133D01*
X161300Y138758D01*
Y138342D01*
X161216Y138092D01*
X161008Y137883D01*
X160716Y137800D01*
X160425Y137925D01*
X160216Y138217D01*
X160133Y138550D01*
X160216Y138883D01*
X160425Y139175D01*
X160716Y139300D01*
X161008Y139217D01*
X161216Y139008D01*
X161300Y138758D01*
Y138342D01*
X161425Y137967D01*
X161675Y137717D01*
X161966Y137633D01*
X162258Y137717D01*
X162466Y137925D01*
X162591Y138258D01*
X162633Y138550D01*
G01X178779Y140506D02*
Y143506D01*
G01X168794Y130474D02*
X166794D01*
G01X186806Y128534D02*
X188806D01*
G01X182700Y121600D02*
X187700D01*
Y126600D01*
G01X172900Y141400D02*
X167900D01*
Y136400D01*
G01X187700D02*
Y141400D01*
X182700D01*
G01X195811Y216477D02*
X195561Y216602D01*
X195269Y216685D01*
X194936D01*
X194561Y216560D01*
X194269Y216352D01*
X194061Y216102D01*
X193894Y215685D01*
X193852Y215310D01*
X193936Y214935D01*
X194061Y214685D01*
X194311Y214435D01*
X194602Y214268D01*
X194894Y214185D01*
X195186D01*
X195477Y214268D01*
X195727Y214393D01*
X195936Y214560D01*
G01X197202Y215227D02*
X197494Y215518D01*
X197744Y215685D01*
X198077Y215768D01*
X198369Y215685D01*
X198577Y215518D01*
X198744Y215268D01*
X198786Y214977D01*
X198744Y214727D01*
X198577Y214477D01*
X198327Y214268D01*
X198036Y214185D01*
X197702Y214268D01*
X197411Y214518D01*
X197244Y214893D01*
X197202Y215310D01*
X197286Y215852D01*
X197411Y216143D01*
X197619Y216435D01*
X197911Y216643D01*
X198202Y216685D01*
X198494Y216602D01*
X198702Y216393D01*
G01X201094Y214185D02*
Y216685D01*
X200594Y216185D01*
G01Y214185D02*
X201594D01*
G01X204194D02*
X204486Y214227D01*
X204819Y214352D01*
X205027Y214560D01*
X205111Y214852D01*
X205027Y215143D01*
X204777Y215393D01*
X204402Y215518D01*
X203986D01*
X203736Y215602D01*
X203527Y215810D01*
X203444Y216102D01*
X203569Y216393D01*
X203861Y216602D01*
X204194Y216685D01*
X204527Y216602D01*
X204819Y216393D01*
X204944Y216102D01*
X204861Y215810D01*
X204652Y215602D01*
X204402Y215518D01*
X203986D01*
X203611Y215393D01*
X203361Y215143D01*
X203277Y214852D01*
X203361Y214560D01*
X203569Y214352D01*
X203902Y214227D01*
X204194Y214185D01*
G01X140108Y209767D02*
X139983Y209517D01*
X139900Y209225D01*
Y208892D01*
X140025Y208517D01*
X140233Y208225D01*
X140483Y208017D01*
X140900Y207850D01*
X141275Y207808D01*
X141650Y207892D01*
X141900Y208017D01*
X142150Y208267D01*
X142317Y208558D01*
X142400Y208850D01*
Y209142D01*
X142317Y209433D01*
X142192Y209683D01*
X142025Y209892D01*
G01Y211033D02*
X142233Y211283D01*
X142358Y211575D01*
X142400Y211950D01*
X142317Y212325D01*
X142150Y212617D01*
X141858Y212825D01*
X141525Y212867D01*
X141192Y212783D01*
X140983Y212575D01*
X140817Y212283D01*
X140775Y211992D01*
X140817Y211700D01*
X140983Y211325D01*
X139900Y211450D01*
Y212575D01*
G01X140317Y214258D02*
X140067Y214508D01*
X139942Y214800D01*
X139900Y215133D01*
X139983Y215550D01*
X140192Y215842D01*
X140442Y215925D01*
X140692Y215883D01*
X140900Y215717D01*
X141317Y214883D01*
X141608Y214508D01*
X142025Y214258D01*
X142400Y214175D01*
Y215925D01*
G01Y218067D02*
X141858Y218150D01*
X141400Y218275D01*
X140983Y218442D01*
X140525Y218650D01*
X139900Y218983D01*
Y217317D01*
G01X148108Y209767D02*
X147983Y209517D01*
X147900Y209225D01*
Y208892D01*
X148025Y208517D01*
X148233Y208225D01*
X148483Y208017D01*
X148900Y207850D01*
X149275Y207808D01*
X149650Y207892D01*
X149900Y208017D01*
X150150Y208267D01*
X150317Y208558D01*
X150400Y208850D01*
Y209142D01*
X150317Y209433D01*
X150192Y209683D01*
X150025Y209892D01*
G01Y211033D02*
X150233Y211283D01*
X150358Y211575D01*
X150400Y211950D01*
X150317Y212325D01*
X150150Y212617D01*
X149858Y212825D01*
X149525Y212867D01*
X149192Y212783D01*
X148983Y212575D01*
X148817Y212283D01*
X148775Y211992D01*
X148817Y211700D01*
X148983Y211325D01*
X147900Y211450D01*
Y212575D01*
G01X149358Y214258D02*
X149067Y214550D01*
X148900Y214800D01*
X148817Y215133D01*
X148900Y215425D01*
X149067Y215633D01*
X149317Y215800D01*
X149608Y215842D01*
X149858Y215800D01*
X150108Y215633D01*
X150317Y215383D01*
X150400Y215092D01*
X150317Y214758D01*
X150067Y214467D01*
X149692Y214300D01*
X149275Y214258D01*
X148733Y214342D01*
X148442Y214467D01*
X148150Y214675D01*
X147942Y214967D01*
X147900Y215258D01*
X147983Y215550D01*
X148192Y215758D01*
G01X150400Y218650D02*
X147900D01*
X149692Y217108D01*
Y219192D01*
G01X155608Y209767D02*
X155483Y209517D01*
X155400Y209225D01*
Y208892D01*
X155525Y208517D01*
X155733Y208225D01*
X155983Y208017D01*
X156400Y207850D01*
X156775Y207808D01*
X157150Y207892D01*
X157400Y208017D01*
X157650Y208267D01*
X157817Y208558D01*
X157900Y208850D01*
Y209142D01*
X157817Y209433D01*
X157692Y209683D01*
X157525Y209892D01*
G01X156858Y211158D02*
X156567Y211450D01*
X156400Y211700D01*
X156317Y212033D01*
X156400Y212325D01*
X156567Y212533D01*
X156817Y212700D01*
X157108Y212742D01*
X157358Y212700D01*
X157608Y212533D01*
X157817Y212283D01*
X157900Y211992D01*
X157817Y211658D01*
X157567Y211367D01*
X157192Y211200D01*
X156775Y211158D01*
X156233Y211242D01*
X155942Y211367D01*
X155650Y211575D01*
X155442Y211867D01*
X155400Y212158D01*
X155483Y212450D01*
X155692Y212658D01*
G01X157900Y214967D02*
X157358Y215050D01*
X156900Y215175D01*
X156483Y215342D01*
X156025Y215550D01*
X155400Y215883D01*
Y214217D01*
G01X157900Y218150D02*
X155400D01*
X155900Y217650D01*
G01X157900D02*
Y218650D01*
G01X171108Y209767D02*
X170983Y209517D01*
X170900Y209225D01*
Y208892D01*
X171025Y208517D01*
X171233Y208225D01*
X171483Y208017D01*
X171900Y207850D01*
X172275Y207808D01*
X172650Y207892D01*
X172900Y208017D01*
X173150Y208267D01*
X173317Y208558D01*
X173400Y208850D01*
Y209142D01*
X173317Y209433D01*
X173192Y209683D01*
X173025Y209892D01*
G01X172358Y211158D02*
X172067Y211450D01*
X171900Y211700D01*
X171817Y212033D01*
X171900Y212325D01*
X172067Y212533D01*
X172317Y212700D01*
X172608Y212742D01*
X172858Y212700D01*
X173108Y212533D01*
X173317Y212283D01*
X173400Y211992D01*
X173317Y211658D01*
X173067Y211367D01*
X172692Y211200D01*
X172275Y211158D01*
X171733Y211242D01*
X171442Y211367D01*
X171150Y211575D01*
X170942Y211867D01*
X170900Y212158D01*
X170983Y212450D01*
X171192Y212658D01*
G01X173400Y214967D02*
X172858Y215050D01*
X172400Y215175D01*
X171983Y215342D01*
X171525Y215550D01*
X170900Y215883D01*
Y214217D01*
G01Y218150D02*
X170983Y217817D01*
X171192Y217567D01*
X171442Y217400D01*
X171775Y217275D01*
X172150Y217233D01*
X172525Y217275D01*
X172858Y217400D01*
X173108Y217567D01*
X173317Y217817D01*
X173400Y218150D01*
X173317Y218483D01*
X173108Y218733D01*
X172858Y218900D01*
X172525Y219025D01*
X172150Y219067D01*
X171775Y219025D01*
X171442Y218900D01*
X171192Y218733D01*
X170983Y218483D01*
X170900Y218150D01*
G01X163108Y209767D02*
X162983Y209517D01*
X162900Y209225D01*
Y208892D01*
X163025Y208517D01*
X163233Y208225D01*
X163483Y208017D01*
X163900Y207850D01*
X164275Y207808D01*
X164650Y207892D01*
X164900Y208017D01*
X165150Y208267D01*
X165317Y208558D01*
X165400Y208850D01*
Y209142D01*
X165317Y209433D01*
X165192Y209683D01*
X165025Y209892D01*
G01X164358Y211158D02*
X164067Y211450D01*
X163900Y211700D01*
X163817Y212033D01*
X163900Y212325D01*
X164067Y212533D01*
X164317Y212700D01*
X164608Y212742D01*
X164858Y212700D01*
X165108Y212533D01*
X165317Y212283D01*
X165400Y211992D01*
X165317Y211658D01*
X165067Y211367D01*
X164692Y211200D01*
X164275Y211158D01*
X163733Y211242D01*
X163442Y211367D01*
X163150Y211575D01*
X162942Y211867D01*
X162900Y212158D01*
X162983Y212450D01*
X163192Y212658D01*
G01X164358Y214258D02*
X164067Y214550D01*
X163900Y214800D01*
X163817Y215133D01*
X163900Y215425D01*
X164067Y215633D01*
X164317Y215800D01*
X164608Y215842D01*
X164858Y215800D01*
X165108Y215633D01*
X165317Y215383D01*
X165400Y215092D01*
X165317Y214758D01*
X165067Y214467D01*
X164692Y214300D01*
X164275Y214258D01*
X163733Y214342D01*
X163442Y214467D01*
X163150Y214675D01*
X162942Y214967D01*
X162900Y215258D01*
X162983Y215550D01*
X163192Y215758D01*
G01X165108Y217442D02*
X165317Y217733D01*
X165400Y218067D01*
X165317Y218400D01*
X165067Y218692D01*
X164692Y218900D01*
X164317Y218983D01*
X163858D01*
X163483Y218900D01*
X163150Y218692D01*
X162983Y218442D01*
X162900Y218150D01*
X162983Y217817D01*
X163150Y217567D01*
X163400Y217400D01*
X163733Y217317D01*
X164025Y217400D01*
X164317Y217608D01*
X164483Y217858D01*
X164525Y218150D01*
X164442Y218483D01*
X164233Y218733D01*
X163858Y218983D01*
G01X176608Y209767D02*
X176483Y209517D01*
X176400Y209225D01*
Y208892D01*
X176525Y208517D01*
X176733Y208225D01*
X176983Y208017D01*
X177400Y207850D01*
X177775Y207808D01*
X178150Y207892D01*
X178400Y208017D01*
X178650Y208267D01*
X178817Y208558D01*
X178900Y208850D01*
Y209142D01*
X178817Y209433D01*
X178692Y209683D01*
X178525Y209892D01*
G01X177858Y211158D02*
X177567Y211450D01*
X177400Y211700D01*
X177317Y212033D01*
X177400Y212325D01*
X177567Y212533D01*
X177817Y212700D01*
X178108Y212742D01*
X178358Y212700D01*
X178608Y212533D01*
X178817Y212283D01*
X178900Y211992D01*
X178817Y211658D01*
X178567Y211367D01*
X178192Y211200D01*
X177775Y211158D01*
X177233Y211242D01*
X176942Y211367D01*
X176650Y211575D01*
X176442Y211867D01*
X176400Y212158D01*
X176483Y212450D01*
X176692Y212658D01*
G01X178900Y214967D02*
X178358Y215050D01*
X177900Y215175D01*
X177483Y215342D01*
X177025Y215550D01*
X176400Y215883D01*
Y214217D01*
G01X176817Y217358D02*
X176567Y217608D01*
X176442Y217900D01*
X176400Y218233D01*
X176483Y218650D01*
X176692Y218942D01*
X176942Y219025D01*
X177192Y218983D01*
X177400Y218817D01*
X177817Y217983D01*
X178108Y217608D01*
X178525Y217358D01*
X178900Y217275D01*
Y219025D01*
G01X183850Y196667D02*
X183517Y196709D01*
X183225Y196875D01*
X182975Y197125D01*
X182808Y197417D01*
X182725Y197750D01*
Y198084D01*
X182808Y198417D01*
X182975Y198709D01*
X183225Y198959D01*
X183517Y199125D01*
X183850Y199167D01*
X184183Y199125D01*
X184475Y198959D01*
X184725Y198709D01*
X184892Y198417D01*
X184975Y198084D01*
Y197750D01*
X184892Y197417D01*
X184725Y197125D01*
X184475Y196875D01*
X184183Y196709D01*
X183850Y196667D01*
G01X184183Y197334D02*
X184683Y196667D01*
G01X186867D02*
X186950Y197209D01*
X187075Y197667D01*
X187242Y198084D01*
X187450Y198542D01*
X187783Y199167D01*
X186117D01*
G01X144900Y178300D02*
Y188500D01*
G01Y178300D02*
Y188500D01*
G01X199517Y266167D02*
Y268667D01*
X200558D01*
X200892Y268542D01*
X201100Y268375D01*
X201183Y268042D01*
X201100Y267709D01*
X200850Y267500D01*
X200558Y267375D01*
X199517D01*
G01X200558D02*
X201183Y266167D01*
G01X203950D02*
Y268667D01*
X202408Y266875D01*
X204492D01*
G01X206467Y266167D02*
X206550Y266709D01*
X206675Y267167D01*
X206842Y267584D01*
X207050Y268042D01*
X207383Y268667D01*
X205717D01*
G01X209650D02*
X209317Y268584D01*
X209067Y268375D01*
X208900Y268125D01*
X208775Y267792D01*
X208733Y267417D01*
X208775Y267042D01*
X208900Y266709D01*
X209067Y266459D01*
X209317Y266250D01*
X209650Y266167D01*
X209983Y266250D01*
X210233Y266459D01*
X210400Y266709D01*
X210525Y267042D01*
X210567Y267417D01*
X210525Y267792D01*
X210400Y268125D01*
X210233Y268375D01*
X209983Y268584D01*
X209650Y268667D01*
G01X184517Y297667D02*
Y300167D01*
X185558D01*
X185892Y300042D01*
X186100Y299875D01*
X186183Y299542D01*
X186100Y299209D01*
X185850Y299000D01*
X185558Y298875D01*
X184517D01*
G01X185558D02*
X186183Y297667D01*
G01X188950D02*
Y300167D01*
X187408Y298375D01*
X189492D01*
G01X191467Y297667D02*
X191550Y298209D01*
X191675Y298667D01*
X191842Y299084D01*
X192050Y299542D01*
X192383Y300167D01*
X190717D01*
G01X194650Y297667D02*
Y300167D01*
X194150Y299667D01*
G01Y297667D02*
X195150D01*
G01X198300Y300800D02*
Y296800D01*
X205700D01*
G01X201267Y272459D02*
X201017Y272584D01*
X200725Y272667D01*
X200392D01*
X200017Y272542D01*
X199725Y272334D01*
X199517Y272084D01*
X199350Y271667D01*
X199308Y271292D01*
X199392Y270917D01*
X199517Y270667D01*
X199767Y270417D01*
X200058Y270250D01*
X200350Y270167D01*
X200642D01*
X200933Y270250D01*
X201183Y270375D01*
X201392Y270542D01*
G01X202533D02*
X202783Y270334D01*
X203075Y270209D01*
X203450Y270167D01*
X203825Y270250D01*
X204117Y270417D01*
X204325Y270709D01*
X204367Y271042D01*
X204283Y271375D01*
X204075Y271584D01*
X203783Y271750D01*
X203492Y271792D01*
X203200Y271750D01*
X202825Y271584D01*
X202950Y272667D01*
X204075D01*
G01X205758Y271209D02*
X206050Y271500D01*
X206300Y271667D01*
X206633Y271750D01*
X206925Y271667D01*
X207133Y271500D01*
X207300Y271250D01*
X207342Y270959D01*
X207300Y270709D01*
X207133Y270459D01*
X206883Y270250D01*
X206592Y270167D01*
X206258Y270250D01*
X205967Y270500D01*
X205800Y270875D01*
X205758Y271292D01*
X205842Y271834D01*
X205967Y272125D01*
X206175Y272417D01*
X206467Y272625D01*
X206758Y272667D01*
X207050Y272584D01*
X207258Y272375D01*
G01X208858Y272250D02*
X209108Y272500D01*
X209400Y272625D01*
X209733Y272667D01*
X210150Y272584D01*
X210442Y272375D01*
X210525Y272125D01*
X210483Y271875D01*
X210317Y271667D01*
X209483Y271250D01*
X209108Y270959D01*
X208858Y270542D01*
X208775Y270167D01*
X210525D01*
G01X154800Y361317D02*
X152300D01*
Y362358D01*
X152425Y362692D01*
X152592Y362900D01*
X152925Y362983D01*
X153258Y362900D01*
X153467Y362650D01*
X153592Y362358D01*
Y361317D01*
G01Y362358D02*
X154800Y362983D01*
G01Y365750D02*
X152300D01*
X154092Y364208D01*
Y366292D01*
G01X152300Y368350D02*
X152383Y368017D01*
X152592Y367767D01*
X152842Y367600D01*
X153175Y367475D01*
X153550Y367433D01*
X153925Y367475D01*
X154258Y367600D01*
X154508Y367767D01*
X154717Y368017D01*
X154800Y368350D01*
X154717Y368683D01*
X154508Y368933D01*
X154258Y369100D01*
X153925Y369225D01*
X153550Y369267D01*
X153175Y369225D01*
X152842Y369100D01*
X152592Y368933D01*
X152383Y368683D01*
X152300Y368350D01*
G01X154800Y371450D02*
X154758Y371742D01*
X154633Y372075D01*
X154425Y372283D01*
X154133Y372367D01*
X153842Y372283D01*
X153592Y372033D01*
X153467Y371658D01*
Y371242D01*
X153383Y370992D01*
X153175Y370783D01*
X152883Y370700D01*
X152592Y370825D01*
X152383Y371117D01*
X152300Y371450D01*
X152383Y371783D01*
X152592Y372075D01*
X152883Y372200D01*
X153175Y372117D01*
X153383Y371908D01*
X153467Y371658D01*
Y371242D01*
X153592Y370867D01*
X153842Y370617D01*
X154133Y370533D01*
X154425Y370617D01*
X154633Y370825D01*
X154758Y371158D01*
X154800Y371450D01*
G01X150700Y361317D02*
X148200D01*
Y362358D01*
X148325Y362692D01*
X148492Y362900D01*
X148825Y362983D01*
X149158Y362900D01*
X149367Y362650D01*
X149492Y362358D01*
Y361317D01*
G01Y362358D02*
X150700Y362983D01*
G01Y365750D02*
X148200D01*
X149992Y364208D01*
Y366292D01*
G01X148200Y368350D02*
X148283Y368017D01*
X148492Y367767D01*
X148742Y367600D01*
X149075Y367475D01*
X149450Y367433D01*
X149825Y367475D01*
X150158Y367600D01*
X150408Y367767D01*
X150617Y368017D01*
X150700Y368350D01*
X150617Y368683D01*
X150408Y368933D01*
X150158Y369100D01*
X149825Y369225D01*
X149450Y369267D01*
X149075Y369225D01*
X148742Y369100D01*
X148492Y368933D01*
X148283Y368683D01*
X148200Y368350D01*
G01X150408Y370742D02*
X150617Y371033D01*
X150700Y371367D01*
X150617Y371700D01*
X150367Y371992D01*
X149992Y372200D01*
X149617Y372283D01*
X149158D01*
X148783Y372200D01*
X148450Y371992D01*
X148283Y371742D01*
X148200Y371450D01*
X148283Y371117D01*
X148450Y370867D01*
X148700Y370700D01*
X149033Y370617D01*
X149325Y370700D01*
X149617Y370908D01*
X149783Y371158D01*
X149825Y371450D01*
X149742Y371783D01*
X149533Y372033D01*
X149158Y372283D01*
G01X156662Y361126D02*
Y363626D01*
X157703D01*
X158037Y363501D01*
X158245Y363334D01*
X158328Y363001D01*
X158245Y362668D01*
X157995Y362459D01*
X157703Y362334D01*
X156662D01*
G01X157703D02*
X158328Y361126D01*
G01X161095D02*
Y363626D01*
X159553Y361834D01*
X161637D01*
G01X164195Y361126D02*
Y363626D01*
X162653Y361834D01*
X164737D01*
G01X166003Y362168D02*
X166295Y362459D01*
X166545Y362626D01*
X166878Y362709D01*
X167170Y362626D01*
X167378Y362459D01*
X167545Y362209D01*
X167587Y361918D01*
X167545Y361668D01*
X167378Y361418D01*
X167128Y361209D01*
X166837Y361126D01*
X166503Y361209D01*
X166212Y361459D01*
X166045Y361834D01*
X166003Y362251D01*
X166087Y362793D01*
X166212Y363084D01*
X166420Y363376D01*
X166712Y363584D01*
X167003Y363626D01*
X167295Y363543D01*
X167503Y363334D01*
G01X171795Y361110D02*
X169295D01*
Y362151D01*
X169420Y362485D01*
X169587Y362693D01*
X169920Y362776D01*
X170253Y362693D01*
X170462Y362443D01*
X170587Y362151D01*
Y361110D01*
G01Y362151D02*
X171795Y362776D01*
G01Y365543D02*
X169295D01*
X171087Y364001D01*
Y366085D01*
G01X171795Y368643D02*
X169295D01*
X171087Y367101D01*
Y369185D01*
G01X171795Y371243D02*
X171753Y371535D01*
X171628Y371868D01*
X171420Y372076D01*
X171128Y372160D01*
X170837Y372076D01*
X170587Y371826D01*
X170462Y371451D01*
Y371035D01*
X170378Y370785D01*
X170170Y370576D01*
X169878Y370493D01*
X169587Y370618D01*
X169378Y370910D01*
X169295Y371243D01*
X169378Y371576D01*
X169587Y371868D01*
X169878Y371993D01*
X170170Y371910D01*
X170378Y371701D01*
X170462Y371451D01*
Y371035D01*
X170587Y370660D01*
X170837Y370410D01*
X171128Y370326D01*
X171420Y370410D01*
X171628Y370618D01*
X171753Y370951D01*
X171795Y371243D01*
G01X175895Y361110D02*
X173395D01*
Y362151D01*
X173520Y362485D01*
X173687Y362693D01*
X174020Y362776D01*
X174353Y362693D01*
X174562Y362443D01*
X174687Y362151D01*
Y361110D01*
G01Y362151D02*
X175895Y362776D01*
G01Y365543D02*
X173395D01*
X175187Y364001D01*
Y366085D01*
G01X175520Y367226D02*
X175728Y367476D01*
X175853Y367768D01*
X175895Y368143D01*
X175812Y368518D01*
X175645Y368810D01*
X175353Y369018D01*
X175020Y369060D01*
X174687Y368976D01*
X174478Y368768D01*
X174312Y368476D01*
X174270Y368185D01*
X174312Y367893D01*
X174478Y367518D01*
X173395Y367643D01*
Y368768D01*
G01Y371243D02*
X173478Y370910D01*
X173687Y370660D01*
X173937Y370493D01*
X174270Y370368D01*
X174645Y370326D01*
X175020Y370368D01*
X175353Y370493D01*
X175603Y370660D01*
X175812Y370910D01*
X175895Y371243D01*
X175812Y371576D01*
X175603Y371826D01*
X175353Y371993D01*
X175020Y372118D01*
X174645Y372160D01*
X174270Y372118D01*
X173937Y371993D01*
X173687Y371826D01*
X173478Y371576D01*
X173395Y371243D01*
G01X193517Y310167D02*
Y312667D01*
X194558D01*
X194892Y312542D01*
X195100Y312375D01*
X195183Y312042D01*
X195100Y311709D01*
X194850Y311500D01*
X194558Y311375D01*
X193517D01*
G01X194558D02*
X195183Y310167D01*
G01X197950D02*
Y312667D01*
X196408Y310875D01*
X198492D01*
G01X200467Y310167D02*
X200550Y310709D01*
X200675Y311167D01*
X200842Y311584D01*
X201050Y312042D01*
X201383Y312667D01*
X199717D01*
G01X202858Y312250D02*
X203108Y312500D01*
X203400Y312625D01*
X203733Y312667D01*
X204150Y312584D01*
X204442Y312375D01*
X204525Y312125D01*
X204483Y311875D01*
X204317Y311667D01*
X203483Y311250D01*
X203108Y310959D01*
X202858Y310542D01*
X202775Y310167D01*
X204525D01*
G01X198300Y308800D02*
Y304800D01*
X205700D01*
G01X201767Y327959D02*
X201517Y328084D01*
X201225Y328167D01*
X200892D01*
X200517Y328042D01*
X200225Y327834D01*
X200017Y327584D01*
X199850Y327167D01*
X199808Y326792D01*
X199892Y326417D01*
X200017Y326167D01*
X200267Y325917D01*
X200558Y325750D01*
X200850Y325667D01*
X201142D01*
X201433Y325750D01*
X201683Y325875D01*
X201892Y326042D01*
G01X203033D02*
X203283Y325834D01*
X203575Y325709D01*
X203950Y325667D01*
X204325Y325750D01*
X204617Y325917D01*
X204825Y326209D01*
X204867Y326542D01*
X204783Y326875D01*
X204575Y327084D01*
X204283Y327250D01*
X203992Y327292D01*
X203700Y327250D01*
X203325Y327084D01*
X203450Y328167D01*
X204575D01*
G01X206258Y326709D02*
X206550Y327000D01*
X206800Y327167D01*
X207133Y327250D01*
X207425Y327167D01*
X207633Y327000D01*
X207800Y326750D01*
X207842Y326459D01*
X207800Y326209D01*
X207633Y325959D01*
X207383Y325750D01*
X207092Y325667D01*
X206758Y325750D01*
X206467Y326000D01*
X206300Y326375D01*
X206258Y326792D01*
X206342Y327334D01*
X206467Y327625D01*
X206675Y327917D01*
X206967Y328125D01*
X207258Y328167D01*
X207550Y328084D01*
X207758Y327875D01*
G01X210150Y325667D02*
Y328167D01*
X209650Y327667D01*
G01Y325667D02*
X210650D01*
G01X159433Y364917D02*
X156933D01*
Y365958D01*
X157058Y366292D01*
X157225Y366500D01*
X157558Y366583D01*
X157891Y366500D01*
X158100Y366250D01*
X158225Y365958D01*
Y364917D01*
G01Y365958D02*
X159433Y366583D01*
G01Y369350D02*
X156933D01*
X158725Y367808D01*
Y369892D01*
G01X159433Y371950D02*
X156933D01*
X157433Y371450D01*
G01X159433D02*
Y372450D01*
G01X158391Y374258D02*
X158100Y374550D01*
X157933Y374800D01*
X157850Y375133D01*
X157933Y375425D01*
X158100Y375633D01*
X158350Y375800D01*
X158641Y375842D01*
X158891Y375800D01*
X159141Y375633D01*
X159350Y375383D01*
X159433Y375092D01*
X159350Y374758D01*
X159100Y374467D01*
X158725Y374300D01*
X158308Y374258D01*
X157766Y374342D01*
X157475Y374467D01*
X157183Y374675D01*
X156975Y374967D01*
X156933Y375258D01*
X157016Y375550D01*
X157225Y375758D01*
G01X145600Y365317D02*
X143100D01*
Y366358D01*
X143225Y366692D01*
X143392Y366900D01*
X143725Y366983D01*
X144058Y366900D01*
X144267Y366650D01*
X144392Y366358D01*
Y365317D01*
G01Y366358D02*
X145600Y366983D01*
G01Y369750D02*
X143100D01*
X144892Y368208D01*
Y370292D01*
G01X143100Y372350D02*
X143183Y372017D01*
X143392Y371767D01*
X143642Y371600D01*
X143975Y371475D01*
X144350Y371433D01*
X144725Y371475D01*
X145058Y371600D01*
X145308Y371767D01*
X145517Y372017D01*
X145600Y372350D01*
X145517Y372683D01*
X145308Y372933D01*
X145058Y373100D01*
X144725Y373225D01*
X144350Y373267D01*
X143975Y373225D01*
X143642Y373100D01*
X143392Y372933D01*
X143183Y372683D01*
X143100Y372350D01*
G01X145600Y375367D02*
X145058Y375450D01*
X144600Y375575D01*
X144183Y375742D01*
X143725Y375950D01*
X143100Y376283D01*
Y374617D01*
G01X167195Y364943D02*
X164695D01*
Y365984D01*
X164820Y366318D01*
X164987Y366526D01*
X165320Y366609D01*
X165653Y366526D01*
X165862Y366276D01*
X165987Y365984D01*
Y364943D01*
G01Y365984D02*
X167195Y366609D01*
G01Y369376D02*
X164695D01*
X166487Y367834D01*
Y369918D01*
G01X167195Y372476D02*
X164695D01*
X166487Y370934D01*
Y373018D01*
G01X166903Y374368D02*
X167112Y374659D01*
X167195Y374993D01*
X167112Y375326D01*
X166862Y375618D01*
X166487Y375826D01*
X166112Y375909D01*
X165653D01*
X165278Y375826D01*
X164945Y375618D01*
X164778Y375368D01*
X164695Y375076D01*
X164778Y374743D01*
X164945Y374493D01*
X165195Y374326D01*
X165528Y374243D01*
X165820Y374326D01*
X166112Y374534D01*
X166278Y374784D01*
X166320Y375076D01*
X166237Y375409D01*
X166028Y375659D01*
X165653Y375909D01*
G01X139508Y367067D02*
X139383Y366817D01*
X139300Y366525D01*
Y366192D01*
X139425Y365817D01*
X139633Y365525D01*
X139883Y365317D01*
X140300Y365150D01*
X140675Y365108D01*
X141050Y365192D01*
X141300Y365317D01*
X141550Y365567D01*
X141717Y365858D01*
X141800Y366150D01*
Y366442D01*
X141717Y366733D01*
X141592Y366983D01*
X141425Y367192D01*
G01Y368333D02*
X141633Y368583D01*
X141758Y368875D01*
X141800Y369250D01*
X141717Y369625D01*
X141550Y369917D01*
X141258Y370125D01*
X140925Y370167D01*
X140592Y370083D01*
X140383Y369875D01*
X140217Y369583D01*
X140175Y369292D01*
X140217Y369000D01*
X140383Y368625D01*
X139300Y368750D01*
Y369875D01*
G01X141800Y372850D02*
X139300D01*
X141092Y371308D01*
Y373392D01*
G01X139717Y374658D02*
X139467Y374908D01*
X139342Y375200D01*
X139300Y375533D01*
X139383Y375950D01*
X139592Y376242D01*
X139842Y376325D01*
X140092Y376283D01*
X140300Y376117D01*
X140717Y375283D01*
X141008Y374908D01*
X141425Y374658D01*
X141800Y374575D01*
Y376325D01*
G01X161103Y366693D02*
X160978Y366443D01*
X160895Y366151D01*
Y365818D01*
X161020Y365443D01*
X161228Y365151D01*
X161478Y364943D01*
X161895Y364776D01*
X162270Y364734D01*
X162645Y364818D01*
X162895Y364943D01*
X163145Y365193D01*
X163312Y365484D01*
X163395Y365776D01*
Y366068D01*
X163312Y366359D01*
X163187Y366609D01*
X163020Y366818D01*
G01Y367959D02*
X163228Y368209D01*
X163353Y368501D01*
X163395Y368876D01*
X163312Y369251D01*
X163145Y369543D01*
X162853Y369751D01*
X162520Y369793D01*
X162187Y369709D01*
X161978Y369501D01*
X161812Y369209D01*
X161770Y368918D01*
X161812Y368626D01*
X161978Y368251D01*
X160895Y368376D01*
Y369501D01*
G01X163395Y371893D02*
X162853Y371976D01*
X162395Y372101D01*
X161978Y372268D01*
X161520Y372476D01*
X160895Y372809D01*
Y371143D01*
G01Y375076D02*
X160978Y374743D01*
X161187Y374493D01*
X161437Y374326D01*
X161770Y374201D01*
X162145Y374159D01*
X162520Y374201D01*
X162853Y374326D01*
X163103Y374493D01*
X163312Y374743D01*
X163395Y375076D01*
X163312Y375409D01*
X163103Y375659D01*
X162853Y375826D01*
X162520Y375951D01*
X162145Y375993D01*
X161770Y375951D01*
X161437Y375826D01*
X161187Y375659D01*
X160978Y375409D01*
X160895Y375076D01*
G01X191767Y480792D02*
X191517Y480917D01*
X191225Y481000D01*
X190892D01*
X190517Y480875D01*
X190225Y480667D01*
X190017Y480417D01*
X189850Y480000D01*
X189808Y479625D01*
X189892Y479250D01*
X190017Y479000D01*
X190267Y478750D01*
X190558Y478583D01*
X190850Y478500D01*
X191142D01*
X191433Y478583D01*
X191683Y478708D01*
X191892Y478875D01*
G01X193867Y478500D02*
X193950Y479042D01*
X194075Y479500D01*
X194242Y479917D01*
X194450Y480375D01*
X194783Y481000D01*
X193117D01*
G01X197050D02*
X196717Y480917D01*
X196467Y480708D01*
X196300Y480458D01*
X196175Y480125D01*
X196133Y479750D01*
X196175Y479375D01*
X196300Y479042D01*
X196467Y478792D01*
X196717Y478583D01*
X197050Y478500D01*
X197383Y478583D01*
X197633Y478792D01*
X197800Y479042D01*
X197925Y479375D01*
X197967Y479750D01*
X197925Y480125D01*
X197800Y480458D01*
X197633Y480708D01*
X197383Y480917D01*
X197050Y481000D01*
G01X199233Y478875D02*
X199483Y478667D01*
X199775Y478542D01*
X200150Y478500D01*
X200525Y478583D01*
X200817Y478750D01*
X201025Y479042D01*
X201067Y479375D01*
X200983Y479708D01*
X200775Y479917D01*
X200483Y480083D01*
X200192Y480125D01*
X199900Y480083D01*
X199525Y479917D01*
X199650Y481000D01*
X200775D01*
G01X191767Y476292D02*
X191517Y476417D01*
X191225Y476500D01*
X190892D01*
X190517Y476375D01*
X190225Y476167D01*
X190017Y475917D01*
X189850Y475500D01*
X189808Y475125D01*
X189892Y474750D01*
X190017Y474500D01*
X190267Y474250D01*
X190558Y474083D01*
X190850Y474000D01*
X191142D01*
X191433Y474083D01*
X191683Y474208D01*
X191892Y474375D01*
G01X193867Y474000D02*
X193950Y474542D01*
X194075Y475000D01*
X194242Y475417D01*
X194450Y475875D01*
X194783Y476500D01*
X193117D01*
G01X197050D02*
X196717Y476417D01*
X196467Y476208D01*
X196300Y475958D01*
X196175Y475625D01*
X196133Y475250D01*
X196175Y474875D01*
X196300Y474542D01*
X196467Y474292D01*
X196717Y474083D01*
X197050Y474000D01*
X197383Y474083D01*
X197633Y474292D01*
X197800Y474542D01*
X197925Y474875D01*
X197967Y475250D01*
X197925Y475625D01*
X197800Y475958D01*
X197633Y476208D01*
X197383Y476417D01*
X197050Y476500D01*
G01X200650Y474000D02*
Y476500D01*
X199108Y474708D01*
X201192D01*
G01X191767Y471792D02*
X191517Y471917D01*
X191225Y472000D01*
X190892D01*
X190517Y471875D01*
X190225Y471667D01*
X190017Y471417D01*
X189850Y471000D01*
X189808Y470625D01*
X189892Y470250D01*
X190017Y470000D01*
X190267Y469750D01*
X190558Y469583D01*
X190850Y469500D01*
X191142D01*
X191433Y469583D01*
X191683Y469708D01*
X191892Y469875D01*
G01X193867Y469500D02*
X193950Y470042D01*
X194075Y470500D01*
X194242Y470917D01*
X194450Y471375D01*
X194783Y472000D01*
X193117D01*
G01X197050D02*
X196717Y471917D01*
X196467Y471708D01*
X196300Y471458D01*
X196175Y471125D01*
X196133Y470750D01*
X196175Y470375D01*
X196300Y470042D01*
X196467Y469792D01*
X196717Y469583D01*
X197050Y469500D01*
X197383Y469583D01*
X197633Y469792D01*
X197800Y470042D01*
X197925Y470375D01*
X197967Y470750D01*
X197925Y471125D01*
X197800Y471458D01*
X197633Y471708D01*
X197383Y471917D01*
X197050Y472000D01*
G01X199233Y470000D02*
X199483Y469708D01*
X199817Y469542D01*
X200192Y469500D01*
X200525Y469542D01*
X200858Y469750D01*
X201067Y470000D01*
X201108Y470250D01*
X201025Y470542D01*
X200733Y470750D01*
X200442Y470833D01*
X200067D01*
G01X200442D02*
X200692Y470958D01*
X200900Y471167D01*
X200983Y471417D01*
X200900Y471667D01*
X200692Y471875D01*
X200317Y472000D01*
X199942Y471958D01*
X199567Y471792D01*
G01X151910Y468441D02*
X150110D01*
Y472441D01*
X151910D01*
G01X251317Y49893D02*
X248817D01*
Y50934D01*
X248942Y51268D01*
X249109Y51476D01*
X249442Y51559D01*
X249775Y51476D01*
X249984Y51226D01*
X250109Y50934D01*
Y49893D01*
G01Y50934D02*
X251317Y51559D01*
G01Y53743D02*
X250775Y53826D01*
X250317Y53951D01*
X249900Y54118D01*
X249442Y54326D01*
X248817Y54659D01*
Y52993D01*
G01X250942Y56009D02*
X251150Y56259D01*
X251275Y56551D01*
X251317Y56926D01*
X251234Y57301D01*
X251067Y57593D01*
X250775Y57801D01*
X250442Y57843D01*
X250109Y57759D01*
X249900Y57551D01*
X249734Y57259D01*
X249692Y56968D01*
X249734Y56676D01*
X249900Y56301D01*
X248817Y56426D01*
Y57551D01*
G01X256517Y41500D02*
Y44000D01*
X257558D01*
X257892Y43875D01*
X258100Y43708D01*
X258183Y43375D01*
X258100Y43042D01*
X257850Y42833D01*
X257558Y42708D01*
X256517D01*
G01X257558D02*
X258183Y41500D01*
G01X259658Y43583D02*
X259908Y43833D01*
X260200Y43958D01*
X260533Y44000D01*
X260950Y43917D01*
X261242Y43708D01*
X261325Y43458D01*
X261283Y43208D01*
X261117Y43000D01*
X260283Y42583D01*
X259908Y42292D01*
X259658Y41875D01*
X259575Y41500D01*
X261325D01*
G01X264050D02*
Y44000D01*
X262508Y42208D01*
X264592D01*
G01X265733Y41875D02*
X265983Y41667D01*
X266275Y41542D01*
X266650Y41500D01*
X267025Y41583D01*
X267317Y41750D01*
X267525Y42042D01*
X267567Y42375D01*
X267483Y42708D01*
X267275Y42917D01*
X266983Y43083D01*
X266692Y43125D01*
X266400Y43083D01*
X266025Y42917D01*
X266150Y44000D01*
X267275D01*
G01X247317Y49893D02*
X244817D01*
Y50934D01*
X244942Y51268D01*
X245109Y51476D01*
X245442Y51559D01*
X245775Y51476D01*
X245984Y51226D01*
X246109Y50934D01*
Y49893D01*
G01Y50934D02*
X247317Y51559D01*
G01X246942Y52909D02*
X247150Y53159D01*
X247275Y53451D01*
X247317Y53826D01*
X247234Y54201D01*
X247067Y54493D01*
X246775Y54701D01*
X246442Y54743D01*
X246109Y54659D01*
X245900Y54451D01*
X245734Y54159D01*
X245692Y53868D01*
X245734Y53576D01*
X245900Y53201D01*
X244817Y53326D01*
Y54451D01*
G01X247317Y56843D02*
X246775Y56926D01*
X246317Y57051D01*
X245900Y57218D01*
X245442Y57426D01*
X244817Y57759D01*
Y56093D01*
G01X246275Y59234D02*
X245984Y59526D01*
X245817Y59776D01*
X245734Y60109D01*
X245817Y60401D01*
X245984Y60609D01*
X246234Y60776D01*
X246525Y60818D01*
X246775Y60776D01*
X247025Y60609D01*
X247234Y60359D01*
X247317Y60068D01*
X247234Y59734D01*
X246984Y59443D01*
X246609Y59276D01*
X246192Y59234D01*
X245650Y59318D01*
X245359Y59443D01*
X245067Y59651D01*
X244859Y59943D01*
X244817Y60234D01*
X244900Y60526D01*
X245109Y60734D01*
G01X239317Y49893D02*
X236817D01*
Y50934D01*
X236942Y51268D01*
X237109Y51476D01*
X237442Y51559D01*
X237775Y51476D01*
X237984Y51226D01*
X238109Y50934D01*
Y49893D01*
G01Y50934D02*
X239317Y51559D01*
G01X238942Y52909D02*
X239150Y53159D01*
X239275Y53451D01*
X239317Y53826D01*
X239234Y54201D01*
X239067Y54493D01*
X238775Y54701D01*
X238442Y54743D01*
X238109Y54659D01*
X237900Y54451D01*
X237734Y54159D01*
X237692Y53868D01*
X237734Y53576D01*
X237900Y53201D01*
X236817Y53326D01*
Y54451D01*
G01X239317Y56843D02*
X238775Y56926D01*
X238317Y57051D01*
X237900Y57218D01*
X237442Y57426D01*
X236817Y57759D01*
Y56093D01*
G01X238942Y59109D02*
X239150Y59359D01*
X239275Y59651D01*
X239317Y60026D01*
X239234Y60401D01*
X239067Y60693D01*
X238775Y60901D01*
X238442Y60943D01*
X238109Y60859D01*
X237900Y60651D01*
X237734Y60359D01*
X237692Y60068D01*
X237734Y59776D01*
X237900Y59401D01*
X236817Y59526D01*
Y60651D01*
G01X256567Y36500D02*
Y39000D01*
X257608D01*
X257942Y38875D01*
X258150Y38708D01*
X258233Y38375D01*
X258150Y38042D01*
X257900Y37833D01*
X257608Y37708D01*
X256567D01*
G01X257608D02*
X258233Y36500D01*
G01X259792Y36792D02*
X260083Y36583D01*
X260417Y36500D01*
X260750Y36583D01*
X261042Y36833D01*
X261250Y37208D01*
X261333Y37583D01*
Y38042D01*
X261250Y38417D01*
X261042Y38750D01*
X260792Y38917D01*
X260500Y39000D01*
X260167Y38917D01*
X259917Y38750D01*
X259750Y38500D01*
X259667Y38167D01*
X259750Y37875D01*
X259958Y37583D01*
X260208Y37417D01*
X260500Y37375D01*
X260833Y37458D01*
X261083Y37667D01*
X261333Y38042D01*
G01X263600Y39000D02*
X263267Y38917D01*
X263017Y38708D01*
X262850Y38458D01*
X262725Y38125D01*
X262683Y37750D01*
X262725Y37375D01*
X262850Y37042D01*
X263017Y36792D01*
X263267Y36583D01*
X263600Y36500D01*
X263933Y36583D01*
X264183Y36792D01*
X264350Y37042D01*
X264475Y37375D01*
X264517Y37750D01*
X264475Y38125D01*
X264350Y38458D01*
X264183Y38708D01*
X263933Y38917D01*
X263600Y39000D01*
G01X256517Y32000D02*
Y34500D01*
X257558D01*
X257892Y34375D01*
X258100Y34208D01*
X258183Y33875D01*
X258100Y33542D01*
X257850Y33333D01*
X257558Y33208D01*
X256517D01*
G01X257558D02*
X258183Y32000D01*
G01X260450D02*
Y34500D01*
X259950Y34000D01*
G01Y32000D02*
X260950D01*
G01X263550Y34500D02*
X263217Y34417D01*
X262967Y34208D01*
X262800Y33958D01*
X262675Y33625D01*
X262633Y33250D01*
X262675Y32875D01*
X262800Y32542D01*
X262967Y32292D01*
X263217Y32083D01*
X263550Y32000D01*
X263883Y32083D01*
X264133Y32292D01*
X264300Y32542D01*
X264425Y32875D01*
X264467Y33250D01*
X264425Y33625D01*
X264300Y33958D01*
X264133Y34208D01*
X263883Y34417D01*
X263550Y34500D01*
G01X265733Y32375D02*
X265983Y32167D01*
X266275Y32042D01*
X266650Y32000D01*
X267025Y32083D01*
X267317Y32250D01*
X267525Y32542D01*
X267567Y32875D01*
X267483Y33208D01*
X267275Y33417D01*
X266983Y33583D01*
X266692Y33625D01*
X266400Y33583D01*
X266025Y33417D01*
X266150Y34500D01*
X267275D01*
G01X256567Y27500D02*
Y30000D01*
X257608D01*
X257942Y29875D01*
X258150Y29708D01*
X258233Y29375D01*
X258150Y29042D01*
X257900Y28833D01*
X257608Y28708D01*
X256567D01*
G01X257608D02*
X258233Y27500D01*
G01X260500D02*
X260792Y27542D01*
X261125Y27667D01*
X261333Y27875D01*
X261417Y28167D01*
X261333Y28458D01*
X261083Y28708D01*
X260708Y28833D01*
X260292D01*
X260042Y28917D01*
X259833Y29125D01*
X259750Y29417D01*
X259875Y29708D01*
X260167Y29917D01*
X260500Y30000D01*
X260833Y29917D01*
X261125Y29708D01*
X261250Y29417D01*
X261167Y29125D01*
X260958Y28917D01*
X260708Y28833D01*
X260292D01*
X259917Y28708D01*
X259667Y28458D01*
X259583Y28167D01*
X259667Y27875D01*
X259875Y27667D01*
X260208Y27542D01*
X260500Y27500D01*
G01X262892Y27792D02*
X263183Y27583D01*
X263517Y27500D01*
X263850Y27583D01*
X264142Y27833D01*
X264350Y28208D01*
X264433Y28583D01*
Y29042D01*
X264350Y29417D01*
X264142Y29750D01*
X263892Y29917D01*
X263600Y30000D01*
X263267Y29917D01*
X263017Y29750D01*
X262850Y29500D01*
X262767Y29167D01*
X262850Y28875D01*
X263058Y28583D01*
X263308Y28417D01*
X263600Y28375D01*
X263933Y28458D01*
X264183Y28667D01*
X264433Y29042D01*
G01X241025Y51643D02*
X240900Y51393D01*
X240817Y51101D01*
Y50768D01*
X240942Y50393D01*
X241150Y50101D01*
X241400Y49893D01*
X241817Y49726D01*
X242192Y49684D01*
X242567Y49768D01*
X242817Y49893D01*
X243067Y50143D01*
X243234Y50434D01*
X243317Y50726D01*
Y51018D01*
X243234Y51309D01*
X243109Y51559D01*
X242942Y51768D01*
G01X243317Y53743D02*
X242775Y53826D01*
X242317Y53951D01*
X241900Y54118D01*
X241442Y54326D01*
X240817Y54659D01*
Y52993D01*
G01X243317Y57426D02*
X240817D01*
X242609Y55884D01*
Y57968D01*
G01X242817Y59109D02*
X243109Y59359D01*
X243275Y59693D01*
X243317Y60068D01*
X243275Y60401D01*
X243067Y60734D01*
X242817Y60943D01*
X242567Y60984D01*
X242275Y60901D01*
X242067Y60609D01*
X241984Y60318D01*
Y59943D01*
G01Y60318D02*
X241859Y60568D01*
X241650Y60776D01*
X241400Y60859D01*
X241150Y60776D01*
X240942Y60568D01*
X240817Y60193D01*
X240859Y59818D01*
X241025Y59443D01*
G01X216500Y79483D02*
X218292D01*
X218667Y79650D01*
X218917Y79983D01*
X219000Y80400D01*
X218917Y80817D01*
X218667Y81150D01*
X218292Y81317D01*
X216500D01*
G01X219000Y84000D02*
X216500D01*
X218292Y82458D01*
Y84542D01*
G01X219000Y86517D02*
X218458Y86600D01*
X218000Y86725D01*
X217583Y86892D01*
X217125Y87100D01*
X216500Y87433D01*
Y85767D01*
G01X231109Y91349D02*
Y77949D01*
G01X221109Y91349D02*
X231109D01*
G01X221109Y77949D02*
Y91349D01*
G01X231109Y77949D02*
X221109D01*
G01X236000Y85483D02*
X237792D01*
X238167Y85650D01*
X238417Y85983D01*
X238500Y86400D01*
X238417Y86817D01*
X238167Y87150D01*
X237792Y87317D01*
X236000D01*
G01X238500Y90000D02*
X236000D01*
X237792Y88458D01*
Y90542D01*
G01X238208Y91892D02*
X238417Y92183D01*
X238500Y92517D01*
X238417Y92850D01*
X238167Y93142D01*
X237792Y93350D01*
X237417Y93433D01*
X236958D01*
X236583Y93350D01*
X236250Y93142D01*
X236083Y92892D01*
X236000Y92600D01*
X236083Y92267D01*
X236250Y92017D01*
X236500Y91850D01*
X236833Y91767D01*
X237125Y91850D01*
X237417Y92058D01*
X237583Y92308D01*
X237625Y92600D01*
X237542Y92933D01*
X237333Y93183D01*
X236958Y93433D01*
G01X250609Y91349D02*
Y77949D01*
G01X240609Y91349D02*
X250609D01*
G01X240609Y77949D02*
Y91349D01*
G01X250609Y77949D02*
X240609D01*
G01X248791Y63727D02*
X252791D01*
Y71127D01*
G01X212800Y99517D02*
X210300D01*
Y100558D01*
X210425Y100892D01*
X210592Y101100D01*
X210925Y101183D01*
X211258Y101100D01*
X211467Y100850D01*
X211592Y100558D01*
Y99517D01*
G01Y100558D02*
X212800Y101183D01*
G01Y103950D02*
X210300D01*
X212092Y102408D01*
Y104492D01*
G01X212800Y106467D02*
X212258Y106550D01*
X211800Y106675D01*
X211383Y106842D01*
X210925Y107050D01*
X210300Y107383D01*
Y105717D01*
G01X212800Y109650D02*
X212758Y109942D01*
X212633Y110275D01*
X212425Y110483D01*
X212133Y110567D01*
X211842Y110483D01*
X211592Y110233D01*
X211467Y109858D01*
Y109442D01*
X211383Y109192D01*
X211175Y108983D01*
X210883Y108900D01*
X210592Y109025D01*
X210383Y109317D01*
X210300Y109650D01*
X210383Y109983D01*
X210592Y110275D01*
X210883Y110400D01*
X211175Y110317D01*
X211383Y110108D01*
X211467Y109858D01*
Y109442D01*
X211592Y109067D01*
X211842Y108817D01*
X212133Y108733D01*
X212425Y108817D01*
X212633Y109025D01*
X212758Y109358D01*
X212800Y109650D01*
G01X221517Y54000D02*
Y56500D01*
X222558D01*
X222892Y56375D01*
X223100Y56208D01*
X223183Y55875D01*
X223100Y55542D01*
X222850Y55333D01*
X222558Y55208D01*
X221517D01*
G01X222558D02*
X223183Y54000D01*
G01X224533Y54375D02*
X224783Y54167D01*
X225075Y54042D01*
X225450Y54000D01*
X225825Y54083D01*
X226117Y54250D01*
X226325Y54542D01*
X226367Y54875D01*
X226283Y55208D01*
X226075Y55417D01*
X225783Y55583D01*
X225492Y55625D01*
X225200Y55583D01*
X224825Y55417D01*
X224950Y56500D01*
X226075D01*
G01X229050Y54000D02*
Y56500D01*
X227508Y54708D01*
X229592D01*
G01X232150Y54000D02*
Y56500D01*
X230608Y54708D01*
X232692D01*
G01X228300Y70000D02*
Y66000D01*
X235700D01*
G01X221567Y58500D02*
Y61000D01*
X222608D01*
X222942Y60875D01*
X223150Y60708D01*
X223233Y60375D01*
X223150Y60042D01*
X222900Y59833D01*
X222608Y59708D01*
X221567D01*
G01X222608D02*
X223233Y58500D01*
G01X224792Y58792D02*
X225083Y58583D01*
X225417Y58500D01*
X225750Y58583D01*
X226042Y58833D01*
X226250Y59208D01*
X226333Y59583D01*
Y60042D01*
X226250Y60417D01*
X226042Y60750D01*
X225792Y60917D01*
X225500Y61000D01*
X225167Y60917D01*
X224917Y60750D01*
X224750Y60500D01*
X224667Y60167D01*
X224750Y59875D01*
X224958Y59583D01*
X225208Y59417D01*
X225500Y59375D01*
X225833Y59458D01*
X226083Y59667D01*
X226333Y60042D01*
G01X227808Y59542D02*
X228100Y59833D01*
X228350Y60000D01*
X228683Y60083D01*
X228975Y60000D01*
X229183Y59833D01*
X229350Y59583D01*
X229392Y59292D01*
X229350Y59042D01*
X229183Y58792D01*
X228933Y58583D01*
X228642Y58500D01*
X228308Y58583D01*
X228017Y58833D01*
X227850Y59208D01*
X227808Y59625D01*
X227892Y60167D01*
X228017Y60458D01*
X228225Y60750D01*
X228517Y60958D01*
X228808Y61000D01*
X229100Y60917D01*
X229308Y60708D01*
G01X225800Y75000D02*
Y71000D01*
X233200D01*
G01X253517Y103000D02*
Y105500D01*
X254558D01*
X254892Y105375D01*
X255100Y105208D01*
X255183Y104875D01*
X255100Y104542D01*
X254850Y104333D01*
X254558Y104208D01*
X253517D01*
G01X254558D02*
X255183Y103000D01*
G01X256533Y103375D02*
X256783Y103167D01*
X257075Y103042D01*
X257450Y103000D01*
X257825Y103083D01*
X258117Y103250D01*
X258325Y103542D01*
X258367Y103875D01*
X258283Y104208D01*
X258075Y104417D01*
X257783Y104583D01*
X257492Y104625D01*
X257200Y104583D01*
X256825Y104417D01*
X256950Y105500D01*
X258075D01*
G01X260467Y103000D02*
X260550Y103542D01*
X260675Y104000D01*
X260842Y104417D01*
X261050Y104875D01*
X261383Y105500D01*
X259717D01*
G01X264150Y103000D02*
Y105500D01*
X262608Y103708D01*
X264692D01*
G01X260700Y88000D02*
Y92000D01*
X253300D01*
G01X248530Y72236D02*
X244530D01*
Y64836D01*
G01X236880Y64862D02*
X240880D01*
Y72262D01*
G01X253517Y99000D02*
Y101500D01*
X254558D01*
X254892Y101375D01*
X255100Y101208D01*
X255183Y100875D01*
X255100Y100542D01*
X254850Y100333D01*
X254558Y100208D01*
X253517D01*
G01X254558D02*
X255183Y99000D01*
G01X256533Y99375D02*
X256783Y99167D01*
X257075Y99042D01*
X257450Y99000D01*
X257825Y99083D01*
X258117Y99250D01*
X258325Y99542D01*
X258367Y99875D01*
X258283Y100208D01*
X258075Y100417D01*
X257783Y100583D01*
X257492Y100625D01*
X257200Y100583D01*
X256825Y100417D01*
X256950Y101500D01*
X258075D01*
G01X260550Y99000D02*
X260842Y99042D01*
X261175Y99167D01*
X261383Y99375D01*
X261467Y99667D01*
X261383Y99958D01*
X261133Y100208D01*
X260758Y100333D01*
X260342D01*
X260092Y100417D01*
X259883Y100625D01*
X259800Y100917D01*
X259925Y101208D01*
X260217Y101417D01*
X260550Y101500D01*
X260883Y101417D01*
X261175Y101208D01*
X261300Y100917D01*
X261217Y100625D01*
X261008Y100417D01*
X260758Y100333D01*
X260342D01*
X259967Y100208D01*
X259717Y99958D01*
X259633Y99667D01*
X259717Y99375D01*
X259925Y99167D01*
X260258Y99042D01*
X260550Y99000D01*
G01X262858Y101083D02*
X263108Y101333D01*
X263400Y101458D01*
X263733Y101500D01*
X264150Y101417D01*
X264442Y101208D01*
X264525Y100958D01*
X264483Y100708D01*
X264317Y100500D01*
X263483Y100083D01*
X263108Y99792D01*
X262858Y99375D01*
X262775Y99000D01*
X264525D01*
G01X260700Y93000D02*
Y97000D01*
X253300D01*
G01X212494Y63649D02*
X209994D01*
Y64690D01*
X210119Y65024D01*
X210286Y65232D01*
X210619Y65315D01*
X210952Y65232D01*
X211161Y64982D01*
X211286Y64690D01*
Y63649D01*
G01Y64690D02*
X212494Y65315D01*
G01X212119Y66665D02*
X212327Y66915D01*
X212452Y67207D01*
X212494Y67582D01*
X212411Y67957D01*
X212244Y68249D01*
X211952Y68457D01*
X211619Y68499D01*
X211286Y68415D01*
X211077Y68207D01*
X210911Y67915D01*
X210869Y67624D01*
X210911Y67332D01*
X211077Y66957D01*
X209994Y67082D01*
Y68207D01*
G01X212494Y70682D02*
X212452Y70974D01*
X212327Y71307D01*
X212119Y71515D01*
X211827Y71599D01*
X211536Y71515D01*
X211286Y71265D01*
X211161Y70890D01*
Y70474D01*
X211077Y70224D01*
X210869Y70015D01*
X210577Y69932D01*
X210286Y70057D01*
X210077Y70349D01*
X209994Y70682D01*
X210077Y71015D01*
X210286Y71307D01*
X210577Y71432D01*
X210869Y71349D01*
X211077Y71140D01*
X211161Y70890D01*
Y70474D01*
X211286Y70099D01*
X211536Y69849D01*
X211827Y69765D01*
X212119Y69849D01*
X212327Y70057D01*
X212452Y70390D01*
X212494Y70682D01*
G01Y73699D02*
X211952Y73782D01*
X211494Y73907D01*
X211077Y74074D01*
X210619Y74282D01*
X209994Y74615D01*
Y72949D01*
G01X218227Y64815D02*
X222227D01*
Y72215D01*
G01X221767Y100792D02*
X221517Y100917D01*
X221225Y101000D01*
X220892D01*
X220517Y100875D01*
X220225Y100667D01*
X220017Y100417D01*
X219850Y100000D01*
X219808Y99625D01*
X219892Y99250D01*
X220017Y99000D01*
X220267Y98750D01*
X220558Y98583D01*
X220850Y98500D01*
X221142D01*
X221433Y98583D01*
X221683Y98708D01*
X221892Y98875D01*
G01X223867Y98500D02*
X223950Y99042D01*
X224075Y99500D01*
X224242Y99917D01*
X224450Y100375D01*
X224783Y101000D01*
X223117D01*
G01X226133Y99000D02*
X226383Y98708D01*
X226717Y98542D01*
X227092Y98500D01*
X227425Y98542D01*
X227758Y98750D01*
X227967Y99000D01*
X228008Y99250D01*
X227925Y99542D01*
X227633Y99750D01*
X227342Y99833D01*
X226967D01*
G01X227342D02*
X227592Y99958D01*
X227800Y100167D01*
X227883Y100417D01*
X227800Y100667D01*
X227592Y100875D01*
X227217Y101000D01*
X226842Y100958D01*
X226467Y100792D01*
G01X230150Y101000D02*
X229817Y100917D01*
X229567Y100708D01*
X229400Y100458D01*
X229275Y100125D01*
X229233Y99750D01*
X229275Y99375D01*
X229400Y99042D01*
X229567Y98792D01*
X229817Y98583D01*
X230150Y98500D01*
X230483Y98583D01*
X230733Y98792D01*
X230900Y99042D01*
X231025Y99375D01*
X231067Y99750D01*
X231025Y100125D01*
X230900Y100458D01*
X230733Y100708D01*
X230483Y100917D01*
X230150Y101000D01*
G01X240267Y104292D02*
X240017Y104417D01*
X239725Y104500D01*
X239392D01*
X239017Y104375D01*
X238725Y104167D01*
X238517Y103917D01*
X238350Y103500D01*
X238308Y103125D01*
X238392Y102750D01*
X238517Y102500D01*
X238767Y102250D01*
X239058Y102083D01*
X239350Y102000D01*
X239642D01*
X239933Y102083D01*
X240183Y102208D01*
X240392Y102375D01*
G01X242367Y102000D02*
X242450Y102542D01*
X242575Y103000D01*
X242742Y103417D01*
X242950Y103875D01*
X243283Y104500D01*
X241617D01*
G01X244633Y102500D02*
X244883Y102208D01*
X245217Y102042D01*
X245592Y102000D01*
X245925Y102042D01*
X246258Y102250D01*
X246467Y102500D01*
X246508Y102750D01*
X246425Y103042D01*
X246133Y103250D01*
X245842Y103333D01*
X245467D01*
G01X245842D02*
X246092Y103458D01*
X246300Y103667D01*
X246383Y103917D01*
X246300Y104167D01*
X246092Y104375D01*
X245717Y104500D01*
X245342Y104458D01*
X244967Y104292D01*
G01X249150Y102000D02*
Y104500D01*
X247608Y102708D01*
X249692D01*
G01X214202Y65399D02*
X214077Y65149D01*
X213994Y64857D01*
Y64524D01*
X214119Y64149D01*
X214327Y63857D01*
X214577Y63649D01*
X214994Y63482D01*
X215369Y63440D01*
X215744Y63524D01*
X215994Y63649D01*
X216244Y63899D01*
X216411Y64190D01*
X216494Y64482D01*
Y64774D01*
X216411Y65065D01*
X216286Y65315D01*
X216119Y65524D01*
G01X216494Y67499D02*
X215952Y67582D01*
X215494Y67707D01*
X215077Y67874D01*
X214619Y68082D01*
X213994Y68415D01*
Y66749D01*
G01X216494Y71182D02*
X213994D01*
X215786Y69640D01*
Y71724D01*
G01X216494Y73782D02*
X213994D01*
X214494Y73282D01*
G01X216494D02*
Y74282D01*
G01X256983Y82500D02*
Y80708D01*
X257150Y80333D01*
X257483Y80083D01*
X257900Y80000D01*
X258317Y80083D01*
X258650Y80333D01*
X258817Y80708D01*
Y82500D01*
G01X261000Y80000D02*
Y82500D01*
X260500Y82000D01*
G01Y80000D02*
X261500D01*
G01X264600D02*
Y82500D01*
X263058Y80708D01*
X265142D01*
G01X213300Y151217D02*
X210800D01*
Y152258D01*
X210925Y152592D01*
X211092Y152800D01*
X211425Y152883D01*
X211758Y152800D01*
X211967Y152550D01*
X212092Y152258D01*
Y151217D01*
G01Y152258D02*
X213300Y152883D01*
G01Y155650D02*
X210800D01*
X212592Y154108D01*
Y156192D01*
G01X213300Y158250D02*
X213258Y158542D01*
X213133Y158875D01*
X212925Y159083D01*
X212633Y159167D01*
X212342Y159083D01*
X212092Y158833D01*
X211967Y158458D01*
Y158042D01*
X211883Y157792D01*
X211675Y157583D01*
X211383Y157500D01*
X211092Y157625D01*
X210883Y157917D01*
X210800Y158250D01*
X210883Y158583D01*
X211092Y158875D01*
X211383Y159000D01*
X211675Y158917D01*
X211883Y158708D01*
X211967Y158458D01*
Y158042D01*
X212092Y157667D01*
X212342Y157417D01*
X212633Y157333D01*
X212925Y157417D01*
X213133Y157625D01*
X213258Y157958D01*
X213300Y158250D01*
G01X210800Y161350D02*
X210883Y161017D01*
X211092Y160767D01*
X211342Y160600D01*
X211675Y160475D01*
X212050Y160433D01*
X212425Y160475D01*
X212758Y160600D01*
X213008Y160767D01*
X213217Y161017D01*
X213300Y161350D01*
X213217Y161683D01*
X213008Y161933D01*
X212758Y162100D01*
X212425Y162225D01*
X212050Y162267D01*
X211675Y162225D01*
X211342Y162100D01*
X211092Y161933D01*
X210883Y161683D01*
X210800Y161350D01*
G01X244000Y161700D02*
Y159200D01*
G01X243042Y161700D02*
X244958D01*
G01X248017Y161492D02*
X247767Y161617D01*
X247475Y161700D01*
X247142D01*
X246767Y161575D01*
X246475Y161367D01*
X246267Y161117D01*
X246100Y160700D01*
X246058Y160325D01*
X246142Y159950D01*
X246267Y159700D01*
X246517Y159450D01*
X246808Y159283D01*
X247100Y159200D01*
X247392D01*
X247683Y159283D01*
X247933Y159408D01*
X248142Y159575D01*
G01X249283Y159700D02*
X249533Y159408D01*
X249867Y159242D01*
X250242Y159200D01*
X250575Y159242D01*
X250908Y159450D01*
X251117Y159700D01*
X251158Y159950D01*
X251075Y160242D01*
X250783Y160450D01*
X250492Y160533D01*
X250117D01*
G01X250492D02*
X250742Y160658D01*
X250950Y160867D01*
X251033Y161117D01*
X250950Y161367D01*
X250742Y161575D01*
X250367Y161700D01*
X249992Y161658D01*
X249617Y161492D01*
G01X267100Y156500D02*
X255900D01*
G01Y138500D02*
X267100D01*
G01X228700Y156500D02*
X239900D01*
G01X228700Y138500D02*
Y156500D01*
G01X239900Y138500D02*
X228700D01*
G01X208700Y170950D02*
X212700D01*
Y174950D01*
G01X261200Y163750D02*
Y197250D01*
X214800D01*
Y163750D01*
X261200D01*
G01X255150Y229600D02*
X266350D01*
G01X227950D02*
Y247600D01*
G01X239150Y229600D02*
X227950D01*
G01X211800Y221500D02*
Y219000D01*
G01X210842Y221500D02*
X212758D01*
G01X215817Y221292D02*
X215567Y221417D01*
X215275Y221500D01*
X214942D01*
X214567Y221375D01*
X214275Y221167D01*
X214067Y220917D01*
X213900Y220500D01*
X213858Y220125D01*
X213942Y219750D01*
X214067Y219500D01*
X214317Y219250D01*
X214608Y219083D01*
X214900Y219000D01*
X215192D01*
X215483Y219083D01*
X215733Y219208D01*
X215942Y219375D01*
G01X218000Y219000D02*
Y221500D01*
X217500Y221000D01*
G01Y219000D02*
X218500D01*
G01X266300Y222500D02*
X255100D01*
G01Y204500D02*
X266300D01*
G01X227900Y222500D02*
X239100D01*
G01X227900Y204500D02*
Y222500D01*
G01X239100Y204500D02*
X227900D01*
G01X218400Y200817D02*
X215900D01*
Y201858D01*
X216025Y202192D01*
X216192Y202400D01*
X216525Y202483D01*
X216858Y202400D01*
X217067Y202150D01*
X217192Y201858D01*
Y200817D01*
G01Y201858D02*
X218400Y202483D01*
G01Y205250D02*
X215900D01*
X217692Y203708D01*
Y205792D01*
G01X218400Y207767D02*
X217858Y207850D01*
X217400Y207975D01*
X216983Y208142D01*
X216525Y208350D01*
X215900Y208683D01*
Y207017D01*
G01X218108Y210242D02*
X218317Y210533D01*
X218400Y210867D01*
X218317Y211200D01*
X218067Y211492D01*
X217692Y211700D01*
X217317Y211783D01*
X216858D01*
X216483Y211700D01*
X216150Y211492D01*
X215983Y211242D01*
X215900Y210950D01*
X215983Y210617D01*
X216150Y210367D01*
X216400Y210200D01*
X216733Y210117D01*
X217025Y210200D01*
X217317Y210408D01*
X217483Y210658D01*
X217525Y210950D01*
X217442Y211283D01*
X217233Y211533D01*
X216858Y211783D01*
G01X207000Y195900D02*
Y201100D01*
G01X214000Y195900D02*
Y203700D01*
G01X207000Y195900D02*
X214000D01*
G01X207000Y209300D02*
Y200600D01*
G01X214000Y209300D02*
X207000D01*
G01X214000Y202900D02*
Y209300D01*
G01X208700Y195050D02*
X212700D01*
Y191050D01*
G01X211711Y175500D02*
X213711D01*
G01X231367Y201700D02*
Y199200D01*
X233033D01*
G01X234383Y199700D02*
X234633Y199408D01*
X234967Y199242D01*
X235342Y199200D01*
X235675Y199242D01*
X236008Y199450D01*
X236217Y199700D01*
X236258Y199950D01*
X236175Y200242D01*
X235883Y200450D01*
X235592Y200533D01*
X235217D01*
G01X235592D02*
X235842Y200658D01*
X236050Y200867D01*
X236133Y201117D01*
X236050Y201367D01*
X235842Y201575D01*
X235467Y201700D01*
X235092Y201658D01*
X234717Y201492D01*
G01X238400Y199200D02*
Y201700D01*
X237900Y201200D01*
G01Y199200D02*
X238900D01*
G01X256700Y298900D02*
X260700D01*
Y306300D01*
G01X245163Y265711D02*
X242663D01*
Y266752D01*
X242788Y267086D01*
X242955Y267294D01*
X243288Y267377D01*
X243621Y267294D01*
X243830Y267044D01*
X243955Y266752D01*
Y265711D01*
G01Y266752D02*
X245163Y267377D01*
G01Y270144D02*
X242663D01*
X244455Y268602D01*
Y270686D01*
G01X245163Y272744D02*
X242663D01*
X243163Y272244D01*
G01X245163D02*
Y273244D01*
G01Y275761D02*
X244621Y275844D01*
X244163Y275969D01*
X243746Y276136D01*
X243288Y276344D01*
X242663Y276677D01*
Y275011D01*
G01X254000Y289900D02*
X250000D01*
Y282500D01*
G01X235400Y265217D02*
X232900D01*
Y266258D01*
X233025Y266592D01*
X233192Y266800D01*
X233525Y266883D01*
X233858Y266800D01*
X234067Y266550D01*
X234192Y266258D01*
Y265217D01*
G01Y266258D02*
X235400Y266883D01*
G01Y269650D02*
X232900D01*
X234692Y268108D01*
Y270192D01*
G01X235400Y272250D02*
X232900D01*
X233400Y271750D01*
G01X235400D02*
Y272750D01*
G01Y275350D02*
X235358Y275642D01*
X235233Y275975D01*
X235025Y276183D01*
X234733Y276267D01*
X234442Y276183D01*
X234192Y275933D01*
X234067Y275558D01*
Y275142D01*
X233983Y274892D01*
X233775Y274683D01*
X233483Y274600D01*
X233192Y274725D01*
X232983Y275017D01*
X232900Y275350D01*
X232983Y275683D01*
X233192Y275975D01*
X233483Y276100D01*
X233775Y276017D01*
X233983Y275808D01*
X234067Y275558D01*
Y275142D01*
X234192Y274767D01*
X234442Y274517D01*
X234733Y274433D01*
X235025Y274517D01*
X235233Y274725D01*
X235358Y275058D01*
X235400Y275350D01*
G01X236900Y282500D02*
X240900D01*
Y289900D01*
G01X241332Y265742D02*
X238832D01*
Y266783D01*
X238957Y267117D01*
X239124Y267325D01*
X239457Y267408D01*
X239790Y267325D01*
X239999Y267075D01*
X240124Y266783D01*
Y265742D01*
G01Y266783D02*
X241332Y267408D01*
G01Y270175D02*
X238832D01*
X240624Y268633D01*
Y270717D01*
G01X241332Y272775D02*
X238832D01*
X239332Y272275D01*
G01X241332D02*
Y273275D01*
G01X241040Y275167D02*
X241249Y275458D01*
X241332Y275792D01*
X241249Y276125D01*
X240999Y276417D01*
X240624Y276625D01*
X240249Y276708D01*
X239790D01*
X239415Y276625D01*
X239082Y276417D01*
X238915Y276167D01*
X238832Y275875D01*
X238915Y275542D01*
X239082Y275292D01*
X239332Y275125D01*
X239665Y275042D01*
X239957Y275125D01*
X240249Y275333D01*
X240415Y275583D01*
X240457Y275875D01*
X240374Y276208D01*
X240165Y276458D01*
X239790Y276708D01*
G01X243800Y282600D02*
X247800D01*
Y290000D01*
G01X227200Y265217D02*
X224700D01*
Y266258D01*
X224825Y266592D01*
X224992Y266800D01*
X225325Y266883D01*
X225658Y266800D01*
X225867Y266550D01*
X225992Y266258D01*
Y265217D01*
G01Y266258D02*
X227200Y266883D01*
G01Y269650D02*
X224700D01*
X226492Y268108D01*
Y270192D01*
G01X225117Y271458D02*
X224867Y271708D01*
X224742Y272000D01*
X224700Y272333D01*
X224783Y272750D01*
X224992Y273042D01*
X225242Y273125D01*
X225492Y273083D01*
X225700Y272917D01*
X226117Y272083D01*
X226408Y271708D01*
X226825Y271458D01*
X227200Y271375D01*
Y273125D01*
G01X224700Y275350D02*
X224783Y275017D01*
X224992Y274767D01*
X225242Y274600D01*
X225575Y274475D01*
X225950Y274433D01*
X226325Y274475D01*
X226658Y274600D01*
X226908Y274767D01*
X227117Y275017D01*
X227200Y275350D01*
X227117Y275683D01*
X226908Y275933D01*
X226658Y276100D01*
X226325Y276225D01*
X225950Y276267D01*
X225575Y276225D01*
X225242Y276100D01*
X224992Y275933D01*
X224783Y275683D01*
X224700Y275350D01*
G01X232700Y289900D02*
X228700D01*
Y282500D01*
G01X218900Y265217D02*
X216400D01*
Y266258D01*
X216525Y266592D01*
X216692Y266800D01*
X217025Y266883D01*
X217358Y266800D01*
X217567Y266550D01*
X217692Y266258D01*
Y265217D01*
G01Y266258D02*
X218900Y266883D01*
G01Y269650D02*
X216400D01*
X218192Y268108D01*
Y270192D01*
G01X216817Y271458D02*
X216567Y271708D01*
X216442Y272000D01*
X216400Y272333D01*
X216483Y272750D01*
X216692Y273042D01*
X216942Y273125D01*
X217192Y273083D01*
X217400Y272917D01*
X217817Y272083D01*
X218108Y271708D01*
X218525Y271458D01*
X218900Y271375D01*
Y273125D01*
G01Y275350D02*
X216400D01*
X216900Y274850D01*
G01X218900D02*
Y275850D01*
G01X217400Y282000D02*
X221400D01*
Y289400D01*
G01X223100Y265217D02*
X220600D01*
Y266258D01*
X220725Y266592D01*
X220892Y266800D01*
X221225Y266883D01*
X221558Y266800D01*
X221767Y266550D01*
X221892Y266258D01*
Y265217D01*
G01Y266258D02*
X223100Y266883D01*
G01Y269650D02*
X220600D01*
X222392Y268108D01*
Y270192D01*
G01X221017Y271458D02*
X220767Y271708D01*
X220642Y272000D01*
X220600Y272333D01*
X220683Y272750D01*
X220892Y273042D01*
X221142Y273125D01*
X221392Y273083D01*
X221600Y272917D01*
X222017Y272083D01*
X222308Y271708D01*
X222725Y271458D01*
X223100Y271375D01*
Y273125D01*
G01X221017Y274558D02*
X220767Y274808D01*
X220642Y275100D01*
X220600Y275433D01*
X220683Y275850D01*
X220892Y276142D01*
X221142Y276225D01*
X221392Y276183D01*
X221600Y276017D01*
X222017Y275183D01*
X222308Y274808D01*
X222725Y274558D01*
X223100Y274475D01*
Y276225D01*
G01X224600Y282500D02*
X228600D01*
Y289900D01*
G01X249163Y265711D02*
X246663D01*
Y266752D01*
X246788Y267086D01*
X246955Y267294D01*
X247288Y267377D01*
X247621Y267294D01*
X247830Y267044D01*
X247955Y266752D01*
Y265711D01*
G01Y266752D02*
X249163Y267377D01*
G01Y270144D02*
X246663D01*
X248455Y268602D01*
Y270686D01*
G01X247080Y271952D02*
X246830Y272202D01*
X246705Y272494D01*
X246663Y272827D01*
X246746Y273244D01*
X246955Y273536D01*
X247205Y273619D01*
X247455Y273577D01*
X247663Y273411D01*
X248080Y272577D01*
X248371Y272202D01*
X248788Y271952D01*
X249163Y271869D01*
Y273619D01*
G01X248663Y274927D02*
X248955Y275177D01*
X249121Y275511D01*
X249163Y275886D01*
X249121Y276219D01*
X248913Y276552D01*
X248663Y276761D01*
X248413Y276802D01*
X248121Y276719D01*
X247913Y276427D01*
X247830Y276136D01*
Y275761D01*
G01Y276136D02*
X247705Y276386D01*
X247496Y276594D01*
X247246Y276677D01*
X246996Y276594D01*
X246788Y276386D01*
X246663Y276011D01*
X246705Y275636D01*
X246871Y275261D01*
G01X258000Y289900D02*
X254000D01*
Y282500D01*
G01X231300Y265117D02*
X228800D01*
Y266158D01*
X228925Y266492D01*
X229092Y266700D01*
X229425Y266783D01*
X229758Y266700D01*
X229967Y266450D01*
X230092Y266158D01*
Y265117D01*
G01Y266158D02*
X231300Y266783D01*
G01Y269550D02*
X228800D01*
X230592Y268008D01*
Y270092D01*
G01X229217Y271358D02*
X228967Y271608D01*
X228842Y271900D01*
X228800Y272233D01*
X228883Y272650D01*
X229092Y272942D01*
X229342Y273025D01*
X229592Y272983D01*
X229800Y272817D01*
X230217Y271983D01*
X230508Y271608D01*
X230925Y271358D01*
X231300Y271275D01*
Y273025D01*
G01Y275750D02*
X228800D01*
X230592Y274208D01*
Y276292D01*
G01X236800Y289800D02*
X232800D01*
Y282400D01*
G01X261163Y265711D02*
X258663D01*
Y266752D01*
X258788Y267086D01*
X258955Y267294D01*
X259288Y267377D01*
X259621Y267294D01*
X259830Y267044D01*
X259955Y266752D01*
Y265711D01*
G01Y266752D02*
X261163Y267377D01*
G01Y270144D02*
X258663D01*
X260455Y268602D01*
Y270686D01*
G01X259080Y271952D02*
X258830Y272202D01*
X258705Y272494D01*
X258663Y272827D01*
X258746Y273244D01*
X258955Y273536D01*
X259205Y273619D01*
X259455Y273577D01*
X259663Y273411D01*
X260080Y272577D01*
X260371Y272202D01*
X260788Y271952D01*
X261163Y271869D01*
Y273619D01*
G01Y275761D02*
X260621Y275844D01*
X260163Y275969D01*
X259746Y276136D01*
X259288Y276344D01*
X258663Y276677D01*
Y275011D01*
G01X253163Y265711D02*
X250663D01*
Y266752D01*
X250788Y267086D01*
X250955Y267294D01*
X251288Y267377D01*
X251621Y267294D01*
X251830Y267044D01*
X251955Y266752D01*
Y265711D01*
G01Y266752D02*
X253163Y267377D01*
G01Y270144D02*
X250663D01*
X252455Y268602D01*
Y270686D01*
G01X251080Y271952D02*
X250830Y272202D01*
X250705Y272494D01*
X250663Y272827D01*
X250746Y273244D01*
X250955Y273536D01*
X251205Y273619D01*
X251455Y273577D01*
X251663Y273411D01*
X252080Y272577D01*
X252371Y272202D01*
X252788Y271952D01*
X253163Y271869D01*
Y273619D01*
G01Y275844D02*
X253121Y276136D01*
X252996Y276469D01*
X252788Y276677D01*
X252496Y276761D01*
X252205Y276677D01*
X251955Y276427D01*
X251830Y276052D01*
Y275636D01*
X251746Y275386D01*
X251538Y275177D01*
X251246Y275094D01*
X250955Y275219D01*
X250746Y275511D01*
X250663Y275844D01*
X250746Y276177D01*
X250955Y276469D01*
X251246Y276594D01*
X251538Y276511D01*
X251746Y276302D01*
X251830Y276052D01*
Y275636D01*
X251955Y275261D01*
X252205Y275011D01*
X252496Y274927D01*
X252788Y275011D01*
X252996Y275219D01*
X253121Y275552D01*
X253163Y275844D01*
G01X258000Y282500D02*
X262000D01*
Y289900D01*
G01X257163Y265711D02*
X254663D01*
Y266752D01*
X254788Y267086D01*
X254955Y267294D01*
X255288Y267377D01*
X255621Y267294D01*
X255830Y267044D01*
X255955Y266752D01*
Y265711D01*
G01Y266752D02*
X257163Y267377D01*
G01Y270144D02*
X254663D01*
X256455Y268602D01*
Y270686D01*
G01X255080Y271952D02*
X254830Y272202D01*
X254705Y272494D01*
X254663Y272827D01*
X254746Y273244D01*
X254955Y273536D01*
X255205Y273619D01*
X255455Y273577D01*
X255663Y273411D01*
X256080Y272577D01*
X256371Y272202D01*
X256788Y271952D01*
X257163Y271869D01*
Y273619D01*
G01X256871Y275136D02*
X257080Y275427D01*
X257163Y275761D01*
X257080Y276094D01*
X256830Y276386D01*
X256455Y276594D01*
X256080Y276677D01*
X255621D01*
X255246Y276594D01*
X254913Y276386D01*
X254746Y276136D01*
X254663Y275844D01*
X254746Y275511D01*
X254913Y275261D01*
X255163Y275094D01*
X255496Y275011D01*
X255788Y275094D01*
X256080Y275302D01*
X256246Y275552D01*
X256288Y275844D01*
X256205Y276177D01*
X255996Y276427D01*
X255621Y276677D01*
G01X265163Y265711D02*
X262663D01*
Y266752D01*
X262788Y267086D01*
X262955Y267294D01*
X263288Y267377D01*
X263621Y267294D01*
X263830Y267044D01*
X263955Y266752D01*
Y265711D01*
G01Y266752D02*
X265163Y267377D01*
G01Y270144D02*
X262663D01*
X264455Y268602D01*
Y270686D01*
G01X264663Y271827D02*
X264955Y272077D01*
X265121Y272411D01*
X265163Y272786D01*
X265121Y273119D01*
X264913Y273452D01*
X264663Y273661D01*
X264413Y273702D01*
X264121Y273619D01*
X263913Y273327D01*
X263830Y273036D01*
Y272661D01*
G01Y273036D02*
X263705Y273286D01*
X263496Y273494D01*
X263246Y273577D01*
X262996Y273494D01*
X262788Y273286D01*
X262663Y272911D01*
X262705Y272536D01*
X262871Y272161D01*
G01X264663Y274927D02*
X264955Y275177D01*
X265121Y275511D01*
X265163Y275886D01*
X265121Y276219D01*
X264913Y276552D01*
X264663Y276761D01*
X264413Y276802D01*
X264121Y276719D01*
X263913Y276427D01*
X263830Y276136D01*
Y275761D01*
G01Y276136D02*
X263705Y276386D01*
X263496Y276594D01*
X263246Y276677D01*
X262996Y276594D01*
X262788Y276386D01*
X262663Y276011D01*
X262705Y275636D01*
X262871Y275261D01*
G01X213200Y282000D02*
Y286000D01*
X205800D01*
G01X214800Y265217D02*
X212300D01*
Y266258D01*
X212425Y266592D01*
X212592Y266800D01*
X212925Y266883D01*
X213258Y266800D01*
X213467Y266550D01*
X213592Y266258D01*
Y265217D01*
G01Y266258D02*
X214800Y266883D01*
G01Y269650D02*
X212300D01*
X214092Y268108D01*
Y270192D01*
G01X214800Y272167D02*
X214258Y272250D01*
X213800Y272375D01*
X213383Y272542D01*
X212925Y272750D01*
X212300Y273083D01*
Y271417D01*
G01X214300Y274433D02*
X214592Y274683D01*
X214758Y275017D01*
X214800Y275392D01*
X214758Y275725D01*
X214550Y276058D01*
X214300Y276267D01*
X214050Y276308D01*
X213758Y276225D01*
X213550Y275933D01*
X213467Y275642D01*
Y275267D01*
G01Y275642D02*
X213342Y275892D01*
X213133Y276100D01*
X212883Y276183D01*
X212633Y276100D01*
X212425Y275892D01*
X212300Y275517D01*
X212342Y275142D01*
X212508Y274767D01*
G01X217300Y289400D02*
X213300D01*
Y282000D01*
G01X249267Y263792D02*
X249017Y263917D01*
X248725Y264000D01*
X248392D01*
X248017Y263875D01*
X247725Y263667D01*
X247517Y263417D01*
X247350Y263000D01*
X247308Y262625D01*
X247392Y262250D01*
X247517Y262000D01*
X247767Y261750D01*
X248058Y261583D01*
X248350Y261500D01*
X248642D01*
X248933Y261583D01*
X249183Y261708D01*
X249392Y261875D01*
G01X250533D02*
X250783Y261667D01*
X251075Y261542D01*
X251450Y261500D01*
X251825Y261583D01*
X252117Y261750D01*
X252325Y262042D01*
X252367Y262375D01*
X252283Y262708D01*
X252075Y262917D01*
X251783Y263083D01*
X251492Y263125D01*
X251200Y263083D01*
X250825Y262917D01*
X250950Y264000D01*
X252075D01*
G01X253633Y261875D02*
X253883Y261667D01*
X254175Y261542D01*
X254550Y261500D01*
X254925Y261583D01*
X255217Y261750D01*
X255425Y262042D01*
X255467Y262375D01*
X255383Y262708D01*
X255175Y262917D01*
X254883Y263083D01*
X254592Y263125D01*
X254300Y263083D01*
X253925Y262917D01*
X254050Y264000D01*
X255175D01*
G01X257650Y261500D02*
Y264000D01*
X257150Y263500D01*
G01Y261500D02*
X258150D01*
G01X236267Y263792D02*
X236017Y263917D01*
X235725Y264000D01*
X235392D01*
X235017Y263875D01*
X234725Y263667D01*
X234517Y263417D01*
X234350Y263000D01*
X234308Y262625D01*
X234392Y262250D01*
X234517Y262000D01*
X234767Y261750D01*
X235058Y261583D01*
X235350Y261500D01*
X235642D01*
X235933Y261583D01*
X236183Y261708D01*
X236392Y261875D01*
G01X237533D02*
X237783Y261667D01*
X238075Y261542D01*
X238450Y261500D01*
X238825Y261583D01*
X239117Y261750D01*
X239325Y262042D01*
X239367Y262375D01*
X239283Y262708D01*
X239075Y262917D01*
X238783Y263083D01*
X238492Y263125D01*
X238200Y263083D01*
X237825Y262917D01*
X237950Y264000D01*
X239075D01*
G01X240633Y261875D02*
X240883Y261667D01*
X241175Y261542D01*
X241550Y261500D01*
X241925Y261583D01*
X242217Y261750D01*
X242425Y262042D01*
X242467Y262375D01*
X242383Y262708D01*
X242175Y262917D01*
X241883Y263083D01*
X241592Y263125D01*
X241300Y263083D01*
X240925Y262917D01*
X241050Y264000D01*
X242175D01*
G01X243858Y263583D02*
X244108Y263833D01*
X244400Y263958D01*
X244733Y264000D01*
X245150Y263917D01*
X245442Y263708D01*
X245525Y263458D01*
X245483Y263208D01*
X245317Y263000D01*
X244483Y262583D01*
X244108Y262292D01*
X243858Y261875D01*
X243775Y261500D01*
X245525D01*
G01X218600Y244900D02*
Y242400D01*
G01X217642Y244900D02*
X219558D01*
G01X222617Y244692D02*
X222367Y244817D01*
X222075Y244900D01*
X221742D01*
X221367Y244775D01*
X221075Y244567D01*
X220867Y244317D01*
X220700Y243900D01*
X220658Y243525D01*
X220742Y243150D01*
X220867Y242900D01*
X221117Y242650D01*
X221408Y242483D01*
X221700Y242400D01*
X221992D01*
X222283Y242483D01*
X222533Y242608D01*
X222742Y242775D01*
G01X224008Y244483D02*
X224258Y244733D01*
X224550Y244858D01*
X224883Y244900D01*
X225300Y244817D01*
X225592Y244608D01*
X225675Y244358D01*
X225633Y244108D01*
X225467Y243900D01*
X224633Y243483D01*
X224258Y243192D01*
X224008Y242775D01*
X223925Y242400D01*
X225675D01*
G01X266350Y247600D02*
X255150D01*
G01X227950D02*
X239150D01*
G01X241733Y310517D02*
X239233D01*
Y311558D01*
X239358Y311892D01*
X239525Y312100D01*
X239858Y312183D01*
X240191Y312100D01*
X240400Y311850D01*
X240525Y311558D01*
Y310517D01*
G01Y311558D02*
X241733Y312183D01*
G01Y314950D02*
X239233D01*
X241025Y313408D01*
Y315492D01*
G01X241233Y316633D02*
X241525Y316883D01*
X241691Y317217D01*
X241733Y317592D01*
X241691Y317925D01*
X241483Y318258D01*
X241233Y318467D01*
X240983Y318508D01*
X240691Y318425D01*
X240483Y318133D01*
X240400Y317842D01*
Y317467D01*
G01Y317842D02*
X240275Y318092D01*
X240066Y318300D01*
X239816Y318383D01*
X239566Y318300D01*
X239358Y318092D01*
X239233Y317717D01*
X239275Y317342D01*
X239441Y316967D01*
G01X241733Y320567D02*
X241191Y320650D01*
X240733Y320775D01*
X240316Y320942D01*
X239858Y321150D01*
X239233Y321483D01*
Y319817D01*
G01X238200Y301400D02*
X242200D01*
Y308800D01*
G01X260233Y307517D02*
X257733D01*
Y308558D01*
X257858Y308892D01*
X258025Y309100D01*
X258358Y309183D01*
X258691Y309100D01*
X258900Y308850D01*
X259025Y308558D01*
Y307517D01*
G01Y308558D02*
X260233Y309183D01*
G01Y311950D02*
X257733D01*
X259525Y310408D01*
Y312492D01*
G01X259733Y313633D02*
X260025Y313883D01*
X260191Y314217D01*
X260233Y314592D01*
X260191Y314925D01*
X259983Y315258D01*
X259733Y315467D01*
X259483Y315508D01*
X259191Y315425D01*
X258983Y315133D01*
X258900Y314842D01*
Y314467D01*
G01Y314842D02*
X258775Y315092D01*
X258566Y315300D01*
X258316Y315383D01*
X258066Y315300D01*
X257858Y315092D01*
X257733Y314717D01*
X257775Y314342D01*
X257941Y313967D01*
G01X260233Y317650D02*
X260191Y317942D01*
X260066Y318275D01*
X259858Y318483D01*
X259566Y318567D01*
X259275Y318483D01*
X259025Y318233D01*
X258900Y317858D01*
Y317442D01*
X258816Y317192D01*
X258608Y316983D01*
X258316Y316900D01*
X258025Y317025D01*
X257816Y317317D01*
X257733Y317650D01*
X257816Y317983D01*
X258025Y318275D01*
X258316Y318400D01*
X258608Y318317D01*
X258816Y318108D01*
X258900Y317858D01*
Y317442D01*
X259025Y317067D01*
X259275Y316817D01*
X259566Y316733D01*
X259858Y316817D01*
X260066Y317025D01*
X260191Y317358D01*
X260233Y317650D01*
G01X223333Y312617D02*
X220833D01*
Y313658D01*
X220958Y313992D01*
X221125Y314200D01*
X221458Y314283D01*
X221791Y314200D01*
X222000Y313950D01*
X222125Y313658D01*
Y312617D01*
G01Y313658D02*
X223333Y314283D01*
G01Y317050D02*
X220833D01*
X222625Y315508D01*
Y317592D01*
G01X223333Y320150D02*
X220833D01*
X222625Y318608D01*
Y320692D01*
G01X223333Y322750D02*
X220833D01*
X221333Y322250D01*
G01X223333D02*
Y323250D01*
G01X220000Y301300D02*
X224000D01*
Y308700D01*
G01X249517Y361500D02*
Y364000D01*
X250558D01*
X250892Y363875D01*
X251100Y363708D01*
X251183Y363375D01*
X251100Y363042D01*
X250850Y362833D01*
X250558Y362708D01*
X249517D01*
G01X250558D02*
X251183Y361500D01*
G01X252533Y361875D02*
X252783Y361667D01*
X253075Y361542D01*
X253450Y361500D01*
X253825Y361583D01*
X254117Y361750D01*
X254325Y362042D01*
X254367Y362375D01*
X254283Y362708D01*
X254075Y362917D01*
X253783Y363083D01*
X253492Y363125D01*
X253200Y363083D01*
X252825Y362917D01*
X252950Y364000D01*
X254075D01*
G01X256550D02*
X256217Y363917D01*
X255967Y363708D01*
X255800Y363458D01*
X255675Y363125D01*
X255633Y362750D01*
X255675Y362375D01*
X255800Y362042D01*
X255967Y361792D01*
X256217Y361583D01*
X256550Y361500D01*
X256883Y361583D01*
X257133Y361792D01*
X257300Y362042D01*
X257425Y362375D01*
X257467Y362750D01*
X257425Y363125D01*
X257300Y363458D01*
X257133Y363708D01*
X256883Y363917D01*
X256550Y364000D01*
G01X258733Y362000D02*
X258983Y361708D01*
X259317Y361542D01*
X259692Y361500D01*
X260025Y361542D01*
X260358Y361750D01*
X260567Y362000D01*
X260608Y362250D01*
X260525Y362542D01*
X260233Y362750D01*
X259942Y362833D01*
X259567D01*
G01X259942D02*
X260192Y362958D01*
X260400Y363167D01*
X260483Y363417D01*
X260400Y363667D01*
X260192Y363875D01*
X259817Y364000D01*
X259442Y363958D01*
X259067Y363792D01*
G01X230267Y328959D02*
X230017Y329084D01*
X229725Y329167D01*
X229392D01*
X229017Y329042D01*
X228725Y328834D01*
X228517Y328584D01*
X228350Y328167D01*
X228308Y327792D01*
X228392Y327417D01*
X228517Y327167D01*
X228767Y326917D01*
X229058Y326750D01*
X229350Y326667D01*
X229642D01*
X229933Y326750D01*
X230183Y326875D01*
X230392Y327042D01*
G01X231533D02*
X231783Y326834D01*
X232075Y326709D01*
X232450Y326667D01*
X232825Y326750D01*
X233117Y326917D01*
X233325Y327209D01*
X233367Y327542D01*
X233283Y327875D01*
X233075Y328084D01*
X232783Y328250D01*
X232492Y328292D01*
X232200Y328250D01*
X231825Y328084D01*
X231950Y329167D01*
X233075D01*
G01X236050Y326667D02*
Y329167D01*
X234508Y327375D01*
X236592D01*
G01X237942Y326959D02*
X238233Y326750D01*
X238567Y326667D01*
X238900Y326750D01*
X239192Y327000D01*
X239400Y327375D01*
X239483Y327750D01*
Y328209D01*
X239400Y328584D01*
X239192Y328917D01*
X238942Y329084D01*
X238650Y329167D01*
X238317Y329084D01*
X238067Y328917D01*
X237900Y328667D01*
X237817Y328334D01*
X237900Y328042D01*
X238108Y327750D01*
X238358Y327584D01*
X238650Y327542D01*
X238983Y327625D01*
X239233Y327834D01*
X239483Y328209D01*
G01X248767Y328959D02*
X248517Y329084D01*
X248225Y329167D01*
X247892D01*
X247517Y329042D01*
X247225Y328834D01*
X247017Y328584D01*
X246850Y328167D01*
X246808Y327792D01*
X246892Y327417D01*
X247017Y327167D01*
X247267Y326917D01*
X247558Y326750D01*
X247850Y326667D01*
X248142D01*
X248433Y326750D01*
X248683Y326875D01*
X248892Y327042D01*
G01X250033D02*
X250283Y326834D01*
X250575Y326709D01*
X250950Y326667D01*
X251325Y326750D01*
X251617Y326917D01*
X251825Y327209D01*
X251867Y327542D01*
X251783Y327875D01*
X251575Y328084D01*
X251283Y328250D01*
X250992Y328292D01*
X250700Y328250D01*
X250325Y328084D01*
X250450Y329167D01*
X251575D01*
G01X253133Y327042D02*
X253383Y326834D01*
X253675Y326709D01*
X254050Y326667D01*
X254425Y326750D01*
X254717Y326917D01*
X254925Y327209D01*
X254967Y327542D01*
X254883Y327875D01*
X254675Y328084D01*
X254383Y328250D01*
X254092Y328292D01*
X253800Y328250D01*
X253425Y328084D01*
X253550Y329167D01*
X254675D01*
G01X257150D02*
X256817Y329084D01*
X256567Y328875D01*
X256400Y328625D01*
X256275Y328292D01*
X256233Y327917D01*
X256275Y327542D01*
X256400Y327209D01*
X256567Y326959D01*
X256817Y326750D01*
X257150Y326667D01*
X257483Y326750D01*
X257733Y326959D01*
X257900Y327209D01*
X258025Y327542D01*
X258067Y327917D01*
X258025Y328292D01*
X257900Y328625D01*
X257733Y328875D01*
X257483Y329084D01*
X257150Y329167D01*
G01X263767Y332292D02*
X263517Y332417D01*
X263225Y332500D01*
X262892D01*
X262517Y332375D01*
X262225Y332167D01*
X262017Y331917D01*
X261850Y331500D01*
X261808Y331125D01*
X261892Y330750D01*
X262017Y330500D01*
X262267Y330250D01*
X262558Y330083D01*
X262850Y330000D01*
X263142D01*
X263433Y330083D01*
X263683Y330208D01*
X263892Y330375D01*
G01X265033D02*
X265283Y330167D01*
X265575Y330042D01*
X265950Y330000D01*
X266325Y330083D01*
X266617Y330250D01*
X266825Y330542D01*
X266867Y330875D01*
X266783Y331208D01*
X266575Y331417D01*
X266283Y331583D01*
X265992Y331625D01*
X265700Y331583D01*
X265325Y331417D01*
X265450Y332500D01*
X266575D01*
G01X268133Y330375D02*
X268383Y330167D01*
X268675Y330042D01*
X269050Y330000D01*
X269425Y330083D01*
X269717Y330250D01*
X269925Y330542D01*
X269967Y330875D01*
X269883Y331208D01*
X269675Y331417D01*
X269383Y331583D01*
X269092Y331625D01*
X268800Y331583D01*
X268425Y331417D01*
X268550Y332500D01*
X269675D01*
G01X272067Y330000D02*
X272150Y330542D01*
X272275Y331000D01*
X272442Y331417D01*
X272650Y331875D01*
X272983Y332500D01*
X271317D01*
G01X210267Y364292D02*
X210017Y364417D01*
X209725Y364500D01*
X209392D01*
X209017Y364375D01*
X208725Y364167D01*
X208517Y363917D01*
X208350Y363500D01*
X208308Y363125D01*
X208392Y362750D01*
X208517Y362500D01*
X208767Y362250D01*
X209058Y362083D01*
X209350Y362000D01*
X209642D01*
X209933Y362083D01*
X210183Y362208D01*
X210392Y362375D01*
G01X211533D02*
X211783Y362167D01*
X212075Y362042D01*
X212450Y362000D01*
X212825Y362083D01*
X213117Y362250D01*
X213325Y362542D01*
X213367Y362875D01*
X213283Y363208D01*
X213075Y363417D01*
X212783Y363583D01*
X212492Y363625D01*
X212200Y363583D01*
X211825Y363417D01*
X211950Y364500D01*
X213075D01*
G01X214842Y362292D02*
X215133Y362083D01*
X215467Y362000D01*
X215800Y362083D01*
X216092Y362333D01*
X216300Y362708D01*
X216383Y363083D01*
Y363542D01*
X216300Y363917D01*
X216092Y364250D01*
X215842Y364417D01*
X215550Y364500D01*
X215217Y364417D01*
X214967Y364250D01*
X214800Y364000D01*
X214717Y363667D01*
X214800Y363375D01*
X215008Y363083D01*
X215258Y362917D01*
X215550Y362875D01*
X215883Y362958D01*
X216133Y363167D01*
X216383Y363542D01*
G01X217733Y362375D02*
X217983Y362167D01*
X218275Y362042D01*
X218650Y362000D01*
X219025Y362083D01*
X219317Y362250D01*
X219525Y362542D01*
X219567Y362875D01*
X219483Y363208D01*
X219275Y363417D01*
X218983Y363583D01*
X218692Y363625D01*
X218400Y363583D01*
X218025Y363417D01*
X218150Y364500D01*
X219275D01*
G01X228983Y324166D02*
Y322374D01*
X229150Y321999D01*
X229483Y321749D01*
X229900Y321666D01*
X230317Y321749D01*
X230650Y321999D01*
X230817Y322374D01*
Y324166D01*
G01X232083Y322166D02*
X232333Y321874D01*
X232667Y321708D01*
X233042Y321666D01*
X233375Y321708D01*
X233708Y321916D01*
X233917Y322166D01*
X233958Y322416D01*
X233875Y322708D01*
X233583Y322916D01*
X233292Y322999D01*
X232917D01*
G01X233292D02*
X233542Y323124D01*
X233750Y323333D01*
X233833Y323583D01*
X233750Y323833D01*
X233542Y324041D01*
X233167Y324166D01*
X232792Y324124D01*
X232417Y323958D01*
G01X236017Y321666D02*
X236100Y322208D01*
X236225Y322666D01*
X236392Y323083D01*
X236600Y323541D01*
X236933Y324166D01*
X235267D01*
G01X226832Y307405D02*
X237032D01*
G01X226832Y302805D02*
Y307405D01*
G01X237732Y302805D02*
X226832D01*
G01X237732D02*
Y314105D01*
G01X236532Y305105D02*
X237732Y303905D01*
G01X236532Y305105D02*
X237732Y306305D01*
G01X248483Y324667D02*
Y322875D01*
X248650Y322500D01*
X248983Y322250D01*
X249400Y322167D01*
X249817Y322250D01*
X250150Y322500D01*
X250317Y322875D01*
Y324667D01*
G01X251583Y322667D02*
X251833Y322375D01*
X252167Y322209D01*
X252542Y322167D01*
X252875Y322209D01*
X253208Y322417D01*
X253417Y322667D01*
X253458Y322917D01*
X253375Y323209D01*
X253083Y323417D01*
X252792Y323500D01*
X252417D01*
G01X252792D02*
X253042Y323625D01*
X253250Y323834D01*
X253333Y324084D01*
X253250Y324334D01*
X253042Y324542D01*
X252667Y324667D01*
X252292Y324625D01*
X251917Y324459D01*
G01X255600Y322167D02*
X255892Y322209D01*
X256225Y322334D01*
X256433Y322542D01*
X256517Y322834D01*
X256433Y323125D01*
X256183Y323375D01*
X255808Y323500D01*
X255392D01*
X255142Y323584D01*
X254933Y323792D01*
X254850Y324084D01*
X254975Y324375D01*
X255267Y324584D01*
X255600Y324667D01*
X255933Y324584D01*
X256225Y324375D01*
X256350Y324084D01*
X256267Y323792D01*
X256058Y323584D01*
X255808Y323500D01*
X255392D01*
X255017Y323375D01*
X254767Y323125D01*
X254683Y322834D01*
X254767Y322542D01*
X254975Y322334D01*
X255308Y322209D01*
X255600Y322167D01*
G01X245175Y307367D02*
X255375D01*
G01X245175Y302767D02*
Y307367D01*
G01X256075Y302767D02*
X245175D01*
G01X256075D02*
Y314067D01*
G01X254875Y305067D02*
X256075Y303867D01*
G01X254875Y305067D02*
X256075Y306267D01*
G01X201983Y323666D02*
Y321874D01*
X202150Y321499D01*
X202483Y321249D01*
X202900Y321166D01*
X203317Y321249D01*
X203650Y321499D01*
X203817Y321874D01*
Y323666D01*
G01X206500Y321166D02*
Y323666D01*
X204958Y321874D01*
X207042D01*
G01X209100Y321166D02*
Y323666D01*
X208600Y323166D01*
G01Y321166D02*
X209600D01*
G01X208600Y307400D02*
X218800D01*
G01X208600Y302800D02*
Y307400D01*
G01X219500Y302800D02*
X208600D01*
G01X219500D02*
Y314100D01*
G01X218300Y305100D02*
X219500Y303900D01*
G01X218300Y305100D02*
X219500Y306300D01*
G01X248834Y351067D02*
X251334D01*
Y352733D01*
G01X249251Y354208D02*
X249001Y354458D01*
X248876Y354750D01*
X248834Y355083D01*
X248917Y355500D01*
X249126Y355792D01*
X249376Y355875D01*
X249626Y355833D01*
X249834Y355667D01*
X250251Y354833D01*
X250542Y354458D01*
X250959Y354208D01*
X251334Y354125D01*
Y355875D01*
G01Y358100D02*
X251292Y358392D01*
X251167Y358725D01*
X250959Y358933D01*
X250667Y359017D01*
X250376Y358933D01*
X250126Y358683D01*
X250001Y358308D01*
Y357892D01*
X249917Y357642D01*
X249709Y357433D01*
X249417Y357350D01*
X249126Y357475D01*
X248917Y357767D01*
X248834Y358100D01*
X248917Y358433D01*
X249126Y358725D01*
X249417Y358850D01*
X249709Y358767D01*
X249917Y358558D01*
X250001Y358308D01*
Y357892D01*
X250126Y357517D01*
X250376Y357267D01*
X250667Y357183D01*
X250959Y357267D01*
X251167Y357475D01*
X251292Y357808D01*
X251334Y358100D01*
G01X239700Y365400D02*
Y352000D01*
G01X246900D02*
Y365400D01*
G01X239700Y352000D02*
X246900D01*
G01X252491Y373827D02*
Y369827D01*
X259891D01*
G01X257800Y414100D02*
Y410100D01*
X265200D01*
G01X253500Y413800D02*
X257500D01*
Y421200D01*
G01X257800Y422300D02*
Y418300D01*
X265200D01*
G01X220042Y400267D02*
X219917Y400017D01*
X219834Y399725D01*
Y399392D01*
X219959Y399017D01*
X220167Y398725D01*
X220417Y398517D01*
X220834Y398350D01*
X221209Y398308D01*
X221584Y398392D01*
X221834Y398517D01*
X222084Y398767D01*
X222251Y399058D01*
X222334Y399350D01*
Y399642D01*
X222251Y399933D01*
X222126Y400183D01*
X221959Y400392D01*
G01X222334Y402367D02*
X221792Y402450D01*
X221334Y402575D01*
X220917Y402742D01*
X220459Y402950D01*
X219834Y403283D01*
Y401617D01*
G01X222334Y405550D02*
X219834D01*
X220334Y405050D01*
G01X222334D02*
Y406050D01*
G01Y408650D02*
X219834D01*
X220334Y408150D01*
G01X222334D02*
Y409150D01*
G01X209767Y371292D02*
X209517Y371417D01*
X209225Y371500D01*
X208892D01*
X208517Y371375D01*
X208225Y371167D01*
X208017Y370917D01*
X207850Y370500D01*
X207808Y370125D01*
X207892Y369750D01*
X208017Y369500D01*
X208267Y369250D01*
X208558Y369083D01*
X208850Y369000D01*
X209142D01*
X209433Y369083D01*
X209683Y369208D01*
X209892Y369375D01*
G01X211867Y369000D02*
X211950Y369542D01*
X212075Y370000D01*
X212242Y370417D01*
X212450Y370875D01*
X212783Y371500D01*
X211117D01*
G01X215050D02*
X214717Y371417D01*
X214467Y371208D01*
X214300Y370958D01*
X214175Y370625D01*
X214133Y370250D01*
X214175Y369875D01*
X214300Y369542D01*
X214467Y369292D01*
X214717Y369083D01*
X215050Y369000D01*
X215383Y369083D01*
X215633Y369292D01*
X215800Y369542D01*
X215925Y369875D01*
X215967Y370250D01*
X215925Y370625D01*
X215800Y370958D01*
X215633Y371208D01*
X215383Y371417D01*
X215050Y371500D01*
G01X217358Y371083D02*
X217608Y371333D01*
X217900Y371458D01*
X218233Y371500D01*
X218650Y371417D01*
X218942Y371208D01*
X219025Y370958D01*
X218983Y370708D01*
X218817Y370500D01*
X217983Y370083D01*
X217608Y369792D01*
X217358Y369375D01*
X217275Y369000D01*
X219025D01*
G01X209767Y379292D02*
X209517Y379417D01*
X209225Y379500D01*
X208892D01*
X208517Y379375D01*
X208225Y379167D01*
X208017Y378917D01*
X207850Y378500D01*
X207808Y378125D01*
X207892Y377750D01*
X208017Y377500D01*
X208267Y377250D01*
X208558Y377083D01*
X208850Y377000D01*
X209142D01*
X209433Y377083D01*
X209683Y377208D01*
X209892Y377375D01*
G01X211867Y377000D02*
X211950Y377542D01*
X212075Y378000D01*
X212242Y378417D01*
X212450Y378875D01*
X212783Y379500D01*
X211117D01*
G01X215050D02*
X214717Y379417D01*
X214467Y379208D01*
X214300Y378958D01*
X214175Y378625D01*
X214133Y378250D01*
X214175Y377875D01*
X214300Y377542D01*
X214467Y377292D01*
X214717Y377083D01*
X215050Y377000D01*
X215383Y377083D01*
X215633Y377292D01*
X215800Y377542D01*
X215925Y377875D01*
X215967Y378250D01*
X215925Y378625D01*
X215800Y378958D01*
X215633Y379208D01*
X215383Y379417D01*
X215050Y379500D01*
G01X218150Y377000D02*
Y379500D01*
X217650Y379000D01*
G01Y377000D02*
X218650D01*
G01X209767Y385792D02*
X209517Y385917D01*
X209225Y386000D01*
X208892D01*
X208517Y385875D01*
X208225Y385667D01*
X208017Y385417D01*
X207850Y385000D01*
X207808Y384625D01*
X207892Y384250D01*
X208017Y384000D01*
X208267Y383750D01*
X208558Y383583D01*
X208850Y383500D01*
X209142D01*
X209433Y383583D01*
X209683Y383708D01*
X209892Y383875D01*
G01X211158Y384542D02*
X211450Y384833D01*
X211700Y385000D01*
X212033Y385083D01*
X212325Y385000D01*
X212533Y384833D01*
X212700Y384583D01*
X212742Y384292D01*
X212700Y384042D01*
X212533Y383792D01*
X212283Y383583D01*
X211992Y383500D01*
X211658Y383583D01*
X211367Y383833D01*
X211200Y384208D01*
X211158Y384625D01*
X211242Y385167D01*
X211367Y385458D01*
X211575Y385750D01*
X211867Y385958D01*
X212158Y386000D01*
X212450Y385917D01*
X212658Y385708D01*
G01X214133Y383875D02*
X214383Y383667D01*
X214675Y383542D01*
X215050Y383500D01*
X215425Y383583D01*
X215717Y383750D01*
X215925Y384042D01*
X215967Y384375D01*
X215883Y384708D01*
X215675Y384917D01*
X215383Y385083D01*
X215092Y385125D01*
X214800Y385083D01*
X214425Y384917D01*
X214550Y386000D01*
X215675D01*
G01X217358Y384542D02*
X217650Y384833D01*
X217900Y385000D01*
X218233Y385083D01*
X218525Y385000D01*
X218733Y384833D01*
X218900Y384583D01*
X218942Y384292D01*
X218900Y384042D01*
X218733Y383792D01*
X218483Y383583D01*
X218192Y383500D01*
X217858Y383583D01*
X217567Y383833D01*
X217400Y384208D01*
X217358Y384625D01*
X217442Y385167D01*
X217567Y385458D01*
X217775Y385750D01*
X218067Y385958D01*
X218358Y386000D01*
X218650Y385917D01*
X218858Y385708D01*
G01X250987Y368062D02*
X250737Y368187D01*
X250445Y368270D01*
X250112D01*
X249737Y368145D01*
X249445Y367937D01*
X249237Y367687D01*
X249070Y367270D01*
X249028Y366895D01*
X249112Y366520D01*
X249237Y366270D01*
X249487Y366020D01*
X249778Y365853D01*
X250070Y365770D01*
X250362D01*
X250653Y365853D01*
X250903Y365978D01*
X251112Y366145D01*
G01X252378Y366812D02*
X252670Y367103D01*
X252920Y367270D01*
X253253Y367353D01*
X253545Y367270D01*
X253753Y367103D01*
X253920Y366853D01*
X253962Y366562D01*
X253920Y366312D01*
X253753Y366062D01*
X253503Y365853D01*
X253212Y365770D01*
X252878Y365853D01*
X252587Y366103D01*
X252420Y366478D01*
X252378Y366895D01*
X252462Y367437D01*
X252587Y367728D01*
X252795Y368020D01*
X253087Y368228D01*
X253378Y368270D01*
X253670Y368187D01*
X253878Y367978D01*
G01X255353Y366270D02*
X255603Y365978D01*
X255937Y365812D01*
X256312Y365770D01*
X256645Y365812D01*
X256978Y366020D01*
X257187Y366270D01*
X257228Y366520D01*
X257145Y366812D01*
X256853Y367020D01*
X256562Y367103D01*
X256187D01*
G01X256562D02*
X256812Y367228D01*
X257020Y367437D01*
X257103Y367687D01*
X257020Y367937D01*
X256812Y368145D01*
X256437Y368270D01*
X256062Y368228D01*
X255687Y368062D01*
G01X259370Y365770D02*
X259662Y365812D01*
X259995Y365937D01*
X260203Y366145D01*
X260287Y366437D01*
X260203Y366728D01*
X259953Y366978D01*
X259578Y367103D01*
X259162D01*
X258912Y367187D01*
X258703Y367395D01*
X258620Y367687D01*
X258745Y367978D01*
X259037Y368187D01*
X259370Y368270D01*
X259703Y368187D01*
X259995Y367978D01*
X260120Y367687D01*
X260037Y367395D01*
X259828Y367187D01*
X259578Y367103D01*
X259162D01*
X258787Y366978D01*
X258537Y366728D01*
X258453Y366437D01*
X258537Y366145D01*
X258745Y365937D01*
X259078Y365812D01*
X259370Y365770D01*
G01X229083Y402900D02*
Y401108D01*
X229250Y400733D01*
X229583Y400483D01*
X230000Y400400D01*
X230417Y400483D01*
X230750Y400733D01*
X230917Y401108D01*
Y402900D01*
G01X233100Y400400D02*
Y402900D01*
X232600Y402400D01*
G01Y400400D02*
X233600D01*
G01X236200Y402900D02*
X235867Y402817D01*
X235617Y402608D01*
X235450Y402358D01*
X235325Y402025D01*
X235283Y401650D01*
X235325Y401275D01*
X235450Y400942D01*
X235617Y400692D01*
X235867Y400483D01*
X236200Y400400D01*
X236533Y400483D01*
X236783Y400692D01*
X236950Y400942D01*
X237075Y401275D01*
X237117Y401650D01*
X237075Y402025D01*
X236950Y402358D01*
X236783Y402608D01*
X236533Y402817D01*
X236200Y402900D01*
G01X260670Y381820D02*
X265670D01*
Y386820D01*
G01X238070D02*
Y381820D01*
X243070D01*
G01Y409520D02*
X238070D01*
Y404520D01*
G01X257776Y382827D02*
Y379827D01*
G01X247933Y382827D02*
Y380827D01*
G01X243996Y408513D02*
Y411513D01*
G01X253839Y408513D02*
Y410513D01*
G01X250820Y446038D02*
Y410638D01*
X222820D01*
Y446038D01*
X250820D01*
G01X211517Y393167D02*
Y395667D01*
X212558D01*
X212892Y395542D01*
X213100Y395375D01*
X213183Y395042D01*
X213100Y394709D01*
X212850Y394500D01*
X212558Y394375D01*
X211517D01*
G01X212558D02*
X213183Y393167D01*
G01X214533Y393542D02*
X214783Y393334D01*
X215075Y393209D01*
X215450Y393167D01*
X215825Y393250D01*
X216117Y393417D01*
X216325Y393709D01*
X216367Y394042D01*
X216283Y394375D01*
X216075Y394584D01*
X215783Y394750D01*
X215492Y394792D01*
X215200Y394750D01*
X214825Y394584D01*
X214950Y395667D01*
X216075D01*
G01X218550Y393167D02*
Y395667D01*
X218050Y395167D01*
G01Y393167D02*
X219050D01*
G01X220858Y394209D02*
X221150Y394500D01*
X221400Y394667D01*
X221733Y394750D01*
X222025Y394667D01*
X222233Y394500D01*
X222400Y394250D01*
X222442Y393959D01*
X222400Y393709D01*
X222233Y393459D01*
X221983Y393250D01*
X221692Y393167D01*
X221358Y393250D01*
X221067Y393500D01*
X220900Y393875D01*
X220858Y394292D01*
X220942Y394834D01*
X221067Y395125D01*
X221275Y395417D01*
X221567Y395625D01*
X221858Y395667D01*
X222150Y395584D01*
X222358Y395375D01*
G01X223800Y398454D02*
X229000D01*
G01X223800Y391454D02*
X231600D01*
G01X223800Y398454D02*
Y391454D01*
G01X237200Y398454D02*
X228500D01*
G01X237200Y391454D02*
Y398454D01*
G01X230800Y391454D02*
X237200D01*
G01X246900Y365400D02*
X239700D01*
G01X259517Y434667D02*
Y437167D01*
X260558D01*
X260892Y437042D01*
X261100Y436875D01*
X261183Y436542D01*
X261100Y436209D01*
X260850Y436000D01*
X260558Y435875D01*
X259517D01*
G01X260558D02*
X261183Y434667D01*
G01X262533Y435042D02*
X262783Y434834D01*
X263075Y434709D01*
X263450Y434667D01*
X263825Y434750D01*
X264117Y434917D01*
X264325Y435209D01*
X264367Y435542D01*
X264283Y435875D01*
X264075Y436084D01*
X263783Y436250D01*
X263492Y436292D01*
X263200Y436250D01*
X262825Y436084D01*
X262950Y437167D01*
X264075D01*
G01X266550D02*
X266217Y437084D01*
X265967Y436875D01*
X265800Y436625D01*
X265675Y436292D01*
X265633Y435917D01*
X265675Y435542D01*
X265800Y435209D01*
X265967Y434959D01*
X266217Y434750D01*
X266550Y434667D01*
X266883Y434750D01*
X267133Y434959D01*
X267300Y435209D01*
X267425Y435542D01*
X267467Y435917D01*
X267425Y436292D01*
X267300Y436625D01*
X267133Y436875D01*
X266883Y437084D01*
X266550Y437167D01*
G01X269650Y434667D02*
Y437167D01*
X269150Y436667D01*
G01Y434667D02*
X270150D01*
G01X259517Y443500D02*
Y446000D01*
X260558D01*
X260892Y445875D01*
X261100Y445708D01*
X261183Y445375D01*
X261100Y445042D01*
X260850Y444833D01*
X260558Y444708D01*
X259517D01*
G01X260558D02*
X261183Y443500D01*
G01X262533Y443875D02*
X262783Y443667D01*
X263075Y443542D01*
X263450Y443500D01*
X263825Y443583D01*
X264117Y443750D01*
X264325Y444042D01*
X264367Y444375D01*
X264283Y444708D01*
X264075Y444917D01*
X263783Y445083D01*
X263492Y445125D01*
X263200Y445083D01*
X262825Y444917D01*
X262950Y446000D01*
X264075D01*
G01X266550Y443500D02*
Y446000D01*
X266050Y445500D01*
G01Y443500D02*
X267050D01*
G01X270150D02*
Y446000D01*
X268608Y444208D01*
X270692D01*
G01X254050Y428500D02*
Y424500D01*
X261450D01*
G01X258334Y435017D02*
X255834D01*
Y436058D01*
X255959Y436392D01*
X256126Y436600D01*
X256459Y436683D01*
X256792Y436600D01*
X257001Y436350D01*
X257126Y436058D01*
Y435017D01*
G01Y436058D02*
X258334Y436683D01*
G01X257959Y438033D02*
X258167Y438283D01*
X258292Y438575D01*
X258334Y438950D01*
X258251Y439325D01*
X258084Y439617D01*
X257792Y439825D01*
X257459Y439867D01*
X257126Y439783D01*
X256917Y439575D01*
X256751Y439283D01*
X256709Y438992D01*
X256751Y438700D01*
X256917Y438325D01*
X255834Y438450D01*
Y439575D01*
G01X258334Y442050D02*
X255834D01*
X256334Y441550D01*
G01X258334D02*
Y442550D01*
G01Y445067D02*
X257792Y445150D01*
X257334Y445275D01*
X256917Y445442D01*
X256459Y445650D01*
X255834Y445983D01*
Y444317D01*
G01X259517Y439167D02*
Y441667D01*
X260558D01*
X260892Y441542D01*
X261100Y441375D01*
X261183Y441042D01*
X261100Y440709D01*
X260850Y440500D01*
X260558Y440375D01*
X259517D01*
G01X260558D02*
X261183Y439167D01*
G01X262533Y439542D02*
X262783Y439334D01*
X263075Y439209D01*
X263450Y439167D01*
X263825Y439250D01*
X264117Y439417D01*
X264325Y439709D01*
X264367Y440042D01*
X264283Y440375D01*
X264075Y440584D01*
X263783Y440750D01*
X263492Y440792D01*
X263200Y440750D01*
X262825Y440584D01*
X262950Y441667D01*
X264075D01*
G01X266550D02*
X266217Y441584D01*
X265967Y441375D01*
X265800Y441125D01*
X265675Y440792D01*
X265633Y440417D01*
X265675Y440042D01*
X265800Y439709D01*
X265967Y439459D01*
X266217Y439250D01*
X266550Y439167D01*
X266883Y439250D01*
X267133Y439459D01*
X267300Y439709D01*
X267425Y440042D01*
X267467Y440417D01*
X267425Y440792D01*
X267300Y441125D01*
X267133Y441375D01*
X266883Y441584D01*
X266550Y441667D01*
G01X269650D02*
X269317Y441584D01*
X269067Y441375D01*
X268900Y441125D01*
X268775Y440792D01*
X268733Y440417D01*
X268775Y440042D01*
X268900Y439709D01*
X269067Y439459D01*
X269317Y439250D01*
X269650Y439167D01*
X269983Y439250D01*
X270233Y439459D01*
X270400Y439709D01*
X270525Y440042D01*
X270567Y440417D01*
X270525Y440792D01*
X270400Y441125D01*
X270233Y441375D01*
X269983Y441584D01*
X269650Y441667D01*
G01X261267Y449959D02*
X261017Y450084D01*
X260725Y450167D01*
X260392D01*
X260017Y450042D01*
X259725Y449834D01*
X259517Y449584D01*
X259350Y449167D01*
X259308Y448792D01*
X259392Y448417D01*
X259517Y448167D01*
X259767Y447917D01*
X260058Y447750D01*
X260350Y447667D01*
X260642D01*
X260933Y447750D01*
X261183Y447875D01*
X261392Y448042D01*
G01X263367Y447667D02*
X263450Y448209D01*
X263575Y448667D01*
X263742Y449084D01*
X263950Y449542D01*
X264283Y450167D01*
X262617D01*
G01X266550Y447667D02*
Y450167D01*
X266050Y449667D01*
G01Y447667D02*
X267050D01*
G01X268733Y448167D02*
X268983Y447875D01*
X269317Y447709D01*
X269692Y447667D01*
X270025Y447709D01*
X270358Y447917D01*
X270567Y448167D01*
X270608Y448417D01*
X270525Y448709D01*
X270233Y448917D01*
X269942Y449000D01*
X269567D01*
G01X269942D02*
X270192Y449125D01*
X270400Y449334D01*
X270483Y449584D01*
X270400Y449834D01*
X270192Y450042D01*
X269817Y450167D01*
X269442Y450125D01*
X269067Y449959D01*
G01X245017Y449735D02*
Y447235D01*
X246683D01*
G01X248033Y447735D02*
X248283Y447443D01*
X248617Y447277D01*
X248992Y447235D01*
X249325Y447277D01*
X249658Y447485D01*
X249867Y447735D01*
X249908Y447985D01*
X249825Y448277D01*
X249533Y448485D01*
X249242Y448568D01*
X248867D01*
G01X249242D02*
X249492Y448693D01*
X249700Y448902D01*
X249783Y449152D01*
X249700Y449402D01*
X249492Y449610D01*
X249117Y449735D01*
X248742Y449693D01*
X248367Y449527D01*
G01X252550Y447235D02*
Y449735D01*
X251008Y447943D01*
X253092D01*
G01X246400Y459000D02*
Y456500D01*
G01X245442Y459000D02*
X247358D01*
G01X250417Y458792D02*
X250167Y458917D01*
X249875Y459000D01*
X249542D01*
X249167Y458875D01*
X248875Y458667D01*
X248667Y458417D01*
X248500Y458000D01*
X248458Y457625D01*
X248542Y457250D01*
X248667Y457000D01*
X248917Y456750D01*
X249208Y456583D01*
X249500Y456500D01*
X249792D01*
X250083Y456583D01*
X250333Y456708D01*
X250542Y456875D01*
G01X253100Y456500D02*
Y459000D01*
X251558Y457208D01*
X253642D01*
G01X243200Y465500D02*
X232000D01*
G01X243200Y447500D02*
Y465500D01*
G01X232000Y447500D02*
X243200D01*
G01X204800Y465500D02*
X216000D01*
G01X204800Y447500D02*
Y465500D01*
G01X216000Y447500D02*
X204800D01*
G01X235625Y491761D02*
Y483961D01*
G01X242625Y478361D02*
Y487061D01*
G01X235625Y478361D02*
X242625D01*
G01X235625Y484761D02*
Y478361D01*
G01X227625Y491761D02*
Y483961D01*
G01X234625Y478361D02*
Y487061D01*
G01X227625Y478361D02*
X234625D01*
G01X227625Y484761D02*
Y478361D01*
G01X243625Y491761D02*
Y483961D01*
G01X250625Y478361D02*
Y487061D01*
G01X243625Y478361D02*
X250625D01*
G01X243625Y484761D02*
Y478361D01*
G01X240025Y494578D02*
X237525D01*
Y495619D01*
X237650Y495953D01*
X237817Y496161D01*
X238150Y496244D01*
X238483Y496161D01*
X238692Y495911D01*
X238817Y495619D01*
Y494578D01*
G01Y495619D02*
X240025Y496244D01*
G01X239650Y497594D02*
X239858Y497844D01*
X239983Y498136D01*
X240025Y498511D01*
X239942Y498886D01*
X239775Y499178D01*
X239483Y499386D01*
X239150Y499428D01*
X238817Y499344D01*
X238608Y499136D01*
X238442Y498844D01*
X238400Y498553D01*
X238442Y498261D01*
X238608Y497886D01*
X237525Y498011D01*
Y499136D01*
G01Y501611D02*
X237608Y501278D01*
X237817Y501028D01*
X238067Y500861D01*
X238400Y500736D01*
X238775Y500694D01*
X239150Y500736D01*
X239483Y500861D01*
X239733Y501028D01*
X239942Y501278D01*
X240025Y501611D01*
X239942Y501944D01*
X239733Y502194D01*
X239483Y502361D01*
X239150Y502486D01*
X238775Y502528D01*
X238400Y502486D01*
X238067Y502361D01*
X237817Y502194D01*
X237608Y501944D01*
X237525Y501611D01*
G01X239733Y504003D02*
X239942Y504294D01*
X240025Y504628D01*
X239942Y504961D01*
X239692Y505253D01*
X239317Y505461D01*
X238942Y505544D01*
X238483D01*
X238108Y505461D01*
X237775Y505253D01*
X237608Y505003D01*
X237525Y504711D01*
X237608Y504378D01*
X237775Y504128D01*
X238025Y503961D01*
X238358Y503878D01*
X238650Y503961D01*
X238942Y504169D01*
X239108Y504419D01*
X239150Y504711D01*
X239067Y505044D01*
X238858Y505294D01*
X238483Y505544D01*
G01X242625Y491761D02*
Y486561D01*
G01Y491761D02*
X235625D01*
G01X232025Y494578D02*
X229525D01*
Y495619D01*
X229650Y495953D01*
X229817Y496161D01*
X230150Y496244D01*
X230483Y496161D01*
X230692Y495911D01*
X230817Y495619D01*
Y494578D01*
G01Y495619D02*
X232025Y496244D01*
G01X231650Y497594D02*
X231858Y497844D01*
X231983Y498136D01*
X232025Y498511D01*
X231942Y498886D01*
X231775Y499178D01*
X231483Y499386D01*
X231150Y499428D01*
X230817Y499344D01*
X230608Y499136D01*
X230442Y498844D01*
X230400Y498553D01*
X230442Y498261D01*
X230608Y497886D01*
X229525Y498011D01*
Y499136D01*
G01X232025Y501611D02*
X229525D01*
X230025Y501111D01*
G01X232025D02*
Y502111D01*
G01X229525Y504711D02*
X229608Y504378D01*
X229817Y504128D01*
X230067Y503961D01*
X230400Y503836D01*
X230775Y503794D01*
X231150Y503836D01*
X231483Y503961D01*
X231733Y504128D01*
X231942Y504378D01*
X232025Y504711D01*
X231942Y505044D01*
X231733Y505294D01*
X231483Y505461D01*
X231150Y505586D01*
X230775Y505628D01*
X230400Y505586D01*
X230067Y505461D01*
X229817Y505294D01*
X229608Y505044D01*
X229525Y504711D01*
G01X234625Y491761D02*
Y486561D01*
G01Y491761D02*
X227625D01*
G01X248025Y494578D02*
X245525D01*
Y495619D01*
X245650Y495953D01*
X245817Y496161D01*
X246150Y496244D01*
X246483Y496161D01*
X246692Y495911D01*
X246817Y495619D01*
Y494578D01*
G01Y495619D02*
X248025Y496244D01*
G01X247650Y497594D02*
X247858Y497844D01*
X247983Y498136D01*
X248025Y498511D01*
X247942Y498886D01*
X247775Y499178D01*
X247483Y499386D01*
X247150Y499428D01*
X246817Y499344D01*
X246608Y499136D01*
X246442Y498844D01*
X246400Y498553D01*
X246442Y498261D01*
X246608Y497886D01*
X245525Y498011D01*
Y499136D01*
G01X248025Y501611D02*
X245525D01*
X246025Y501111D01*
G01X248025D02*
Y502111D01*
G01Y504711D02*
X245525D01*
X246025Y504211D01*
G01X248025D02*
Y505211D01*
G01X250625Y491761D02*
Y486561D01*
G01Y491761D02*
X243625D01*
G01X272300Y44500D02*
Y40500D01*
X279700D01*
G01X272300Y40000D02*
Y36000D01*
X279700D01*
G01X272300Y35500D02*
Y31500D01*
X279700D01*
G01X272300Y31000D02*
Y27000D01*
X279700D01*
G01X290017Y110500D02*
Y113000D01*
X291058D01*
X291392Y112875D01*
X291600Y112708D01*
X291683Y112375D01*
X291600Y112042D01*
X291350Y111833D01*
X291058Y111708D01*
X290017D01*
G01X291058D02*
X291683Y110500D01*
G01X293033Y111000D02*
X293283Y110708D01*
X293617Y110542D01*
X293992Y110500D01*
X294325Y110542D01*
X294658Y110750D01*
X294867Y111000D01*
X294908Y111250D01*
X294825Y111542D01*
X294533Y111750D01*
X294242Y111833D01*
X293867D01*
G01X294242D02*
X294492Y111958D01*
X294700Y112167D01*
X294783Y112417D01*
X294700Y112667D01*
X294492Y112875D01*
X294117Y113000D01*
X293742Y112958D01*
X293367Y112792D01*
G01X297550Y110500D02*
Y113000D01*
X296008Y111208D01*
X298092D01*
G01X300150Y110500D02*
X300442Y110542D01*
X300775Y110667D01*
X300983Y110875D01*
X301067Y111167D01*
X300983Y111458D01*
X300733Y111708D01*
X300358Y111833D01*
X299942D01*
X299692Y111917D01*
X299483Y112125D01*
X299400Y112417D01*
X299525Y112708D01*
X299817Y112917D01*
X300150Y113000D01*
X300483Y112917D01*
X300775Y112708D01*
X300900Y112417D01*
X300817Y112125D01*
X300608Y111917D01*
X300358Y111833D01*
X299942D01*
X299567Y111708D01*
X299317Y111458D01*
X299233Y111167D01*
X299317Y110875D01*
X299525Y110667D01*
X299858Y110542D01*
X300150Y110500D01*
G01X301835Y102177D02*
Y106177D01*
X294435D01*
G01X272202Y56550D02*
X273652Y55100D01*
G01X270752D02*
X272202Y56550D01*
G01X266702Y55100D02*
X277702D01*
G01X266702Y75700D02*
Y55100D01*
G01X277702Y75700D02*
X266702D01*
G01X277702Y55100D02*
Y75700D01*
G01X270285Y116484D02*
Y118984D01*
X271326D01*
X271660Y118859D01*
X271868Y118692D01*
X271951Y118359D01*
X271868Y118026D01*
X271618Y117817D01*
X271326Y117692D01*
X270285D01*
G01X271326D02*
X271951Y116484D01*
G01X274218D02*
Y118984D01*
X273718Y118484D01*
G01Y116484D02*
X274718D01*
G01X276526Y117526D02*
X276818Y117817D01*
X277068Y117984D01*
X277401Y118067D01*
X277693Y117984D01*
X277901Y117817D01*
X278068Y117567D01*
X278110Y117276D01*
X278068Y117026D01*
X277901Y116776D01*
X277651Y116567D01*
X277360Y116484D01*
X277026Y116567D01*
X276735Y116817D01*
X276568Y117192D01*
X276526Y117609D01*
X276610Y118151D01*
X276735Y118442D01*
X276943Y118734D01*
X277235Y118942D01*
X277526Y118984D01*
X277818Y118901D01*
X278026Y118692D01*
G01X280418Y116484D02*
Y118984D01*
X279918Y118484D01*
G01Y116484D02*
X280918D01*
G01X270285Y128484D02*
Y130984D01*
X271326D01*
X271660Y130859D01*
X271868Y130692D01*
X271951Y130359D01*
X271868Y130026D01*
X271618Y129817D01*
X271326Y129692D01*
X270285D01*
G01X271326D02*
X271951Y128484D01*
G01X274218D02*
Y130984D01*
X273718Y130484D01*
G01Y128484D02*
X274718D01*
G01X276526Y129526D02*
X276818Y129817D01*
X277068Y129984D01*
X277401Y130067D01*
X277693Y129984D01*
X277901Y129817D01*
X278068Y129567D01*
X278110Y129276D01*
X278068Y129026D01*
X277901Y128776D01*
X277651Y128567D01*
X277360Y128484D01*
X277026Y128567D01*
X276735Y128817D01*
X276568Y129192D01*
X276526Y129609D01*
X276610Y130151D01*
X276735Y130442D01*
X276943Y130734D01*
X277235Y130942D01*
X277526Y130984D01*
X277818Y130901D01*
X278026Y130692D01*
G01X279501Y128859D02*
X279751Y128651D01*
X280043Y128526D01*
X280418Y128484D01*
X280793Y128567D01*
X281085Y128734D01*
X281293Y129026D01*
X281335Y129359D01*
X281251Y129692D01*
X281043Y129901D01*
X280751Y130067D01*
X280460Y130109D01*
X280168Y130067D01*
X279793Y129901D01*
X279918Y130984D01*
X281043D01*
G01X270285Y122984D02*
Y120484D01*
X271951D01*
G01X274218D02*
Y122984D01*
X273718Y122484D01*
G01Y120484D02*
X274718D01*
G01X277318D02*
Y122984D01*
X276818Y122484D01*
G01Y120484D02*
X277818D01*
G01X270800Y144000D02*
Y151000D01*
X284200D01*
Y144000D01*
X270800D01*
G01X270285Y126984D02*
Y124484D01*
X271951D01*
G01X274218D02*
Y126984D01*
X273718Y126484D01*
G01Y124484D02*
X274718D01*
G01X277818D02*
Y126984D01*
X276276Y125192D01*
X278360D01*
G01X270800Y153000D02*
Y160000D01*
X284200D01*
Y153000D01*
X270800D01*
G01X301042Y137267D02*
X300917Y137017D01*
X300834Y136725D01*
Y136392D01*
X300959Y136017D01*
X301167Y135725D01*
X301417Y135517D01*
X301834Y135350D01*
X302209Y135308D01*
X302584Y135392D01*
X302834Y135517D01*
X303084Y135767D01*
X303251Y136058D01*
X303334Y136350D01*
Y136642D01*
X303251Y136933D01*
X303126Y137183D01*
X302959Y137392D01*
G01X301251Y138658D02*
X301001Y138908D01*
X300876Y139200D01*
X300834Y139533D01*
X300917Y139950D01*
X301126Y140242D01*
X301376Y140325D01*
X301626Y140283D01*
X301834Y140117D01*
X302251Y139283D01*
X302542Y138908D01*
X302959Y138658D01*
X303334Y138575D01*
Y140325D01*
G01X302959Y141633D02*
X303167Y141883D01*
X303292Y142175D01*
X303334Y142550D01*
X303251Y142925D01*
X303084Y143217D01*
X302792Y143425D01*
X302459Y143467D01*
X302126Y143383D01*
X301917Y143175D01*
X301751Y142883D01*
X301709Y142592D01*
X301751Y142300D01*
X301917Y141925D01*
X300834Y142050D01*
Y143175D01*
G01X302959Y144733D02*
X303167Y144983D01*
X303292Y145275D01*
X303334Y145650D01*
X303251Y146025D01*
X303084Y146317D01*
X302792Y146525D01*
X302459Y146567D01*
X302126Y146483D01*
X301917Y146275D01*
X301751Y145983D01*
X301709Y145692D01*
X301751Y145400D01*
X301917Y145025D01*
X300834Y145150D01*
Y146275D01*
G01X293500Y150800D02*
Y145300D01*
G01X285500Y150800D02*
X293500D01*
G01X285500Y145300D02*
Y150800D01*
G01Y133200D02*
Y138700D01*
G01X293500Y133200D02*
X285500D01*
G01X293500Y138700D02*
Y133200D01*
G01X285500Y175200D02*
Y180700D01*
G01X293500Y175200D02*
X285500D01*
G01X293500Y180700D02*
Y175200D01*
G01X300216Y158005D02*
X300091Y157755D01*
X300008Y157463D01*
Y157130D01*
X300133Y156755D01*
X300341Y156463D01*
X300591Y156255D01*
X301008Y156088D01*
X301383Y156046D01*
X301758Y156130D01*
X302008Y156255D01*
X302258Y156505D01*
X302425Y156796D01*
X302508Y157088D01*
Y157380D01*
X302425Y157671D01*
X302300Y157921D01*
X302133Y158130D01*
G01X300425Y159396D02*
X300175Y159646D01*
X300050Y159938D01*
X300008Y160271D01*
X300091Y160688D01*
X300300Y160980D01*
X300550Y161063D01*
X300800Y161021D01*
X301008Y160855D01*
X301425Y160021D01*
X301716Y159646D01*
X302133Y159396D01*
X302508Y159313D01*
Y161063D01*
G01Y163288D02*
X302466Y163580D01*
X302341Y163913D01*
X302133Y164121D01*
X301841Y164205D01*
X301550Y164121D01*
X301300Y163871D01*
X301175Y163496D01*
Y163080D01*
X301091Y162830D01*
X300883Y162621D01*
X300591Y162538D01*
X300300Y162663D01*
X300091Y162955D01*
X300008Y163288D01*
X300091Y163621D01*
X300300Y163913D01*
X300591Y164038D01*
X300883Y163955D01*
X301091Y163746D01*
X301175Y163496D01*
Y163080D01*
X301300Y162705D01*
X301550Y162455D01*
X301841Y162371D01*
X302133Y162455D01*
X302341Y162663D01*
X302466Y162996D01*
X302508Y163288D01*
G01X302008Y165471D02*
X302300Y165721D01*
X302466Y166055D01*
X302508Y166430D01*
X302466Y166763D01*
X302258Y167096D01*
X302008Y167305D01*
X301758Y167346D01*
X301466Y167263D01*
X301258Y166971D01*
X301175Y166680D01*
Y166305D01*
G01Y166680D02*
X301050Y166930D01*
X300841Y167138D01*
X300591Y167221D01*
X300341Y167138D01*
X300133Y166930D01*
X300008Y166555D01*
X300050Y166180D01*
X300216Y165805D01*
G01X285500Y153200D02*
Y158700D01*
G01X293500Y153200D02*
X285500D01*
G01X293500Y158700D02*
Y153200D01*
G01Y170800D02*
Y165300D01*
G01X285500Y170800D02*
X293500D01*
G01X285500Y165300D02*
Y170800D01*
G01X305042Y137267D02*
X304917Y137017D01*
X304834Y136725D01*
Y136392D01*
X304959Y136017D01*
X305167Y135725D01*
X305417Y135517D01*
X305834Y135350D01*
X306209Y135308D01*
X306584Y135392D01*
X306834Y135517D01*
X307084Y135767D01*
X307251Y136058D01*
X307334Y136350D01*
Y136642D01*
X307251Y136933D01*
X307126Y137183D01*
X306959Y137392D01*
G01X305251Y138658D02*
X305001Y138908D01*
X304876Y139200D01*
X304834Y139533D01*
X304917Y139950D01*
X305126Y140242D01*
X305376Y140325D01*
X305626Y140283D01*
X305834Y140117D01*
X306251Y139283D01*
X306542Y138908D01*
X306959Y138658D01*
X307334Y138575D01*
Y140325D01*
G01X306959Y141633D02*
X307167Y141883D01*
X307292Y142175D01*
X307334Y142550D01*
X307251Y142925D01*
X307084Y143217D01*
X306792Y143425D01*
X306459Y143467D01*
X306126Y143383D01*
X305917Y143175D01*
X305751Y142883D01*
X305709Y142592D01*
X305751Y142300D01*
X305917Y141925D01*
X304834Y142050D01*
Y143175D01*
G01X306292Y144858D02*
X306001Y145150D01*
X305834Y145400D01*
X305751Y145733D01*
X305834Y146025D01*
X306001Y146233D01*
X306251Y146400D01*
X306542Y146442D01*
X306792Y146400D01*
X307042Y146233D01*
X307251Y145983D01*
X307334Y145692D01*
X307251Y145358D01*
X307001Y145067D01*
X306626Y144900D01*
X306209Y144858D01*
X305667Y144942D01*
X305376Y145067D01*
X305084Y145275D01*
X304876Y145567D01*
X304834Y145858D01*
X304917Y146150D01*
X305126Y146358D01*
G01X304216Y158005D02*
X304091Y157755D01*
X304008Y157463D01*
Y157130D01*
X304133Y156755D01*
X304341Y156463D01*
X304591Y156255D01*
X305008Y156088D01*
X305383Y156046D01*
X305758Y156130D01*
X306008Y156255D01*
X306258Y156505D01*
X306425Y156796D01*
X306508Y157088D01*
Y157380D01*
X306425Y157671D01*
X306300Y157921D01*
X306133Y158130D01*
G01X304425Y159396D02*
X304175Y159646D01*
X304050Y159938D01*
X304008Y160271D01*
X304091Y160688D01*
X304300Y160980D01*
X304550Y161063D01*
X304800Y161021D01*
X305008Y160855D01*
X305425Y160021D01*
X305716Y159646D01*
X306133Y159396D01*
X306508Y159313D01*
Y161063D01*
G01Y163288D02*
X306466Y163580D01*
X306341Y163913D01*
X306133Y164121D01*
X305841Y164205D01*
X305550Y164121D01*
X305300Y163871D01*
X305175Y163496D01*
Y163080D01*
X305091Y162830D01*
X304883Y162621D01*
X304591Y162538D01*
X304300Y162663D01*
X304091Y162955D01*
X304008Y163288D01*
X304091Y163621D01*
X304300Y163913D01*
X304591Y164038D01*
X304883Y163955D01*
X305091Y163746D01*
X305175Y163496D01*
Y163080D01*
X305300Y162705D01*
X305550Y162455D01*
X305841Y162371D01*
X306133Y162455D01*
X306341Y162663D01*
X306466Y162996D01*
X306508Y163288D01*
G01Y166388D02*
X306466Y166680D01*
X306341Y167013D01*
X306133Y167221D01*
X305841Y167305D01*
X305550Y167221D01*
X305300Y166971D01*
X305175Y166596D01*
Y166180D01*
X305091Y165930D01*
X304883Y165721D01*
X304591Y165638D01*
X304300Y165763D01*
X304091Y166055D01*
X304008Y166388D01*
X304091Y166721D01*
X304300Y167013D01*
X304591Y167138D01*
X304883Y167055D01*
X305091Y166846D01*
X305175Y166596D01*
Y166180D01*
X305300Y165805D01*
X305550Y165555D01*
X305841Y165471D01*
X306133Y165555D01*
X306341Y165763D01*
X306466Y166096D01*
X306508Y166388D01*
G01X267100Y138500D02*
Y156500D01*
G01X313950Y230400D02*
X317450Y235400D01*
G01X313950D02*
X317450Y230400D01*
G01X321300D02*
Y235400D01*
X320300Y234400D01*
G01Y230400D02*
X322300D01*
G01X326900Y230233D02*
X326733Y230317D01*
Y230483D01*
X326900Y230567D01*
X327067Y230483D01*
Y230317D01*
X326900Y230233D01*
G01Y232483D02*
X326733Y232567D01*
Y232733D01*
X326900Y232817D01*
X327067Y232733D01*
Y232567D01*
X326900Y232483D01*
G01X330917Y234567D02*
X331417Y235067D01*
X332000Y235317D01*
X332667Y235400D01*
X333500Y235233D01*
X334083Y234817D01*
X334250Y234317D01*
X334167Y233817D01*
X333833Y233400D01*
X332167Y232567D01*
X331417Y231983D01*
X330917Y231150D01*
X330750Y230400D01*
X334250D01*
G01X336267Y231150D02*
X336767Y230733D01*
X337350Y230483D01*
X338100Y230400D01*
X338850Y230567D01*
X339433Y230900D01*
X339850Y231483D01*
X339933Y232150D01*
X339767Y232817D01*
X339350Y233233D01*
X338767Y233567D01*
X338183Y233650D01*
X337600Y233567D01*
X336850Y233233D01*
X337100Y235400D01*
X339350D01*
G01X341533Y230400D02*
Y235400D01*
X343700Y231233D01*
X345867Y235400D01*
Y230400D01*
G01X347550D02*
Y235400D01*
G01X351050D02*
Y230400D01*
G01Y232900D02*
X347550D01*
G01X353317Y235400D02*
X356483D01*
X353317Y230400D01*
X356483D01*
G01X272487Y212598D02*
Y215098D01*
X273528D01*
X273862Y214973D01*
X274070Y214806D01*
X274153Y214473D01*
X274070Y214140D01*
X273820Y213931D01*
X273528Y213806D01*
X272487D01*
G01X273528D02*
X274153Y212598D01*
G01X276420D02*
Y215098D01*
X275920Y214598D01*
G01Y212598D02*
X276920D01*
G01X278728Y213640D02*
X279020Y213931D01*
X279270Y214098D01*
X279603Y214181D01*
X279895Y214098D01*
X280103Y213931D01*
X280270Y213681D01*
X280312Y213390D01*
X280270Y213140D01*
X280103Y212890D01*
X279853Y212681D01*
X279562Y212598D01*
X279228Y212681D01*
X278937Y212931D01*
X278770Y213306D01*
X278728Y213723D01*
X278812Y214265D01*
X278937Y214556D01*
X279145Y214848D01*
X279437Y215056D01*
X279728Y215098D01*
X280020Y215015D01*
X280228Y214806D01*
G01X281703Y213098D02*
X281953Y212806D01*
X282287Y212640D01*
X282662Y212598D01*
X282995Y212640D01*
X283328Y212848D01*
X283537Y213098D01*
X283578Y213348D01*
X283495Y213640D01*
X283203Y213848D01*
X282912Y213931D01*
X282537D01*
G01X282912D02*
X283162Y214056D01*
X283370Y214265D01*
X283453Y214515D01*
X283370Y214765D01*
X283162Y214973D01*
X282787Y215098D01*
X282412Y215056D01*
X282037Y214890D01*
G01X312789Y184023D02*
Y186523D01*
X313830D01*
X314164Y186398D01*
X314372Y186231D01*
X314455Y185898D01*
X314372Y185565D01*
X314122Y185356D01*
X313830Y185231D01*
X312789D01*
G01X313830D02*
X314455Y184023D01*
G01X316722D02*
Y186523D01*
X316222Y186023D01*
G01Y184023D02*
X317222D01*
G01X319030Y185065D02*
X319322Y185356D01*
X319572Y185523D01*
X319905Y185606D01*
X320197Y185523D01*
X320405Y185356D01*
X320572Y185106D01*
X320614Y184815D01*
X320572Y184565D01*
X320405Y184315D01*
X320155Y184106D01*
X319864Y184023D01*
X319530Y184106D01*
X319239Y184356D01*
X319072Y184731D01*
X319030Y185148D01*
X319114Y185690D01*
X319239Y185981D01*
X319447Y186273D01*
X319739Y186481D01*
X320030Y186523D01*
X320322Y186440D01*
X320530Y186231D01*
G01X323422Y184023D02*
Y186523D01*
X321880Y184731D01*
X323964D01*
G01X270800Y236000D02*
Y243000D01*
X284200D01*
Y236000D01*
X270800D01*
G01X272487Y211098D02*
Y208598D01*
X274153D01*
G01X276420D02*
Y211098D01*
X275920Y210598D01*
G01Y208598D02*
X276920D01*
G01X278603Y209098D02*
X278853Y208806D01*
X279187Y208640D01*
X279562Y208598D01*
X279895Y208640D01*
X280228Y208848D01*
X280437Y209098D01*
X280478Y209348D01*
X280395Y209640D01*
X280103Y209848D01*
X279812Y209931D01*
X279437D01*
G01X279812D02*
X280062Y210056D01*
X280270Y210265D01*
X280353Y210515D01*
X280270Y210765D01*
X280062Y210973D01*
X279687Y211098D01*
X279312Y211056D01*
X278937Y210890D01*
G01X270800Y194500D02*
Y201500D01*
X284200D01*
Y194500D01*
X270800D01*
G01Y227500D02*
Y234500D01*
X284200D01*
Y227500D01*
X270800D01*
G01X312789Y190523D02*
Y188023D01*
X314455D01*
G01X316722D02*
Y190523D01*
X316222Y190023D01*
G01Y188023D02*
X317222D01*
G01X319822D02*
X320114Y188065D01*
X320447Y188190D01*
X320655Y188398D01*
X320739Y188690D01*
X320655Y188981D01*
X320405Y189231D01*
X320030Y189356D01*
X319614D01*
X319364Y189440D01*
X319155Y189648D01*
X319072Y189940D01*
X319197Y190231D01*
X319489Y190440D01*
X319822Y190523D01*
X320155Y190440D01*
X320447Y190231D01*
X320572Y189940D01*
X320489Y189648D01*
X320280Y189440D01*
X320030Y189356D01*
X319614D01*
X319239Y189231D01*
X318989Y188981D01*
X318905Y188690D01*
X318989Y188398D01*
X319197Y188190D01*
X319530Y188065D01*
X319822Y188023D01*
G01X270800Y186000D02*
Y193000D01*
X284200D01*
Y186000D01*
X270800D01*
G01X285500Y236200D02*
Y241700D01*
G01X293500Y236200D02*
X285500D01*
G01X293500Y241700D02*
Y236200D01*
G01X300042Y199767D02*
X299917Y199517D01*
X299834Y199225D01*
Y198892D01*
X299959Y198517D01*
X300167Y198225D01*
X300417Y198017D01*
X300834Y197850D01*
X301209Y197808D01*
X301584Y197892D01*
X301834Y198017D01*
X302084Y198267D01*
X302251Y198558D01*
X302334Y198850D01*
Y199142D01*
X302251Y199433D01*
X302126Y199683D01*
X301959Y199892D01*
G01X300251Y201158D02*
X300001Y201408D01*
X299876Y201700D01*
X299834Y202033D01*
X299917Y202450D01*
X300126Y202742D01*
X300376Y202825D01*
X300626Y202783D01*
X300834Y202617D01*
X301251Y201783D01*
X301542Y201408D01*
X301959Y201158D01*
X302334Y201075D01*
Y202825D01*
G01Y204967D02*
X301792Y205050D01*
X301334Y205175D01*
X300917Y205342D01*
X300459Y205550D01*
X299834Y205883D01*
Y204217D01*
G01Y208150D02*
X299917Y207817D01*
X300126Y207567D01*
X300376Y207400D01*
X300709Y207275D01*
X301084Y207233D01*
X301459Y207275D01*
X301792Y207400D01*
X302042Y207567D01*
X302251Y207817D01*
X302334Y208150D01*
X302251Y208483D01*
X302042Y208733D01*
X301792Y208900D01*
X301459Y209025D01*
X301084Y209067D01*
X300709Y209025D01*
X300376Y208900D01*
X300126Y208733D01*
X299917Y208483D01*
X299834Y208150D01*
G01X285500Y194700D02*
Y200200D01*
G01X293500Y194700D02*
X285500D01*
G01X293500Y200200D02*
Y194700D01*
G01Y212300D02*
Y206800D01*
G01X285500Y212300D02*
X293500D01*
G01X285500Y206800D02*
Y212300D01*
G01X293500Y192800D02*
Y187300D01*
G01X285500Y192800D02*
X293500D01*
G01X285500Y187300D02*
Y192800D01*
G01X300708Y221767D02*
X300583Y221517D01*
X300500Y221225D01*
Y220892D01*
X300625Y220517D01*
X300833Y220225D01*
X301083Y220017D01*
X301500Y219850D01*
X301875Y219808D01*
X302250Y219892D01*
X302500Y220017D01*
X302750Y220267D01*
X302917Y220558D01*
X303000Y220850D01*
Y221142D01*
X302917Y221433D01*
X302792Y221683D01*
X302625Y221892D01*
G01X300917Y223158D02*
X300667Y223408D01*
X300542Y223700D01*
X300500Y224033D01*
X300583Y224450D01*
X300792Y224742D01*
X301042Y224825D01*
X301292Y224783D01*
X301500Y224617D01*
X301917Y223783D01*
X302208Y223408D01*
X302625Y223158D01*
X303000Y223075D01*
Y224825D01*
G01X302708Y226342D02*
X302917Y226633D01*
X303000Y226967D01*
X302917Y227300D01*
X302667Y227592D01*
X302292Y227800D01*
X301917Y227883D01*
X301458D01*
X301083Y227800D01*
X300750Y227592D01*
X300583Y227342D01*
X300500Y227050D01*
X300583Y226717D01*
X300750Y226467D01*
X301000Y226300D01*
X301333Y226217D01*
X301625Y226300D01*
X301917Y226508D01*
X302083Y226758D01*
X302125Y227050D01*
X302042Y227383D01*
X301833Y227633D01*
X301458Y227883D01*
G01X300500Y230150D02*
X300583Y229817D01*
X300792Y229567D01*
X301042Y229400D01*
X301375Y229275D01*
X301750Y229233D01*
X302125Y229275D01*
X302458Y229400D01*
X302708Y229567D01*
X302917Y229817D01*
X303000Y230150D01*
X302917Y230483D01*
X302708Y230733D01*
X302458Y230900D01*
X302125Y231025D01*
X301750Y231067D01*
X301375Y231025D01*
X301042Y230900D01*
X300792Y230733D01*
X300583Y230483D01*
X300500Y230150D01*
G01X293500Y234300D02*
Y228800D01*
G01X285500Y234300D02*
X293500D01*
G01X285500Y228800D02*
Y234300D01*
G01Y216700D02*
Y222200D01*
G01X293500Y216700D02*
X285500D01*
G01X293500Y222200D02*
Y216700D01*
G01X304542Y199967D02*
X304417Y199717D01*
X304334Y199425D01*
Y199092D01*
X304459Y198717D01*
X304667Y198425D01*
X304917Y198217D01*
X305334Y198050D01*
X305709Y198008D01*
X306084Y198092D01*
X306334Y198217D01*
X306584Y198467D01*
X306751Y198758D01*
X306834Y199050D01*
Y199342D01*
X306751Y199633D01*
X306626Y199883D01*
X306459Y200092D01*
G01X304751Y201358D02*
X304501Y201608D01*
X304376Y201900D01*
X304334Y202233D01*
X304417Y202650D01*
X304626Y202942D01*
X304876Y203025D01*
X305126Y202983D01*
X305334Y202817D01*
X305751Y201983D01*
X306042Y201608D01*
X306459Y201358D01*
X306834Y201275D01*
Y203025D01*
G01Y205167D02*
X306292Y205250D01*
X305834Y205375D01*
X305417Y205542D01*
X304959Y205750D01*
X304334Y206083D01*
Y204417D01*
G01X306459Y207433D02*
X306667Y207683D01*
X306792Y207975D01*
X306834Y208350D01*
X306751Y208725D01*
X306584Y209017D01*
X306292Y209225D01*
X305959Y209267D01*
X305626Y209183D01*
X305417Y208975D01*
X305251Y208683D01*
X305209Y208392D01*
X305251Y208100D01*
X305417Y207725D01*
X304334Y207850D01*
Y208975D01*
G01X305208Y221117D02*
X305083Y220867D01*
X305000Y220575D01*
Y220242D01*
X305125Y219867D01*
X305333Y219575D01*
X305583Y219367D01*
X306000Y219200D01*
X306375Y219158D01*
X306750Y219242D01*
X307000Y219367D01*
X307250Y219617D01*
X307417Y219908D01*
X307500Y220200D01*
Y220492D01*
X307417Y220783D01*
X307292Y221033D01*
X307125Y221242D01*
G01X305417Y222508D02*
X305167Y222758D01*
X305042Y223050D01*
X305000Y223383D01*
X305083Y223800D01*
X305292Y224092D01*
X305542Y224175D01*
X305792Y224133D01*
X306000Y223967D01*
X306417Y223133D01*
X306708Y222758D01*
X307125Y222508D01*
X307500Y222425D01*
Y224175D01*
G01X307208Y225692D02*
X307417Y225983D01*
X307500Y226317D01*
X307417Y226650D01*
X307167Y226942D01*
X306792Y227150D01*
X306417Y227233D01*
X305958D01*
X305583Y227150D01*
X305250Y226942D01*
X305083Y226692D01*
X305000Y226400D01*
X305083Y226067D01*
X305250Y225817D01*
X305500Y225650D01*
X305833Y225567D01*
X306125Y225650D01*
X306417Y225858D01*
X306583Y226108D01*
X306625Y226400D01*
X306542Y226733D01*
X306333Y226983D01*
X305958Y227233D01*
G01X307125Y228583D02*
X307333Y228833D01*
X307458Y229125D01*
X307500Y229500D01*
X307417Y229875D01*
X307250Y230167D01*
X306958Y230375D01*
X306625Y230417D01*
X306292Y230333D01*
X306083Y230125D01*
X305917Y229833D01*
X305875Y229542D01*
X305917Y229250D01*
X306083Y228875D01*
X305000Y229000D01*
Y230125D01*
G01X266350Y229600D02*
Y247600D01*
G01X266300Y204500D02*
Y222500D01*
G01X287117Y272966D02*
Y275466D01*
X288158D01*
X288492Y275341D01*
X288700Y275174D01*
X288783Y274841D01*
X288700Y274508D01*
X288450Y274299D01*
X288158Y274174D01*
X287117D01*
G01X288158D02*
X288783Y272966D01*
G01X291550D02*
Y275466D01*
X290008Y273674D01*
X292092D01*
G01X293233Y273466D02*
X293483Y273174D01*
X293817Y273008D01*
X294192Y272966D01*
X294525Y273008D01*
X294858Y273216D01*
X295067Y273466D01*
X295108Y273716D01*
X295025Y274008D01*
X294733Y274216D01*
X294442Y274299D01*
X294067D01*
G01X294442D02*
X294692Y274424D01*
X294900Y274633D01*
X294983Y274883D01*
X294900Y275133D01*
X294692Y275341D01*
X294317Y275466D01*
X293942Y275424D01*
X293567Y275258D01*
G01X296542Y273258D02*
X296833Y273049D01*
X297167Y272966D01*
X297500Y273049D01*
X297792Y273299D01*
X298000Y273674D01*
X298083Y274049D01*
Y274508D01*
X298000Y274883D01*
X297792Y275216D01*
X297542Y275383D01*
X297250Y275466D01*
X296917Y275383D01*
X296667Y275216D01*
X296500Y274966D01*
X296417Y274633D01*
X296500Y274341D01*
X296708Y274049D01*
X296958Y273883D01*
X297250Y273841D01*
X297583Y273924D01*
X297833Y274133D01*
X298083Y274508D01*
G01X281541Y280576D02*
Y276576D01*
X288941D01*
G01X314834Y288067D02*
X312334D01*
Y289108D01*
X312459Y289442D01*
X312626Y289650D01*
X312959Y289733D01*
X313292Y289650D01*
X313501Y289400D01*
X313626Y289108D01*
Y288067D01*
G01Y289108D02*
X314834Y289733D01*
G01X314542Y291292D02*
X314751Y291583D01*
X314834Y291917D01*
X314751Y292250D01*
X314501Y292542D01*
X314126Y292750D01*
X313751Y292833D01*
X313292D01*
X312917Y292750D01*
X312584Y292542D01*
X312417Y292292D01*
X312334Y292000D01*
X312417Y291667D01*
X312584Y291417D01*
X312834Y291250D01*
X313167Y291167D01*
X313459Y291250D01*
X313751Y291458D01*
X313917Y291708D01*
X313959Y292000D01*
X313876Y292333D01*
X313667Y292583D01*
X313292Y292833D01*
G01X314834Y295600D02*
X312334D01*
X314126Y294058D01*
Y296142D01*
G01X316050Y291200D02*
X320050D01*
Y298600D01*
G01X273600Y289900D02*
X269600D01*
Y282500D01*
G01X265600D02*
X269600D01*
Y289900D01*
G01X277600D02*
X273600D01*
Y282500D01*
G01X306834Y293017D02*
X304334D01*
Y294058D01*
X304459Y294392D01*
X304626Y294600D01*
X304959Y294683D01*
X305292Y294600D01*
X305501Y294350D01*
X305626Y294058D01*
Y293017D01*
G01Y294058D02*
X306834Y294683D01*
G01X306459Y296033D02*
X306667Y296283D01*
X306792Y296575D01*
X306834Y296950D01*
X306751Y297325D01*
X306584Y297617D01*
X306292Y297825D01*
X305959Y297867D01*
X305626Y297783D01*
X305417Y297575D01*
X305251Y297283D01*
X305209Y296992D01*
X305251Y296700D01*
X305417Y296325D01*
X304334Y296450D01*
Y297575D01*
G01X304751Y299258D02*
X304501Y299508D01*
X304376Y299800D01*
X304334Y300133D01*
X304417Y300550D01*
X304626Y300842D01*
X304876Y300925D01*
X305126Y300883D01*
X305334Y300717D01*
X305751Y299883D01*
X306042Y299508D01*
X306459Y299258D01*
X306834Y299175D01*
Y300925D01*
G01X306542Y302442D02*
X306751Y302733D01*
X306834Y303067D01*
X306751Y303400D01*
X306501Y303692D01*
X306126Y303900D01*
X305751Y303983D01*
X305292D01*
X304917Y303900D01*
X304584Y303692D01*
X304417Y303442D01*
X304334Y303150D01*
X304417Y302817D01*
X304584Y302567D01*
X304834Y302400D01*
X305167Y302317D01*
X305459Y302400D01*
X305751Y302608D01*
X305917Y302858D01*
X305959Y303150D01*
X305876Y303483D01*
X305667Y303733D01*
X305292Y303983D01*
G01X296708Y297526D02*
X292708D01*
Y290126D01*
G01X300517Y273000D02*
Y275500D01*
X301558D01*
X301892Y275375D01*
X302100Y275208D01*
X302183Y274875D01*
X302100Y274542D01*
X301850Y274333D01*
X301558Y274208D01*
X300517D01*
G01X301558D02*
X302183Y273000D01*
G01X303533Y273375D02*
X303783Y273167D01*
X304075Y273042D01*
X304450Y273000D01*
X304825Y273083D01*
X305117Y273250D01*
X305325Y273542D01*
X305367Y273875D01*
X305283Y274208D01*
X305075Y274417D01*
X304783Y274583D01*
X304492Y274625D01*
X304200Y274583D01*
X303825Y274417D01*
X303950Y275500D01*
X305075D01*
G01X308050Y273000D02*
Y275500D01*
X306508Y273708D01*
X308592D01*
G01X310650Y275500D02*
X310317Y275417D01*
X310067Y275208D01*
X309900Y274958D01*
X309775Y274625D01*
X309733Y274250D01*
X309775Y273875D01*
X309900Y273542D01*
X310067Y273292D01*
X310317Y273083D01*
X310650Y273000D01*
X310983Y273083D01*
X311233Y273292D01*
X311400Y273542D01*
X311525Y273875D01*
X311567Y274250D01*
X311525Y274625D01*
X311400Y274958D01*
X311233Y275208D01*
X310983Y275417D01*
X310650Y275500D01*
G01X296010Y283122D02*
Y279122D01*
X303410D01*
G01X276506Y299434D02*
Y295434D01*
X283906D01*
G01X302500Y286017D02*
X300000D01*
Y287058D01*
X300125Y287392D01*
X300292Y287600D01*
X300625Y287683D01*
X300958Y287600D01*
X301167Y287350D01*
X301292Y287058D01*
Y286017D01*
G01Y287058D02*
X302500Y287683D01*
G01X302125Y289033D02*
X302333Y289283D01*
X302458Y289575D01*
X302500Y289950D01*
X302417Y290325D01*
X302250Y290617D01*
X301958Y290825D01*
X301625Y290867D01*
X301292Y290783D01*
X301083Y290575D01*
X300917Y290283D01*
X300875Y289992D01*
X300917Y289700D01*
X301083Y289325D01*
X300000Y289450D01*
Y290575D01*
G01X302500Y293550D02*
X300000D01*
X301792Y292008D01*
Y294092D01*
G01X300417Y295358D02*
X300167Y295608D01*
X300042Y295900D01*
X300000Y296233D01*
X300083Y296650D01*
X300292Y296942D01*
X300542Y297025D01*
X300792Y296983D01*
X301000Y296817D01*
X301417Y295983D01*
X301708Y295608D01*
X302125Y295358D01*
X302500Y295275D01*
Y297025D01*
G01X289214Y293617D02*
X285214D01*
Y286217D01*
G01X320834Y246567D02*
X318334D01*
Y247608D01*
X318459Y247942D01*
X318626Y248150D01*
X318959Y248233D01*
X319292Y248150D01*
X319501Y247900D01*
X319626Y247608D01*
Y246567D01*
G01Y247608D02*
X320834Y248233D01*
G01Y250417D02*
X320292Y250500D01*
X319834Y250625D01*
X319417Y250792D01*
X318959Y251000D01*
X318334Y251333D01*
Y249667D01*
G01X319792Y252808D02*
X319501Y253100D01*
X319334Y253350D01*
X319251Y253683D01*
X319334Y253975D01*
X319501Y254183D01*
X319751Y254350D01*
X320042Y254392D01*
X320292Y254350D01*
X320542Y254183D01*
X320751Y253933D01*
X320834Y253642D01*
X320751Y253308D01*
X320501Y253017D01*
X320126Y252850D01*
X319709Y252808D01*
X319167Y252892D01*
X318876Y253017D01*
X318584Y253225D01*
X318376Y253517D01*
X318334Y253808D01*
X318417Y254100D01*
X318626Y254308D01*
G01X325900Y253200D02*
X321900D01*
Y245800D01*
G01X276042Y275596D02*
X275792Y275721D01*
X275500Y275804D01*
X275167D01*
X274792Y275679D01*
X274500Y275471D01*
X274292Y275221D01*
X274125Y274804D01*
X274083Y274429D01*
X274167Y274054D01*
X274292Y273804D01*
X274542Y273554D01*
X274833Y273387D01*
X275125Y273304D01*
X275417D01*
X275708Y273387D01*
X275958Y273512D01*
X276167Y273679D01*
G01X277308D02*
X277558Y273471D01*
X277850Y273346D01*
X278225Y273304D01*
X278600Y273387D01*
X278892Y273554D01*
X279100Y273846D01*
X279142Y274179D01*
X279058Y274512D01*
X278850Y274721D01*
X278558Y274887D01*
X278267Y274929D01*
X277975Y274887D01*
X277600Y274721D01*
X277725Y275804D01*
X278850D01*
G01X280408Y273679D02*
X280658Y273471D01*
X280950Y273346D01*
X281325Y273304D01*
X281700Y273387D01*
X281992Y273554D01*
X282200Y273846D01*
X282242Y274179D01*
X282158Y274512D01*
X281950Y274721D01*
X281658Y274887D01*
X281367Y274929D01*
X281075Y274887D01*
X280700Y274721D01*
X280825Y275804D01*
X281950D01*
G01X283717Y273596D02*
X284008Y273387D01*
X284342Y273304D01*
X284675Y273387D01*
X284967Y273637D01*
X285175Y274012D01*
X285258Y274387D01*
Y274846D01*
X285175Y275221D01*
X284967Y275554D01*
X284717Y275721D01*
X284425Y275804D01*
X284092Y275721D01*
X283842Y275554D01*
X283675Y275304D01*
X283592Y274971D01*
X283675Y274679D01*
X283883Y274387D01*
X284133Y274221D01*
X284425Y274179D01*
X284758Y274262D01*
X285008Y274471D01*
X285258Y274846D01*
G01X271111Y264661D02*
Y267161D01*
X272152D01*
X272486Y267036D01*
X272694Y266869D01*
X272777Y266536D01*
X272694Y266203D01*
X272444Y265994D01*
X272152Y265869D01*
X271111D01*
G01X272152D02*
X272777Y264661D01*
G01X275044D02*
Y267161D01*
X274544Y266661D01*
G01Y264661D02*
X275544D01*
G01X277352Y265703D02*
X277644Y265994D01*
X277894Y266161D01*
X278227Y266244D01*
X278519Y266161D01*
X278727Y265994D01*
X278894Y265744D01*
X278936Y265453D01*
X278894Y265203D01*
X278727Y264953D01*
X278477Y264744D01*
X278186Y264661D01*
X277852Y264744D01*
X277561Y264994D01*
X277394Y265369D01*
X277352Y265786D01*
X277436Y266328D01*
X277561Y266619D01*
X277769Y266911D01*
X278061Y267119D01*
X278352Y267161D01*
X278644Y267078D01*
X278852Y266869D01*
G01X280452Y266744D02*
X280702Y266994D01*
X280994Y267119D01*
X281327Y267161D01*
X281744Y267078D01*
X282036Y266869D01*
X282119Y266619D01*
X282077Y266369D01*
X281911Y266161D01*
X281077Y265744D01*
X280702Y265453D01*
X280452Y265036D01*
X280369Y264661D01*
X282119D01*
G01X271111Y252661D02*
Y255161D01*
X272152D01*
X272486Y255036D01*
X272694Y254869D01*
X272777Y254536D01*
X272694Y254203D01*
X272444Y253994D01*
X272152Y253869D01*
X271111D01*
G01X272152D02*
X272777Y252661D01*
G01X275044D02*
Y255161D01*
X274544Y254661D01*
G01Y252661D02*
X275544D01*
G01X277352Y253703D02*
X277644Y253994D01*
X277894Y254161D01*
X278227Y254244D01*
X278519Y254161D01*
X278727Y253994D01*
X278894Y253744D01*
X278936Y253453D01*
X278894Y253203D01*
X278727Y252953D01*
X278477Y252744D01*
X278186Y252661D01*
X277852Y252744D01*
X277561Y252994D01*
X277394Y253369D01*
X277352Y253786D01*
X277436Y254328D01*
X277561Y254619D01*
X277769Y254911D01*
X278061Y255119D01*
X278352Y255161D01*
X278644Y255078D01*
X278852Y254869D01*
G01X280452Y253703D02*
X280744Y253994D01*
X280994Y254161D01*
X281327Y254244D01*
X281619Y254161D01*
X281827Y253994D01*
X281994Y253744D01*
X282036Y253453D01*
X281994Y253203D01*
X281827Y252953D01*
X281577Y252744D01*
X281286Y252661D01*
X280952Y252744D01*
X280661Y252994D01*
X280494Y253369D01*
X280452Y253786D01*
X280536Y254328D01*
X280661Y254619D01*
X280869Y254911D01*
X281161Y255119D01*
X281452Y255161D01*
X281744Y255078D01*
X281952Y254869D01*
G01X271111Y263161D02*
Y260661D01*
X272777D01*
G01X275044D02*
Y263161D01*
X274544Y262661D01*
G01Y260661D02*
X275544D01*
G01X277352Y262744D02*
X277602Y262994D01*
X277894Y263119D01*
X278227Y263161D01*
X278644Y263078D01*
X278936Y262869D01*
X279019Y262619D01*
X278977Y262369D01*
X278811Y262161D01*
X277977Y261744D01*
X277602Y261453D01*
X277352Y261036D01*
X277269Y260661D01*
X279019D01*
G01X271111Y259161D02*
Y256661D01*
X272777D01*
G01X275044D02*
Y259161D01*
X274544Y258661D01*
G01Y256661D02*
X275544D01*
G01X277227Y257036D02*
X277477Y256828D01*
X277769Y256703D01*
X278144Y256661D01*
X278519Y256744D01*
X278811Y256911D01*
X279019Y257203D01*
X279061Y257536D01*
X278977Y257869D01*
X278769Y258078D01*
X278477Y258244D01*
X278186Y258286D01*
X277894Y258244D01*
X277519Y258078D01*
X277644Y259161D01*
X278769D01*
G01X300708Y241767D02*
X300583Y241517D01*
X300500Y241225D01*
Y240892D01*
X300625Y240517D01*
X300833Y240225D01*
X301083Y240017D01*
X301500Y239850D01*
X301875Y239808D01*
X302250Y239892D01*
X302500Y240017D01*
X302750Y240267D01*
X302917Y240558D01*
X303000Y240850D01*
Y241142D01*
X302917Y241433D01*
X302792Y241683D01*
X302625Y241892D01*
G01X300917Y243158D02*
X300667Y243408D01*
X300542Y243700D01*
X300500Y244033D01*
X300583Y244450D01*
X300792Y244742D01*
X301042Y244825D01*
X301292Y244783D01*
X301500Y244617D01*
X301917Y243783D01*
X302208Y243408D01*
X302625Y243158D01*
X303000Y243075D01*
Y244825D01*
G01X301958Y246258D02*
X301667Y246550D01*
X301500Y246800D01*
X301417Y247133D01*
X301500Y247425D01*
X301667Y247633D01*
X301917Y247800D01*
X302208Y247842D01*
X302458Y247800D01*
X302708Y247633D01*
X302917Y247383D01*
X303000Y247092D01*
X302917Y246758D01*
X302667Y246467D01*
X302292Y246300D01*
X301875Y246258D01*
X301333Y246342D01*
X301042Y246467D01*
X300750Y246675D01*
X300542Y246967D01*
X300500Y247258D01*
X300583Y247550D01*
X300792Y247758D01*
G01X300917Y249358D02*
X300667Y249608D01*
X300542Y249900D01*
X300500Y250233D01*
X300583Y250650D01*
X300792Y250942D01*
X301042Y251025D01*
X301292Y250983D01*
X301500Y250817D01*
X301917Y249983D01*
X302208Y249608D01*
X302625Y249358D01*
X303000Y249275D01*
Y251025D01*
G01X293500Y253800D02*
Y248300D01*
G01X285500Y253800D02*
X293500D01*
G01X285500Y248300D02*
Y253800D01*
G01X304708Y241767D02*
X304583Y241517D01*
X304500Y241225D01*
Y240892D01*
X304625Y240517D01*
X304833Y240225D01*
X305083Y240017D01*
X305500Y239850D01*
X305875Y239808D01*
X306250Y239892D01*
X306500Y240017D01*
X306750Y240267D01*
X306917Y240558D01*
X307000Y240850D01*
Y241142D01*
X306917Y241433D01*
X306792Y241683D01*
X306625Y241892D01*
G01X304917Y243158D02*
X304667Y243408D01*
X304542Y243700D01*
X304500Y244033D01*
X304583Y244450D01*
X304792Y244742D01*
X305042Y244825D01*
X305292Y244783D01*
X305500Y244617D01*
X305917Y243783D01*
X306208Y243408D01*
X306625Y243158D01*
X307000Y243075D01*
Y244825D01*
G01X305958Y246258D02*
X305667Y246550D01*
X305500Y246800D01*
X305417Y247133D01*
X305500Y247425D01*
X305667Y247633D01*
X305917Y247800D01*
X306208Y247842D01*
X306458Y247800D01*
X306708Y247633D01*
X306917Y247383D01*
X307000Y247092D01*
X306917Y246758D01*
X306667Y246467D01*
X306292Y246300D01*
X305875Y246258D01*
X305333Y246342D01*
X305042Y246467D01*
X304750Y246675D01*
X304542Y246967D01*
X304500Y247258D01*
X304583Y247550D01*
X304792Y247758D01*
G01X306500Y249233D02*
X306792Y249483D01*
X306958Y249817D01*
X307000Y250192D01*
X306958Y250525D01*
X306750Y250858D01*
X306500Y251067D01*
X306250Y251108D01*
X305958Y251025D01*
X305750Y250733D01*
X305667Y250442D01*
Y250067D01*
G01Y250442D02*
X305542Y250692D01*
X305333Y250900D01*
X305083Y250983D01*
X304833Y250900D01*
X304625Y250692D01*
X304500Y250317D01*
X304542Y249942D01*
X304708Y249567D01*
G01X326859Y299095D02*
X316059D01*
Y304295D01*
X326859D01*
Y299095D01*
G01X304500Y306433D02*
X306292D01*
X306667Y306600D01*
X306917Y306933D01*
X307000Y307350D01*
X306917Y307767D01*
X306667Y308100D01*
X306292Y308267D01*
X304500D01*
G01X307000Y310450D02*
X304500D01*
X305000Y309950D01*
G01X307000D02*
Y310950D01*
G01Y313550D02*
X304500D01*
X305000Y313050D01*
G01X307000D02*
Y314050D01*
G01Y316650D02*
X306958Y316942D01*
X306833Y317275D01*
X306625Y317483D01*
X306333Y317567D01*
X306042Y317483D01*
X305792Y317233D01*
X305667Y316858D01*
Y316442D01*
X305583Y316192D01*
X305375Y315983D01*
X305083Y315900D01*
X304792Y316025D01*
X304583Y316317D01*
X304500Y316650D01*
X304583Y316983D01*
X304792Y317275D01*
X305083Y317400D01*
X305375Y317317D01*
X305583Y317108D01*
X305667Y316858D01*
Y316442D01*
X305792Y316067D01*
X306042Y315817D01*
X306333Y315733D01*
X306625Y315817D01*
X306833Y316025D01*
X306958Y316358D01*
X307000Y316650D01*
G01X299938Y314339D02*
Y300939D01*
G01X289938Y314339D02*
X299938D01*
G01X289938Y300939D02*
Y314339D01*
G01X299938Y300939D02*
X289938D01*
G01X275433Y340666D02*
Y338874D01*
X275600Y338499D01*
X275933Y338249D01*
X276350Y338166D01*
X276767Y338249D01*
X277100Y338499D01*
X277267Y338874D01*
Y340666D01*
G01X279450Y338166D02*
Y340666D01*
X278950Y340166D01*
G01Y338166D02*
X279950D01*
G01X281758Y340249D02*
X282008Y340499D01*
X282300Y340624D01*
X282633Y340666D01*
X283050Y340583D01*
X283342Y340374D01*
X283425Y340124D01*
X283383Y339874D01*
X283217Y339666D01*
X282383Y339249D01*
X282008Y338958D01*
X281758Y338541D01*
X281675Y338166D01*
X283425D01*
G01X284858Y340249D02*
X285108Y340499D01*
X285400Y340624D01*
X285733Y340666D01*
X286150Y340583D01*
X286442Y340374D01*
X286525Y340124D01*
X286483Y339874D01*
X286317Y339666D01*
X285483Y339249D01*
X285108Y338958D01*
X284858Y338541D01*
X284775Y338166D01*
X286525D01*
G01X286938Y314339D02*
Y300939D01*
G01X276938Y314339D02*
X286938D01*
G01X276938Y300939D02*
Y314339D01*
G01X286938Y300939D02*
X276938D01*
G01X290834Y332517D02*
X288334D01*
Y333558D01*
X288459Y333892D01*
X288626Y334100D01*
X288959Y334183D01*
X289292Y334100D01*
X289501Y333850D01*
X289626Y333558D01*
Y332517D01*
G01Y333558D02*
X290834Y334183D01*
G01X290459Y335533D02*
X290667Y335783D01*
X290792Y336075D01*
X290834Y336450D01*
X290751Y336825D01*
X290584Y337117D01*
X290292Y337325D01*
X289959Y337367D01*
X289626Y337283D01*
X289417Y337075D01*
X289251Y336783D01*
X289209Y336492D01*
X289251Y336200D01*
X289417Y335825D01*
X288334Y335950D01*
Y337075D01*
G01X290834Y339467D02*
X290292Y339550D01*
X289834Y339675D01*
X289417Y339842D01*
X288959Y340050D01*
X288334Y340383D01*
Y338717D01*
G01X290334Y341733D02*
X290626Y341983D01*
X290792Y342317D01*
X290834Y342692D01*
X290792Y343025D01*
X290584Y343358D01*
X290334Y343567D01*
X290084Y343608D01*
X289792Y343525D01*
X289584Y343233D01*
X289501Y342942D01*
Y342567D01*
G01Y342942D02*
X289376Y343192D01*
X289167Y343400D01*
X288917Y343483D01*
X288667Y343400D01*
X288459Y343192D01*
X288334Y342817D01*
X288376Y342442D01*
X288542Y342067D01*
G01X283400Y315400D02*
X287400D01*
Y322800D01*
G01X275517Y334000D02*
Y336500D01*
X276558D01*
X276892Y336375D01*
X277100Y336208D01*
X277183Y335875D01*
X277100Y335542D01*
X276850Y335333D01*
X276558Y335208D01*
X275517D01*
G01X276558D02*
X277183Y334000D01*
G01X278533Y334375D02*
X278783Y334167D01*
X279075Y334042D01*
X279450Y334000D01*
X279825Y334083D01*
X280117Y334250D01*
X280325Y334542D01*
X280367Y334875D01*
X280283Y335208D01*
X280075Y335417D01*
X279783Y335583D01*
X279492Y335625D01*
X279200Y335583D01*
X278825Y335417D01*
X278950Y336500D01*
X280075D01*
G01X283050Y334000D02*
Y336500D01*
X281508Y334708D01*
X283592D01*
G01X285650Y334000D02*
Y336500D01*
X285150Y336000D01*
G01Y334000D02*
X286150D01*
G01X270834Y358517D02*
X268334D01*
Y359558D01*
X268459Y359892D01*
X268626Y360100D01*
X268959Y360183D01*
X269292Y360100D01*
X269501Y359850D01*
X269626Y359558D01*
Y358517D01*
G01Y359558D02*
X270834Y360183D01*
G01X270459Y361533D02*
X270667Y361783D01*
X270792Y362075D01*
X270834Y362450D01*
X270751Y362825D01*
X270584Y363117D01*
X270292Y363325D01*
X269959Y363367D01*
X269626Y363283D01*
X269417Y363075D01*
X269251Y362783D01*
X269209Y362492D01*
X269251Y362200D01*
X269417Y361825D01*
X268334Y361950D01*
Y363075D01*
G01Y365550D02*
X268417Y365217D01*
X268626Y364967D01*
X268876Y364800D01*
X269209Y364675D01*
X269584Y364633D01*
X269959Y364675D01*
X270292Y364800D01*
X270542Y364967D01*
X270751Y365217D01*
X270834Y365550D01*
X270751Y365883D01*
X270542Y366133D01*
X270292Y366300D01*
X269959Y366425D01*
X269584Y366467D01*
X269209Y366425D01*
X268876Y366300D01*
X268626Y366133D01*
X268417Y365883D01*
X268334Y365550D01*
G01X270834Y368650D02*
X270792Y368942D01*
X270667Y369275D01*
X270459Y369483D01*
X270167Y369567D01*
X269876Y369483D01*
X269626Y369233D01*
X269501Y368858D01*
Y368442D01*
X269417Y368192D01*
X269209Y367983D01*
X268917Y367900D01*
X268626Y368025D01*
X268417Y368317D01*
X268334Y368650D01*
X268417Y368983D01*
X268626Y369275D01*
X268917Y369400D01*
X269209Y369317D01*
X269417Y369108D01*
X269501Y368858D01*
Y368442D01*
X269626Y368067D01*
X269876Y367817D01*
X270167Y367733D01*
X270459Y367817D01*
X270667Y368025D01*
X270792Y368358D01*
X270834Y368650D01*
G01X275517Y342000D02*
Y344500D01*
X276558D01*
X276892Y344375D01*
X277100Y344208D01*
X277183Y343875D01*
X277100Y343542D01*
X276850Y343333D01*
X276558Y343208D01*
X275517D01*
G01X276558D02*
X277183Y342000D01*
G01X278533Y342375D02*
X278783Y342167D01*
X279075Y342042D01*
X279450Y342000D01*
X279825Y342083D01*
X280117Y342250D01*
X280325Y342542D01*
X280367Y342875D01*
X280283Y343208D01*
X280075Y343417D01*
X279783Y343583D01*
X279492Y343625D01*
X279200Y343583D01*
X278825Y343417D01*
X278950Y344500D01*
X280075D01*
G01X282550Y342000D02*
X282842Y342042D01*
X283175Y342167D01*
X283383Y342375D01*
X283467Y342667D01*
X283383Y342958D01*
X283133Y343208D01*
X282758Y343333D01*
X282342D01*
X282092Y343417D01*
X281883Y343625D01*
X281800Y343917D01*
X281925Y344208D01*
X282217Y344417D01*
X282550Y344500D01*
X282883Y344417D01*
X283175Y344208D01*
X283300Y343917D01*
X283217Y343625D01*
X283008Y343417D01*
X282758Y343333D01*
X282342D01*
X281967Y343208D01*
X281717Y342958D01*
X281633Y342667D01*
X281717Y342375D01*
X281925Y342167D01*
X282258Y342042D01*
X282550Y342000D01*
G01X286150D02*
Y344500D01*
X284608Y342708D01*
X286692D01*
G01X282700Y319600D02*
Y323600D01*
X275300D01*
G01X293017Y331000D02*
Y333500D01*
X294058D01*
X294392Y333375D01*
X294600Y333208D01*
X294683Y332875D01*
X294600Y332542D01*
X294350Y332333D01*
X294058Y332208D01*
X293017D01*
G01X294058D02*
X294683Y331000D01*
G01X296033Y331375D02*
X296283Y331167D01*
X296575Y331042D01*
X296950Y331000D01*
X297325Y331083D01*
X297617Y331250D01*
X297825Y331542D01*
X297867Y331875D01*
X297783Y332208D01*
X297575Y332417D01*
X297283Y332583D01*
X296992Y332625D01*
X296700Y332583D01*
X296325Y332417D01*
X296450Y333500D01*
X297575D01*
G01X300050Y331000D02*
X300342Y331042D01*
X300675Y331167D01*
X300883Y331375D01*
X300967Y331667D01*
X300883Y331958D01*
X300633Y332208D01*
X300258Y332333D01*
X299842D01*
X299592Y332417D01*
X299383Y332625D01*
X299300Y332917D01*
X299425Y333208D01*
X299717Y333417D01*
X300050Y333500D01*
X300383Y333417D01*
X300675Y333208D01*
X300800Y332917D01*
X300717Y332625D01*
X300508Y332417D01*
X300258Y332333D01*
X299842D01*
X299467Y332208D01*
X299217Y331958D01*
X299133Y331667D01*
X299217Y331375D01*
X299425Y331167D01*
X299758Y331042D01*
X300050Y331000D01*
G01X302233Y331500D02*
X302483Y331208D01*
X302817Y331042D01*
X303192Y331000D01*
X303525Y331042D01*
X303858Y331250D01*
X304067Y331500D01*
X304108Y331750D01*
X304025Y332042D01*
X303733Y332250D01*
X303442Y332333D01*
X303067D01*
G01X303442D02*
X303692Y332458D01*
X303900Y332667D01*
X303983Y332917D01*
X303900Y333167D01*
X303692Y333375D01*
X303317Y333500D01*
X302942Y333458D01*
X302567Y333292D01*
G01X289500Y323700D02*
Y319700D01*
X296900D01*
G01X294767Y337292D02*
X294517Y337417D01*
X294225Y337500D01*
X293892D01*
X293517Y337375D01*
X293225Y337167D01*
X293017Y336917D01*
X292850Y336500D01*
X292808Y336125D01*
X292892Y335750D01*
X293017Y335500D01*
X293267Y335250D01*
X293558Y335083D01*
X293850Y335000D01*
X294142D01*
X294433Y335083D01*
X294683Y335208D01*
X294892Y335375D01*
G01X296033D02*
X296283Y335167D01*
X296575Y335042D01*
X296950Y335000D01*
X297325Y335083D01*
X297617Y335250D01*
X297825Y335542D01*
X297867Y335875D01*
X297783Y336208D01*
X297575Y336417D01*
X297283Y336583D01*
X296992Y336625D01*
X296700Y336583D01*
X296325Y336417D01*
X296450Y337500D01*
X297575D01*
G01X299342Y335292D02*
X299633Y335083D01*
X299967Y335000D01*
X300300Y335083D01*
X300592Y335333D01*
X300800Y335708D01*
X300883Y336083D01*
Y336542D01*
X300800Y336917D01*
X300592Y337250D01*
X300342Y337417D01*
X300050Y337500D01*
X299717Y337417D01*
X299467Y337250D01*
X299300Y337000D01*
X299217Y336667D01*
X299300Y336375D01*
X299508Y336083D01*
X299758Y335917D01*
X300050Y335875D01*
X300383Y335958D01*
X300633Y336167D01*
X300883Y336542D01*
G01X303150Y335000D02*
X303442Y335042D01*
X303775Y335167D01*
X303983Y335375D01*
X304067Y335667D01*
X303983Y335958D01*
X303733Y336208D01*
X303358Y336333D01*
X302942D01*
X302692Y336417D01*
X302483Y336625D01*
X302400Y336917D01*
X302525Y337208D01*
X302817Y337417D01*
X303150Y337500D01*
X303483Y337417D01*
X303775Y337208D01*
X303900Y336917D01*
X303817Y336625D01*
X303608Y336417D01*
X303358Y336333D01*
X302942D01*
X302567Y336208D01*
X302317Y335958D01*
X302233Y335667D01*
X302317Y335375D01*
X302525Y335167D01*
X302858Y335042D01*
X303150Y335000D01*
G01X277267Y348292D02*
X277017Y348417D01*
X276725Y348500D01*
X276392D01*
X276017Y348375D01*
X275725Y348167D01*
X275517Y347917D01*
X275350Y347500D01*
X275308Y347125D01*
X275392Y346750D01*
X275517Y346500D01*
X275767Y346250D01*
X276058Y346083D01*
X276350Y346000D01*
X276642D01*
X276933Y346083D01*
X277183Y346208D01*
X277392Y346375D01*
G01X278533D02*
X278783Y346167D01*
X279075Y346042D01*
X279450Y346000D01*
X279825Y346083D01*
X280117Y346250D01*
X280325Y346542D01*
X280367Y346875D01*
X280283Y347208D01*
X280075Y347417D01*
X279783Y347583D01*
X279492Y347625D01*
X279200Y347583D01*
X278825Y347417D01*
X278950Y348500D01*
X280075D01*
G01X281842Y346292D02*
X282133Y346083D01*
X282467Y346000D01*
X282800Y346083D01*
X283092Y346333D01*
X283300Y346708D01*
X283383Y347083D01*
Y347542D01*
X283300Y347917D01*
X283092Y348250D01*
X282842Y348417D01*
X282550Y348500D01*
X282217Y348417D01*
X281967Y348250D01*
X281800Y348000D01*
X281717Y347667D01*
X281800Y347375D01*
X282008Y347083D01*
X282258Y346917D01*
X282550Y346875D01*
X282883Y346958D01*
X283133Y347167D01*
X283383Y347542D01*
G01X284942Y346292D02*
X285233Y346083D01*
X285567Y346000D01*
X285900Y346083D01*
X286192Y346333D01*
X286400Y346708D01*
X286483Y347083D01*
Y347542D01*
X286400Y347917D01*
X286192Y348250D01*
X285942Y348417D01*
X285650Y348500D01*
X285317Y348417D01*
X285067Y348250D01*
X284900Y348000D01*
X284817Y347667D01*
X284900Y347375D01*
X285108Y347083D01*
X285358Y346917D01*
X285650Y346875D01*
X285983Y346958D01*
X286233Y347167D01*
X286483Y347542D01*
G01X316633Y307500D02*
X316800Y307625D01*
X316925Y307834D01*
X317008Y308125D01*
X316925Y308375D01*
X316758Y308542D01*
X316467Y308667D01*
X315342D01*
Y306167D01*
X316717D01*
X317008Y306334D01*
X317175Y306584D01*
X317258Y306875D01*
X317175Y307167D01*
X316925Y307417D01*
X316633Y307500D01*
X315342D01*
G01X318567Y308667D02*
Y306167D01*
X320233D01*
G01X323333D02*
X321667D01*
Y308667D01*
X323333D01*
G01X322667Y307459D02*
X321667D01*
G01X324683Y306167D02*
Y308667D01*
X325517D01*
X325850Y308542D01*
X326100Y308375D01*
X326308Y308125D01*
X326475Y307834D01*
X326517Y307417D01*
X326475Y307000D01*
X326308Y306709D01*
X326100Y306459D01*
X325850Y306292D01*
X325517Y306167D01*
X324683D01*
G01X328700D02*
Y308667D01*
X328200Y308167D01*
G01Y306167D02*
X329200D01*
G01X263483Y328500D02*
Y326708D01*
X263650Y326333D01*
X263983Y326083D01*
X264400Y326000D01*
X264817Y326083D01*
X265150Y326333D01*
X265317Y326708D01*
Y328500D01*
G01X266583Y326500D02*
X266833Y326208D01*
X267167Y326042D01*
X267542Y326000D01*
X267875Y326042D01*
X268208Y326250D01*
X268417Y326500D01*
X268458Y326750D01*
X268375Y327042D01*
X268083Y327250D01*
X267792Y327333D01*
X267417D01*
G01X267792D02*
X268042Y327458D01*
X268250Y327667D01*
X268333Y327917D01*
X268250Y328167D01*
X268042Y328375D01*
X267667Y328500D01*
X267292Y328458D01*
X266917Y328292D01*
G01X269892Y326292D02*
X270183Y326083D01*
X270517Y326000D01*
X270850Y326083D01*
X271142Y326333D01*
X271350Y326708D01*
X271433Y327083D01*
Y327542D01*
X271350Y327917D01*
X271142Y328250D01*
X270892Y328417D01*
X270600Y328500D01*
X270267Y328417D01*
X270017Y328250D01*
X269850Y328000D01*
X269767Y327667D01*
X269850Y327375D01*
X270058Y327083D01*
X270308Y326917D01*
X270600Y326875D01*
X270933Y326958D01*
X271183Y327167D01*
X271433Y327542D01*
G01X264597Y307656D02*
X274797D01*
G01X264597Y303056D02*
Y307656D01*
G01X275497Y303056D02*
X264597D01*
G01X275497D02*
Y314356D01*
G01X274297Y305356D02*
X275497Y304156D01*
G01X274297Y305356D02*
X275497Y306556D01*
G01X281885Y377200D02*
Y379700D01*
X282926D01*
X283260Y379575D01*
X283468Y379408D01*
X283551Y379075D01*
X283468Y378742D01*
X283218Y378533D01*
X282926Y378408D01*
X281885D01*
G01X282926D02*
X283551Y377200D01*
G01X284901Y377575D02*
X285151Y377367D01*
X285443Y377242D01*
X285818Y377200D01*
X286193Y377283D01*
X286485Y377450D01*
X286693Y377742D01*
X286735Y378075D01*
X286651Y378408D01*
X286443Y378617D01*
X286151Y378783D01*
X285860Y378825D01*
X285568Y378783D01*
X285193Y378617D01*
X285318Y379700D01*
X286443D01*
G01X288918D02*
X288585Y379617D01*
X288335Y379408D01*
X288168Y379158D01*
X288043Y378825D01*
X288001Y378450D01*
X288043Y378075D01*
X288168Y377742D01*
X288335Y377492D01*
X288585Y377283D01*
X288918Y377200D01*
X289251Y377283D01*
X289501Y377492D01*
X289668Y377742D01*
X289793Y378075D01*
X289835Y378450D01*
X289793Y378825D01*
X289668Y379158D01*
X289501Y379408D01*
X289251Y379617D01*
X288918Y379700D01*
G01X292518Y377200D02*
Y379700D01*
X290976Y377908D01*
X293060D01*
G01X276068Y376200D02*
Y380200D01*
X268668D01*
G01X297834Y401517D02*
X295334D01*
Y402558D01*
X295459Y402892D01*
X295626Y403100D01*
X295959Y403183D01*
X296292Y403100D01*
X296501Y402850D01*
X296626Y402558D01*
Y401517D01*
G01Y402558D02*
X297834Y403183D01*
G01X297459Y404533D02*
X297667Y404783D01*
X297792Y405075D01*
X297834Y405450D01*
X297751Y405825D01*
X297584Y406117D01*
X297292Y406325D01*
X296959Y406367D01*
X296626Y406283D01*
X296417Y406075D01*
X296251Y405783D01*
X296209Y405492D01*
X296251Y405200D01*
X296417Y404825D01*
X295334Y404950D01*
Y406075D01*
G01X297834Y408550D02*
X295334D01*
X295834Y408050D01*
G01X297834D02*
Y409050D01*
G01X297334Y410733D02*
X297626Y410983D01*
X297792Y411317D01*
X297834Y411692D01*
X297792Y412025D01*
X297584Y412358D01*
X297334Y412567D01*
X297084Y412608D01*
X296792Y412525D01*
X296584Y412233D01*
X296501Y411942D01*
Y411567D01*
G01Y411942D02*
X296376Y412192D01*
X296167Y412400D01*
X295917Y412483D01*
X295667Y412400D01*
X295459Y412192D01*
X295334Y411817D01*
X295376Y411442D01*
X295542Y411067D01*
G01X281000Y403800D02*
X285000D01*
Y411200D01*
G01X267250Y376150D02*
X263250D01*
Y368750D01*
G01X281885Y381700D02*
Y384200D01*
X282926D01*
X283260Y384075D01*
X283468Y383908D01*
X283551Y383575D01*
X283468Y383242D01*
X283218Y383033D01*
X282926Y382908D01*
X281885D01*
G01X282926D02*
X283551Y381700D01*
G01X284901Y382075D02*
X285151Y381867D01*
X285443Y381742D01*
X285818Y381700D01*
X286193Y381783D01*
X286485Y381950D01*
X286693Y382242D01*
X286735Y382575D01*
X286651Y382908D01*
X286443Y383117D01*
X286151Y383283D01*
X285860Y383325D01*
X285568Y383283D01*
X285193Y383117D01*
X285318Y384200D01*
X286443D01*
G01X288918D02*
X288585Y384117D01*
X288335Y383908D01*
X288168Y383658D01*
X288043Y383325D01*
X288001Y382950D01*
X288043Y382575D01*
X288168Y382242D01*
X288335Y381992D01*
X288585Y381783D01*
X288918Y381700D01*
X289251Y381783D01*
X289501Y381992D01*
X289668Y382242D01*
X289793Y382575D01*
X289835Y382950D01*
X289793Y383325D01*
X289668Y383658D01*
X289501Y383908D01*
X289251Y384117D01*
X288918Y384200D01*
G01X291226Y383783D02*
X291476Y384033D01*
X291768Y384158D01*
X292101Y384200D01*
X292518Y384117D01*
X292810Y383908D01*
X292893Y383658D01*
X292851Y383408D01*
X292685Y383200D01*
X291851Y382783D01*
X291476Y382492D01*
X291226Y382075D01*
X291143Y381700D01*
X292893D01*
G01X276068Y380200D02*
Y384200D01*
X268668D01*
G01X324232Y399186D02*
Y401686D01*
X325273D01*
X325607Y401561D01*
X325815Y401394D01*
X325898Y401061D01*
X325815Y400728D01*
X325565Y400519D01*
X325273Y400394D01*
X324232D01*
G01X325273D02*
X325898Y399186D01*
G01X327248Y399561D02*
X327498Y399353D01*
X327790Y399228D01*
X328165Y399186D01*
X328540Y399269D01*
X328832Y399436D01*
X329040Y399728D01*
X329082Y400061D01*
X328998Y400394D01*
X328790Y400603D01*
X328498Y400769D01*
X328207Y400811D01*
X327915Y400769D01*
X327540Y400603D01*
X327665Y401686D01*
X328790D01*
G01X331765Y399186D02*
Y401686D01*
X330223Y399894D01*
X332307D01*
G01X333448Y399561D02*
X333698Y399353D01*
X333990Y399228D01*
X334365Y399186D01*
X334740Y399269D01*
X335032Y399436D01*
X335240Y399728D01*
X335282Y400061D01*
X335198Y400394D01*
X334990Y400603D01*
X334698Y400769D01*
X334407Y400811D01*
X334115Y400769D01*
X333740Y400603D01*
X333865Y401686D01*
X334990D01*
G01X332038Y403044D02*
Y407044D01*
X324638D01*
G01X283517Y373000D02*
Y375500D01*
X284558D01*
X284892Y375375D01*
X285100Y375208D01*
X285183Y374875D01*
X285100Y374542D01*
X284850Y374333D01*
X284558Y374208D01*
X283517D01*
G01X284558D02*
X285183Y373000D01*
G01X286533Y373375D02*
X286783Y373167D01*
X287075Y373042D01*
X287450Y373000D01*
X287825Y373083D01*
X288117Y373250D01*
X288325Y373542D01*
X288367Y373875D01*
X288283Y374208D01*
X288075Y374417D01*
X287783Y374583D01*
X287492Y374625D01*
X287200Y374583D01*
X286825Y374417D01*
X286950Y375500D01*
X288075D01*
G01X290550D02*
X290217Y375417D01*
X289967Y375208D01*
X289800Y374958D01*
X289675Y374625D01*
X289633Y374250D01*
X289675Y373875D01*
X289800Y373542D01*
X289967Y373292D01*
X290217Y373083D01*
X290550Y373000D01*
X290883Y373083D01*
X291133Y373292D01*
X291300Y373542D01*
X291425Y373875D01*
X291467Y374250D01*
X291425Y374625D01*
X291300Y374958D01*
X291133Y375208D01*
X290883Y375417D01*
X290550Y375500D01*
G01X292733Y373375D02*
X292983Y373167D01*
X293275Y373042D01*
X293650Y373000D01*
X294025Y373083D01*
X294317Y373250D01*
X294525Y373542D01*
X294567Y373875D01*
X294483Y374208D01*
X294275Y374417D01*
X293983Y374583D01*
X293692Y374625D01*
X293400Y374583D01*
X293025Y374417D01*
X293150Y375500D01*
X294275D01*
G01X280169Y371425D02*
Y375425D01*
X272769D01*
G01X275334Y417567D02*
X272834D01*
Y418608D01*
X272959Y418942D01*
X273126Y419150D01*
X273459Y419233D01*
X273792Y419150D01*
X274001Y418900D01*
X274126Y418608D01*
Y417567D01*
G01Y418608D02*
X275334Y419233D01*
G01Y421500D02*
X275292Y421792D01*
X275167Y422125D01*
X274959Y422333D01*
X274667Y422417D01*
X274376Y422333D01*
X274126Y422083D01*
X274001Y421708D01*
Y421292D01*
X273917Y421042D01*
X273709Y420833D01*
X273417Y420750D01*
X273126Y420875D01*
X272917Y421167D01*
X272834Y421500D01*
X272917Y421833D01*
X273126Y422125D01*
X273417Y422250D01*
X273709Y422167D01*
X273917Y421958D01*
X274001Y421708D01*
Y421292D01*
X274126Y420917D01*
X274376Y420667D01*
X274667Y420583D01*
X274959Y420667D01*
X275167Y420875D01*
X275292Y421208D01*
X275334Y421500D01*
G01Y424600D02*
X275292Y424892D01*
X275167Y425225D01*
X274959Y425433D01*
X274667Y425517D01*
X274376Y425433D01*
X274126Y425183D01*
X274001Y424808D01*
Y424392D01*
X273917Y424142D01*
X273709Y423933D01*
X273417Y423850D01*
X273126Y423975D01*
X272917Y424267D01*
X272834Y424600D01*
X272917Y424933D01*
X273126Y425225D01*
X273417Y425350D01*
X273709Y425267D01*
X273917Y425058D01*
X274001Y424808D01*
Y424392D01*
X274126Y424017D01*
X274376Y423767D01*
X274667Y423683D01*
X274959Y423767D01*
X275167Y423975D01*
X275292Y424308D01*
X275334Y424600D01*
G01X267500Y414800D02*
X271500D01*
Y422200D01*
G01X285834Y391017D02*
X283334D01*
Y392058D01*
X283459Y392392D01*
X283626Y392600D01*
X283959Y392683D01*
X284292Y392600D01*
X284501Y392350D01*
X284626Y392058D01*
Y391017D01*
G01Y392058D02*
X285834Y392683D01*
G01X285459Y394033D02*
X285667Y394283D01*
X285792Y394575D01*
X285834Y394950D01*
X285751Y395325D01*
X285584Y395617D01*
X285292Y395825D01*
X284959Y395867D01*
X284626Y395783D01*
X284417Y395575D01*
X284251Y395283D01*
X284209Y394992D01*
X284251Y394700D01*
X284417Y394325D01*
X283334Y394450D01*
Y395575D01*
G01X285834Y398050D02*
X283334D01*
X283834Y397550D01*
G01X285834D02*
Y398550D01*
G01Y401150D02*
X285792Y401442D01*
X285667Y401775D01*
X285459Y401983D01*
X285167Y402067D01*
X284876Y401983D01*
X284626Y401733D01*
X284501Y401358D01*
Y400942D01*
X284417Y400692D01*
X284209Y400483D01*
X283917Y400400D01*
X283626Y400525D01*
X283417Y400817D01*
X283334Y401150D01*
X283417Y401483D01*
X283626Y401775D01*
X283917Y401900D01*
X284209Y401817D01*
X284417Y401608D01*
X284501Y401358D01*
Y400942D01*
X284626Y400567D01*
X284876Y400317D01*
X285167Y400233D01*
X285459Y400317D01*
X285667Y400525D01*
X285792Y400858D01*
X285834Y401150D01*
G01X281000Y403700D02*
X277000D01*
Y396300D01*
G01X317886Y407844D02*
X315386D01*
Y408885D01*
X315511Y409219D01*
X315678Y409427D01*
X316011Y409510D01*
X316344Y409427D01*
X316553Y409177D01*
X316678Y408885D01*
Y407844D01*
G01Y408885D02*
X317886Y409510D01*
G01X317511Y410860D02*
X317719Y411110D01*
X317844Y411402D01*
X317886Y411777D01*
X317803Y412152D01*
X317636Y412444D01*
X317344Y412652D01*
X317011Y412694D01*
X316678Y412610D01*
X316469Y412402D01*
X316303Y412110D01*
X316261Y411819D01*
X316303Y411527D01*
X316469Y411152D01*
X315386Y411277D01*
Y412402D01*
G01X317511Y413960D02*
X317719Y414210D01*
X317844Y414502D01*
X317886Y414877D01*
X317803Y415252D01*
X317636Y415544D01*
X317344Y415752D01*
X317011Y415794D01*
X316678Y415710D01*
X316469Y415502D01*
X316303Y415210D01*
X316261Y414919D01*
X316303Y414627D01*
X316469Y414252D01*
X315386Y414377D01*
Y415502D01*
G01X317386Y417060D02*
X317678Y417310D01*
X317844Y417644D01*
X317886Y418019D01*
X317844Y418352D01*
X317636Y418685D01*
X317386Y418894D01*
X317136Y418935D01*
X316844Y418852D01*
X316636Y418560D01*
X316553Y418269D01*
Y417894D01*
G01Y418269D02*
X316428Y418519D01*
X316219Y418727D01*
X315969Y418810D01*
X315719Y418727D01*
X315511Y418519D01*
X315386Y418144D01*
X315428Y417769D01*
X315594Y417394D01*
G01X324083Y407166D02*
X328083D01*
Y414566D01*
G01X321886Y407844D02*
X319386D01*
Y408885D01*
X319511Y409219D01*
X319678Y409427D01*
X320011Y409510D01*
X320344Y409427D01*
X320553Y409177D01*
X320678Y408885D01*
Y407844D01*
G01Y408885D02*
X321886Y409510D01*
G01X321511Y410860D02*
X321719Y411110D01*
X321844Y411402D01*
X321886Y411777D01*
X321803Y412152D01*
X321636Y412444D01*
X321344Y412652D01*
X321011Y412694D01*
X320678Y412610D01*
X320469Y412402D01*
X320303Y412110D01*
X320261Y411819D01*
X320303Y411527D01*
X320469Y411152D01*
X319386Y411277D01*
Y412402D01*
G01X321511Y413960D02*
X321719Y414210D01*
X321844Y414502D01*
X321886Y414877D01*
X321803Y415252D01*
X321636Y415544D01*
X321344Y415752D01*
X321011Y415794D01*
X320678Y415710D01*
X320469Y415502D01*
X320303Y415210D01*
X320261Y414919D01*
X320303Y414627D01*
X320469Y414252D01*
X319386Y414377D01*
Y415502D01*
G01X319803Y417185D02*
X319553Y417435D01*
X319428Y417727D01*
X319386Y418060D01*
X319469Y418477D01*
X319678Y418769D01*
X319928Y418852D01*
X320178Y418810D01*
X320386Y418644D01*
X320803Y417810D01*
X321094Y417435D01*
X321511Y417185D01*
X321886Y417102D01*
Y418852D01*
G01X291542Y403267D02*
X291417Y403017D01*
X291334Y402725D01*
Y402392D01*
X291459Y402017D01*
X291667Y401725D01*
X291917Y401517D01*
X292334Y401350D01*
X292709Y401308D01*
X293084Y401392D01*
X293334Y401517D01*
X293584Y401767D01*
X293751Y402058D01*
X293834Y402350D01*
Y402642D01*
X293751Y402933D01*
X293626Y403183D01*
X293459Y403392D01*
G01X292792Y404658D02*
X292501Y404950D01*
X292334Y405200D01*
X292251Y405533D01*
X292334Y405825D01*
X292501Y406033D01*
X292751Y406200D01*
X293042Y406242D01*
X293292Y406200D01*
X293542Y406033D01*
X293751Y405783D01*
X293834Y405492D01*
X293751Y405158D01*
X293501Y404867D01*
X293126Y404700D01*
X292709Y404658D01*
X292167Y404742D01*
X291876Y404867D01*
X291584Y405075D01*
X291376Y405367D01*
X291334Y405658D01*
X291417Y405950D01*
X291626Y406158D01*
G01X293834Y409050D02*
X291334D01*
X293126Y407508D01*
Y409592D01*
G01X291751Y410858D02*
X291501Y411108D01*
X291376Y411400D01*
X291334Y411733D01*
X291417Y412150D01*
X291626Y412442D01*
X291876Y412525D01*
X292126Y412483D01*
X292334Y412317D01*
X292751Y411483D01*
X293042Y411108D01*
X293459Y410858D01*
X293834Y410775D01*
Y412525D01*
G01X287542Y403267D02*
X287417Y403017D01*
X287334Y402725D01*
Y402392D01*
X287459Y402017D01*
X287667Y401725D01*
X287917Y401517D01*
X288334Y401350D01*
X288709Y401308D01*
X289084Y401392D01*
X289334Y401517D01*
X289584Y401767D01*
X289751Y402058D01*
X289834Y402350D01*
Y402642D01*
X289751Y402933D01*
X289626Y403183D01*
X289459Y403392D01*
G01X288792Y404658D02*
X288501Y404950D01*
X288334Y405200D01*
X288251Y405533D01*
X288334Y405825D01*
X288501Y406033D01*
X288751Y406200D01*
X289042Y406242D01*
X289292Y406200D01*
X289542Y406033D01*
X289751Y405783D01*
X289834Y405492D01*
X289751Y405158D01*
X289501Y404867D01*
X289126Y404700D01*
X288709Y404658D01*
X288167Y404742D01*
X287876Y404867D01*
X287584Y405075D01*
X287376Y405367D01*
X287334Y405658D01*
X287417Y405950D01*
X287626Y406158D01*
G01X289834Y409050D02*
X287334D01*
X289126Y407508D01*
Y409592D01*
G01X287334Y411650D02*
X287417Y411317D01*
X287626Y411067D01*
X287876Y410900D01*
X288209Y410775D01*
X288584Y410733D01*
X288959Y410775D01*
X289292Y410900D01*
X289542Y411067D01*
X289751Y411317D01*
X289834Y411650D01*
X289751Y411983D01*
X289542Y412233D01*
X289292Y412400D01*
X288959Y412525D01*
X288584Y412567D01*
X288209Y412525D01*
X287876Y412400D01*
X287626Y412233D01*
X287417Y411983D01*
X287334Y411650D01*
G01X269700Y389750D02*
X270533D01*
Y389000D01*
X270283Y388750D01*
X269992Y388583D01*
X269575Y388500D01*
X269158Y388583D01*
X268867Y388750D01*
X268617Y389000D01*
X268450Y389292D01*
X268367Y389625D01*
Y389917D01*
X268450Y390167D01*
X268617Y390458D01*
X268867Y390708D01*
X269117Y390875D01*
X269450Y391000D01*
X269742D01*
X270075Y390917D01*
X270325Y390750D01*
G01X271633Y389000D02*
X271883Y388708D01*
X272217Y388542D01*
X272592Y388500D01*
X272925Y388542D01*
X273258Y388750D01*
X273467Y389000D01*
X273508Y389250D01*
X273425Y389542D01*
X273133Y389750D01*
X272842Y389833D01*
X272467D01*
G01X272842D02*
X273092Y389958D01*
X273300Y390167D01*
X273383Y390417D01*
X273300Y390667D01*
X273092Y390875D01*
X272717Y391000D01*
X272342Y390958D01*
X271967Y390792D01*
G01X320334Y425483D02*
X322126D01*
X322501Y425650D01*
X322751Y425983D01*
X322834Y426400D01*
X322751Y426817D01*
X322501Y427150D01*
X322126Y427317D01*
X320334D01*
G01X322834Y430000D02*
X320334D01*
X322126Y428458D01*
Y430542D01*
G01X322834Y432600D02*
X322792Y432892D01*
X322667Y433225D01*
X322459Y433433D01*
X322167Y433517D01*
X321876Y433433D01*
X321626Y433183D01*
X321501Y432808D01*
Y432392D01*
X321417Y432142D01*
X321209Y431933D01*
X320917Y431850D01*
X320626Y431975D01*
X320417Y432267D01*
X320334Y432600D01*
X320417Y432933D01*
X320626Y433225D01*
X320917Y433350D01*
X321209Y433267D01*
X321417Y433058D01*
X321501Y432808D01*
Y432392D01*
X321626Y432017D01*
X321876Y431767D01*
X322167Y431683D01*
X322459Y431767D01*
X322667Y431975D01*
X322792Y432308D01*
X322834Y432600D01*
G01X324564Y451015D02*
Y453515D01*
X325605D01*
X325939Y453390D01*
X326147Y453223D01*
X326230Y452890D01*
X326147Y452557D01*
X325897Y452348D01*
X325605Y452223D01*
X324564D01*
G01X325605D02*
X326230Y451015D01*
G01X327580Y451390D02*
X327830Y451182D01*
X328122Y451057D01*
X328497Y451015D01*
X328872Y451098D01*
X329164Y451265D01*
X329372Y451557D01*
X329414Y451890D01*
X329330Y452223D01*
X329122Y452432D01*
X328830Y452598D01*
X328539Y452640D01*
X328247Y452598D01*
X327872Y452432D01*
X327997Y453515D01*
X329122D01*
G01X330680Y451390D02*
X330930Y451182D01*
X331222Y451057D01*
X331597Y451015D01*
X331972Y451098D01*
X332264Y451265D01*
X332472Y451557D01*
X332514Y451890D01*
X332430Y452223D01*
X332222Y452432D01*
X331930Y452598D01*
X331639Y452640D01*
X331347Y452598D01*
X330972Y452432D01*
X331097Y453515D01*
X332222D01*
G01X333780Y451390D02*
X334030Y451182D01*
X334322Y451057D01*
X334697Y451015D01*
X335072Y451098D01*
X335364Y451265D01*
X335572Y451557D01*
X335614Y451890D01*
X335530Y452223D01*
X335322Y452432D01*
X335030Y452598D01*
X334739Y452640D01*
X334447Y452598D01*
X334072Y452432D01*
X334197Y453515D01*
X335322D01*
G01X326314Y449307D02*
X326064Y449432D01*
X325772Y449515D01*
X325439D01*
X325064Y449390D01*
X324772Y449182D01*
X324564Y448932D01*
X324397Y448515D01*
X324355Y448140D01*
X324439Y447765D01*
X324564Y447515D01*
X324814Y447265D01*
X325105Y447098D01*
X325397Y447015D01*
X325689D01*
X325980Y447098D01*
X326230Y447223D01*
X326439Y447390D01*
G01X328414Y447015D02*
X328497Y447557D01*
X328622Y448015D01*
X328789Y448432D01*
X328997Y448890D01*
X329330Y449515D01*
X327664D01*
G01X332097Y447015D02*
Y449515D01*
X330555Y447723D01*
X332639D01*
G01X333905Y449098D02*
X334155Y449348D01*
X334447Y449473D01*
X334780Y449515D01*
X335197Y449432D01*
X335489Y449223D01*
X335572Y448973D01*
X335530Y448723D01*
X335364Y448515D01*
X334530Y448098D01*
X334155Y447807D01*
X333905Y447390D01*
X333822Y447015D01*
X335572D01*
G01X284334Y427517D02*
X281834D01*
Y428558D01*
X281959Y428892D01*
X282126Y429100D01*
X282459Y429183D01*
X282792Y429100D01*
X283001Y428850D01*
X283126Y428558D01*
Y427517D01*
G01Y428558D02*
X284334Y429183D01*
G01X283959Y430533D02*
X284167Y430783D01*
X284292Y431075D01*
X284334Y431450D01*
X284251Y431825D01*
X284084Y432117D01*
X283792Y432325D01*
X283459Y432367D01*
X283126Y432283D01*
X282917Y432075D01*
X282751Y431783D01*
X282709Y431492D01*
X282751Y431200D01*
X282917Y430825D01*
X281834Y430950D01*
Y432075D01*
G01X284334Y434550D02*
X281834D01*
X282334Y434050D01*
G01X284334D02*
Y435050D01*
G01X282251Y436858D02*
X282001Y437108D01*
X281876Y437400D01*
X281834Y437733D01*
X281917Y438150D01*
X282126Y438442D01*
X282376Y438525D01*
X282626Y438483D01*
X282834Y438317D01*
X283251Y437483D01*
X283542Y437108D01*
X283959Y436858D01*
X284334Y436775D01*
Y438525D01*
G01X369933Y-97872D02*
X370333Y-97472D01*
X370800Y-97272D01*
X371333Y-97205D01*
X372000Y-97338D01*
X372467Y-97672D01*
X372600Y-98072D01*
X372533Y-98472D01*
X372267Y-98805D01*
X370933Y-99472D01*
X370333Y-99938D01*
X369933Y-100605D01*
X369800Y-101205D01*
X372600D01*
G01X339705D02*
Y-97205D01*
X338905Y-98005D01*
G01Y-101205D02*
X340505D01*
G01X591883Y0D02*
Y63561D01*
X334883D01*
Y0D01*
X591883D01*
G01X357097Y204357D02*
X354597D01*
Y205398D01*
X354722Y205732D01*
X354889Y205940D01*
X355222Y206023D01*
X355555Y205940D01*
X355764Y205690D01*
X355889Y205398D01*
Y204357D01*
G01Y205398D02*
X357097Y206023D01*
G01Y208290D02*
X354597D01*
X355097Y207790D01*
G01X357097D02*
Y208790D01*
G01X355014Y210598D02*
X354764Y210848D01*
X354639Y211140D01*
X354597Y211473D01*
X354680Y211890D01*
X354889Y212182D01*
X355139Y212265D01*
X355389Y212223D01*
X355597Y212057D01*
X356014Y211223D01*
X356305Y210848D01*
X356722Y210598D01*
X357097Y210515D01*
Y212265D01*
G01Y214490D02*
X354597D01*
X355097Y213990D01*
G01X357097D02*
Y214990D01*
G01X350597Y215040D02*
X346597D01*
Y207640D01*
G01X348142Y198267D02*
X348017Y198017D01*
X347934Y197725D01*
Y197392D01*
X348059Y197017D01*
X348267Y196725D01*
X348517Y196517D01*
X348934Y196350D01*
X349309Y196308D01*
X349684Y196392D01*
X349934Y196517D01*
X350184Y196767D01*
X350351Y197058D01*
X350434Y197350D01*
Y197642D01*
X350351Y197933D01*
X350226Y198183D01*
X350059Y198392D01*
G01X350434Y200450D02*
X347934D01*
X348434Y199950D01*
G01X350434D02*
Y200950D01*
G01Y203550D02*
X347934D01*
X348434Y203050D01*
G01X350434D02*
Y204050D01*
G01Y206650D02*
X347934D01*
X348434Y206150D01*
G01X350434D02*
Y207150D01*
G01X354805Y218607D02*
X354680Y218357D01*
X354597Y218065D01*
Y217732D01*
X354722Y217357D01*
X354930Y217065D01*
X355180Y216857D01*
X355597Y216690D01*
X355972Y216648D01*
X356347Y216732D01*
X356597Y216857D01*
X356847Y217107D01*
X357014Y217398D01*
X357097Y217690D01*
Y217982D01*
X357014Y218273D01*
X356889Y218523D01*
X356722Y218732D01*
G01X357097Y220790D02*
X354597D01*
X355097Y220290D01*
G01X357097D02*
Y221290D01*
G01Y223890D02*
X354597D01*
X355097Y223390D01*
G01X357097D02*
Y224390D01*
G01X354597Y226990D02*
X354680Y226657D01*
X354889Y226407D01*
X355139Y226240D01*
X355472Y226115D01*
X355847Y226073D01*
X356222Y226115D01*
X356555Y226240D01*
X356805Y226407D01*
X357014Y226657D01*
X357097Y226990D01*
X357014Y227323D01*
X356805Y227573D01*
X356555Y227740D01*
X356222Y227865D01*
X355847Y227907D01*
X355472Y227865D01*
X355139Y227740D01*
X354889Y227573D01*
X354680Y227323D01*
X354597Y226990D01*
G01X326589Y185795D02*
X326464Y185545D01*
X326381Y185253D01*
Y184920D01*
X326506Y184545D01*
X326714Y184253D01*
X326964Y184045D01*
X327381Y183878D01*
X327756Y183836D01*
X328131Y183920D01*
X328381Y184045D01*
X328631Y184295D01*
X328798Y184586D01*
X328881Y184878D01*
Y185170D01*
X328798Y185461D01*
X328673Y185711D01*
X328506Y185920D01*
G01X326798Y187186D02*
X326548Y187436D01*
X326423Y187728D01*
X326381Y188061D01*
X326464Y188478D01*
X326673Y188770D01*
X326923Y188853D01*
X327173Y188811D01*
X327381Y188645D01*
X327798Y187811D01*
X328089Y187436D01*
X328506Y187186D01*
X328881Y187103D01*
Y188853D01*
G01Y190995D02*
X328339Y191078D01*
X327881Y191203D01*
X327464Y191370D01*
X327006Y191578D01*
X326381Y191911D01*
Y190245D01*
G01X328881Y194095D02*
X328339Y194178D01*
X327881Y194303D01*
X327464Y194470D01*
X327006Y194678D01*
X326381Y195011D01*
Y193345D01*
G01X389645Y198819D02*
G02I-1850J0D01*
G01Y208662D02*
G02I-1850J0D01*
G01X331089Y185595D02*
X330964Y185345D01*
X330881Y185053D01*
Y184720D01*
X331006Y184345D01*
X331214Y184053D01*
X331464Y183845D01*
X331881Y183678D01*
X332256Y183636D01*
X332631Y183720D01*
X332881Y183845D01*
X333131Y184095D01*
X333298Y184386D01*
X333381Y184678D01*
Y184970D01*
X333298Y185261D01*
X333173Y185511D01*
X333006Y185720D01*
G01X331298Y186986D02*
X331048Y187236D01*
X330923Y187528D01*
X330881Y187861D01*
X330964Y188278D01*
X331173Y188570D01*
X331423Y188653D01*
X331673Y188611D01*
X331881Y188445D01*
X332298Y187611D01*
X332589Y187236D01*
X333006Y186986D01*
X333381Y186903D01*
Y188653D01*
G01X333089Y190170D02*
X333298Y190461D01*
X333381Y190795D01*
X333298Y191128D01*
X333048Y191420D01*
X332673Y191628D01*
X332298Y191711D01*
X331839D01*
X331464Y191628D01*
X331131Y191420D01*
X330964Y191170D01*
X330881Y190878D01*
X330964Y190545D01*
X331131Y190295D01*
X331381Y190128D01*
X331714Y190045D01*
X332006Y190128D01*
X332298Y190336D01*
X332464Y190586D01*
X332506Y190878D01*
X332423Y191211D01*
X332214Y191461D01*
X331839Y191711D01*
G01X332339Y193186D02*
X332048Y193478D01*
X331881Y193728D01*
X331798Y194061D01*
X331881Y194353D01*
X332048Y194561D01*
X332298Y194728D01*
X332589Y194770D01*
X332839Y194728D01*
X333089Y194561D01*
X333298Y194311D01*
X333381Y194020D01*
X333298Y193686D01*
X333048Y193395D01*
X332673Y193228D01*
X332256Y193186D01*
X331714Y193270D01*
X331423Y193395D01*
X331131Y193603D01*
X330923Y193895D01*
X330881Y194186D01*
X330964Y194478D01*
X331173Y194686D01*
G01X336572Y224840D02*
X338322Y227340D01*
G01X336572D02*
X338322Y224840D01*
G01X340547D02*
Y227340D01*
X340047Y226840D01*
G01Y224840D02*
X341047D01*
G01X332529Y213112D02*
Y221912D01*
X344929D01*
Y213112D01*
X332529D01*
G01X355067Y287000D02*
Y289500D01*
X356108D01*
X356442Y289375D01*
X356650Y289208D01*
X356733Y288875D01*
X356650Y288542D01*
X356400Y288333D01*
X356108Y288208D01*
X355067D01*
G01X356108D02*
X356733Y287000D01*
G01X358083Y287500D02*
X358333Y287208D01*
X358667Y287042D01*
X359042Y287000D01*
X359375Y287042D01*
X359708Y287250D01*
X359917Y287500D01*
X359958Y287750D01*
X359875Y288042D01*
X359583Y288250D01*
X359292Y288333D01*
X358917D01*
G01X359292D02*
X359542Y288458D01*
X359750Y288667D01*
X359833Y288917D01*
X359750Y289167D01*
X359542Y289375D01*
X359167Y289500D01*
X358792Y289458D01*
X358417Y289292D01*
G01X362600Y287000D02*
Y289500D01*
X361058Y287708D01*
X363142D01*
G01X367100Y290000D02*
Y286000D01*
X374500D01*
G01X355017Y279000D02*
Y281500D01*
X356058D01*
X356392Y281375D01*
X356600Y281208D01*
X356683Y280875D01*
X356600Y280542D01*
X356350Y280333D01*
X356058Y280208D01*
X355017D01*
G01X356058D02*
X356683Y279000D01*
G01X358950D02*
Y281500D01*
X358450Y281000D01*
G01Y279000D02*
X359450D01*
G01X362550D02*
Y281500D01*
X361008Y279708D01*
X363092D01*
G01X365150Y279000D02*
X365442Y279042D01*
X365775Y279167D01*
X365983Y279375D01*
X366067Y279667D01*
X365983Y279958D01*
X365733Y280208D01*
X365358Y280333D01*
X364942D01*
X364692Y280417D01*
X364483Y280625D01*
X364400Y280917D01*
X364525Y281208D01*
X364817Y281417D01*
X365150Y281500D01*
X365483Y281417D01*
X365775Y281208D01*
X365900Y280917D01*
X365817Y280625D01*
X365608Y280417D01*
X365358Y280333D01*
X364942D01*
X364567Y280208D01*
X364317Y279958D01*
X364233Y279667D01*
X364317Y279375D01*
X364525Y279167D01*
X364858Y279042D01*
X365150Y279000D01*
G01X374700Y277500D02*
Y281500D01*
X367300D01*
G01X349017Y291667D02*
Y294167D01*
X350058D01*
X350392Y294042D01*
X350600Y293875D01*
X350683Y293542D01*
X350600Y293209D01*
X350350Y293000D01*
X350058Y292875D01*
X349017D01*
G01X350058D02*
X350683Y291667D01*
G01X352950D02*
Y294167D01*
X352450Y293667D01*
G01Y291667D02*
X353450D01*
G01X356050Y294167D02*
X355717Y294084D01*
X355467Y293875D01*
X355300Y293625D01*
X355175Y293292D01*
X355133Y292917D01*
X355175Y292542D01*
X355300Y292209D01*
X355467Y291959D01*
X355717Y291750D01*
X356050Y291667D01*
X356383Y291750D01*
X356633Y291959D01*
X356800Y292209D01*
X356925Y292542D01*
X356967Y292917D01*
X356925Y293292D01*
X356800Y293625D01*
X356633Y293875D01*
X356383Y294084D01*
X356050Y294167D01*
G01X358358Y292709D02*
X358650Y293000D01*
X358900Y293167D01*
X359233Y293250D01*
X359525Y293167D01*
X359733Y293000D01*
X359900Y292750D01*
X359942Y292459D01*
X359900Y292209D01*
X359733Y291959D01*
X359483Y291750D01*
X359192Y291667D01*
X358858Y291750D01*
X358567Y292000D01*
X358400Y292375D01*
X358358Y292792D01*
X358442Y293334D01*
X358567Y293625D01*
X358775Y293917D01*
X359067Y294125D01*
X359358Y294167D01*
X359650Y294084D01*
X359858Y293875D01*
G01X368200Y291000D02*
Y295000D01*
X360800D01*
G01X355017Y275000D02*
Y277500D01*
X356058D01*
X356392Y277375D01*
X356600Y277208D01*
X356683Y276875D01*
X356600Y276542D01*
X356350Y276333D01*
X356058Y276208D01*
X355017D01*
G01X356058D02*
X356683Y275000D01*
G01X358950D02*
Y277500D01*
X358450Y277000D01*
G01Y275000D02*
X359450D01*
G01X362050Y277500D02*
X361717Y277417D01*
X361467Y277208D01*
X361300Y276958D01*
X361175Y276625D01*
X361133Y276250D01*
X361175Y275875D01*
X361300Y275542D01*
X361467Y275292D01*
X361717Y275083D01*
X362050Y275000D01*
X362383Y275083D01*
X362633Y275292D01*
X362800Y275542D01*
X362925Y275875D01*
X362967Y276250D01*
X362925Y276625D01*
X362800Y276958D01*
X362633Y277208D01*
X362383Y277417D01*
X362050Y277500D01*
G01X365150Y275000D02*
X365442Y275042D01*
X365775Y275167D01*
X365983Y275375D01*
X366067Y275667D01*
X365983Y275958D01*
X365733Y276208D01*
X365358Y276333D01*
X364942D01*
X364692Y276417D01*
X364483Y276625D01*
X364400Y276917D01*
X364525Y277208D01*
X364817Y277417D01*
X365150Y277500D01*
X365483Y277417D01*
X365775Y277208D01*
X365900Y276917D01*
X365817Y276625D01*
X365608Y276417D01*
X365358Y276333D01*
X364942D01*
X364567Y276208D01*
X364317Y275958D01*
X364233Y275667D01*
X364317Y275375D01*
X364525Y275167D01*
X364858Y275042D01*
X365150Y275000D01*
G01X374700Y273500D02*
Y277500D01*
X367300D01*
G01X355017Y283000D02*
Y285500D01*
X356058D01*
X356392Y285375D01*
X356600Y285208D01*
X356683Y284875D01*
X356600Y284542D01*
X356350Y284333D01*
X356058Y284208D01*
X355017D01*
G01X356058D02*
X356683Y283000D01*
G01X358950D02*
Y285500D01*
X358450Y285000D01*
G01Y283000D02*
X359450D01*
G01X362050D02*
Y285500D01*
X361550Y285000D01*
G01Y283000D02*
X362550D01*
G01X364358Y285083D02*
X364608Y285333D01*
X364900Y285458D01*
X365233Y285500D01*
X365650Y285417D01*
X365942Y285208D01*
X366025Y284958D01*
X365983Y284708D01*
X365817Y284500D01*
X364983Y284083D01*
X364608Y283792D01*
X364358Y283375D01*
X364275Y283000D01*
X366025D01*
G01X374500Y281900D02*
Y285900D01*
X367100D01*
G01X349017Y296667D02*
Y299167D01*
X350058D01*
X350392Y299042D01*
X350600Y298875D01*
X350683Y298542D01*
X350600Y298209D01*
X350350Y298000D01*
X350058Y297875D01*
X349017D01*
G01X350058D02*
X350683Y296667D01*
G01X352950D02*
Y299167D01*
X352450Y298667D01*
G01Y296667D02*
X353450D01*
G01X355258Y298750D02*
X355508Y299000D01*
X355800Y299125D01*
X356133Y299167D01*
X356550Y299084D01*
X356842Y298875D01*
X356925Y298625D01*
X356883Y298375D01*
X356717Y298167D01*
X355883Y297750D01*
X355508Y297459D01*
X355258Y297042D01*
X355175Y296667D01*
X356925D01*
G01X358233Y297167D02*
X358483Y296875D01*
X358817Y296709D01*
X359192Y296667D01*
X359525Y296709D01*
X359858Y296917D01*
X360067Y297167D01*
X360108Y297417D01*
X360025Y297709D01*
X359733Y297917D01*
X359442Y298000D01*
X359067D01*
G01X359442D02*
X359692Y298125D01*
X359900Y298334D01*
X359983Y298584D01*
X359900Y298834D01*
X359692Y299042D01*
X359317Y299167D01*
X358942Y299125D01*
X358567Y298959D01*
G01X360800Y301200D02*
Y297200D01*
X368200D01*
G01X368800Y301200D02*
Y297200D01*
X376200D01*
G01X362334Y258017D02*
X359834D01*
Y259058D01*
X359959Y259392D01*
X360126Y259600D01*
X360459Y259683D01*
X360792Y259600D01*
X361001Y259350D01*
X361126Y259058D01*
Y258017D01*
G01Y259058D02*
X362334Y259683D01*
G01X361959Y261033D02*
X362167Y261283D01*
X362292Y261575D01*
X362334Y261950D01*
X362251Y262325D01*
X362084Y262617D01*
X361792Y262825D01*
X361459Y262867D01*
X361126Y262783D01*
X360917Y262575D01*
X360751Y262283D01*
X360709Y261992D01*
X360751Y261700D01*
X360917Y261325D01*
X359834Y261450D01*
Y262575D01*
G01X362334Y265050D02*
X362292Y265342D01*
X362167Y265675D01*
X361959Y265883D01*
X361667Y265967D01*
X361376Y265883D01*
X361126Y265633D01*
X361001Y265258D01*
Y264842D01*
X360917Y264592D01*
X360709Y264383D01*
X360417Y264300D01*
X360126Y264425D01*
X359917Y264717D01*
X359834Y265050D01*
X359917Y265383D01*
X360126Y265675D01*
X360417Y265800D01*
X360709Y265717D01*
X360917Y265508D01*
X361001Y265258D01*
Y264842D01*
X361126Y264467D01*
X361376Y264217D01*
X361667Y264133D01*
X361959Y264217D01*
X362167Y264425D01*
X362292Y264758D01*
X362334Y265050D01*
G01Y268150D02*
X359834D01*
X360334Y267650D01*
G01X362334D02*
Y268650D01*
G01X367387Y263409D02*
X363387D01*
Y256009D01*
G01X374834Y244017D02*
X372334D01*
Y245058D01*
X372459Y245392D01*
X372626Y245600D01*
X372959Y245683D01*
X373292Y245600D01*
X373501Y245350D01*
X373626Y245058D01*
Y244017D01*
G01Y245058D02*
X374834Y245683D01*
G01X374459Y247033D02*
X374667Y247283D01*
X374792Y247575D01*
X374834Y247950D01*
X374751Y248325D01*
X374584Y248617D01*
X374292Y248825D01*
X373959Y248867D01*
X373626Y248783D01*
X373417Y248575D01*
X373251Y248283D01*
X373209Y247992D01*
X373251Y247700D01*
X373417Y247325D01*
X372334Y247450D01*
Y248575D01*
G01X374459Y250133D02*
X374667Y250383D01*
X374792Y250675D01*
X374834Y251050D01*
X374751Y251425D01*
X374584Y251717D01*
X374292Y251925D01*
X373959Y251967D01*
X373626Y251883D01*
X373417Y251675D01*
X373251Y251383D01*
X373209Y251092D01*
X373251Y250800D01*
X373417Y250425D01*
X372334Y250550D01*
Y251675D01*
G01X373792Y253358D02*
X373501Y253650D01*
X373334Y253900D01*
X373251Y254233D01*
X373334Y254525D01*
X373501Y254733D01*
X373751Y254900D01*
X374042Y254942D01*
X374292Y254900D01*
X374542Y254733D01*
X374751Y254483D01*
X374834Y254192D01*
X374751Y253858D01*
X374501Y253567D01*
X374126Y253400D01*
X373709Y253358D01*
X373167Y253442D01*
X372876Y253567D01*
X372584Y253775D01*
X372376Y254067D01*
X372334Y254358D01*
X372417Y254650D01*
X372626Y254858D01*
G01X374119Y263280D02*
X370119D01*
Y255880D01*
G01X347000Y285450D02*
X346958Y285117D01*
X346792Y284825D01*
X346542Y284575D01*
X346250Y284408D01*
X345917Y284325D01*
X345583D01*
X345250Y284408D01*
X344958Y284575D01*
X344708Y284825D01*
X344542Y285117D01*
X344500Y285450D01*
X344542Y285783D01*
X344708Y286075D01*
X344958Y286325D01*
X345250Y286492D01*
X345583Y286575D01*
X345917D01*
X346250Y286492D01*
X346542Y286325D01*
X346792Y286075D01*
X346958Y285783D01*
X347000Y285450D01*
G01X346333Y285783D02*
X347000Y286283D01*
G01X344917Y287758D02*
X344667Y288008D01*
X344542Y288300D01*
X344500Y288633D01*
X344583Y289050D01*
X344792Y289342D01*
X345042Y289425D01*
X345292Y289383D01*
X345500Y289217D01*
X345917Y288383D01*
X346208Y288008D01*
X346625Y287758D01*
X347000Y287675D01*
Y289425D01*
G01X343500Y299480D02*
X329500D01*
G01X343500Y286480D02*
Y299480D01*
G01X329500Y286480D02*
X343500D01*
G01X329500Y299480D02*
Y286480D01*
G01X347300Y250167D02*
Y247667D01*
G01X346342Y250167D02*
X348258D01*
G01X349567Y247667D02*
Y250167D01*
X350567D01*
X350900Y250042D01*
X351150Y249750D01*
X351233Y249417D01*
X351150Y249084D01*
X350942Y248834D01*
X350567Y248709D01*
X349567D01*
G01X353500Y247667D02*
Y250167D01*
X353000Y249667D01*
G01Y247667D02*
X354000D01*
G01X355808Y248709D02*
X356100Y249000D01*
X356350Y249167D01*
X356683Y249250D01*
X356975Y249167D01*
X357183Y249000D01*
X357350Y248750D01*
X357392Y248459D01*
X357350Y248209D01*
X357183Y247959D01*
X356933Y247750D01*
X356642Y247667D01*
X356308Y247750D01*
X356017Y248000D01*
X355850Y248375D01*
X355808Y248792D01*
X355892Y249334D01*
X356017Y249625D01*
X356225Y249917D01*
X356517Y250125D01*
X356808Y250167D01*
X357100Y250084D01*
X357308Y249875D01*
G01X360200Y247667D02*
Y250167D01*
X358658Y248375D01*
X360742D01*
G01X347300Y254167D02*
Y251667D01*
G01X346342Y254167D02*
X348258D01*
G01X349567Y251667D02*
Y254167D01*
X350567D01*
X350900Y254042D01*
X351150Y253750D01*
X351233Y253417D01*
X351150Y253084D01*
X350942Y252834D01*
X350567Y252709D01*
X349567D01*
G01X353500Y251667D02*
Y254167D01*
X353000Y253667D01*
G01Y251667D02*
X354000D01*
G01X355808Y252709D02*
X356100Y253000D01*
X356350Y253167D01*
X356683Y253250D01*
X356975Y253167D01*
X357183Y253000D01*
X357350Y252750D01*
X357392Y252459D01*
X357350Y252209D01*
X357183Y251959D01*
X356933Y251750D01*
X356642Y251667D01*
X356308Y251750D01*
X356017Y252000D01*
X355850Y252375D01*
X355808Y252792D01*
X355892Y253334D01*
X356017Y253625D01*
X356225Y253917D01*
X356517Y254125D01*
X356808Y254167D01*
X357100Y254084D01*
X357308Y253875D01*
G01X358783Y252042D02*
X359033Y251834D01*
X359325Y251709D01*
X359700Y251667D01*
X360075Y251750D01*
X360367Y251917D01*
X360575Y252209D01*
X360617Y252542D01*
X360533Y252875D01*
X360325Y253084D01*
X360033Y253250D01*
X359742Y253292D01*
X359450Y253250D01*
X359075Y253084D01*
X359200Y254167D01*
X360325D01*
G01X329483Y285167D02*
Y283375D01*
X329650Y283000D01*
X329983Y282750D01*
X330400Y282667D01*
X330817Y282750D01*
X331150Y283000D01*
X331317Y283375D01*
Y285167D01*
G01X332708Y284750D02*
X332958Y285000D01*
X333250Y285125D01*
X333583Y285167D01*
X334000Y285084D01*
X334292Y284875D01*
X334375Y284625D01*
X334333Y284375D01*
X334167Y284167D01*
X333333Y283750D01*
X332958Y283459D01*
X332708Y283042D01*
X332625Y282667D01*
X334375D01*
G01X337100D02*
Y285167D01*
X335558Y283375D01*
X337642D01*
G01X333750Y280266D02*
X332300Y281716D01*
G01X335200D02*
X333750Y280266D01*
G01X339250Y281716D02*
X328250D01*
G01X339250Y261116D02*
Y281716D01*
G01X328250Y261116D02*
X339250D01*
G01X328250Y281716D02*
Y261116D01*
G01X367517Y350000D02*
Y352500D01*
X368558D01*
X368892Y352375D01*
X369100Y352208D01*
X369183Y351875D01*
X369100Y351542D01*
X368850Y351333D01*
X368558Y351208D01*
X367517D01*
G01X368558D02*
X369183Y350000D01*
G01X370533Y350375D02*
X370783Y350167D01*
X371075Y350042D01*
X371450Y350000D01*
X371825Y350083D01*
X372117Y350250D01*
X372325Y350542D01*
X372367Y350875D01*
X372283Y351208D01*
X372075Y351417D01*
X371783Y351583D01*
X371492Y351625D01*
X371200Y351583D01*
X370825Y351417D01*
X370950Y352500D01*
X372075D01*
G01X373758Y351042D02*
X374050Y351333D01*
X374300Y351500D01*
X374633Y351583D01*
X374925Y351500D01*
X375133Y351333D01*
X375300Y351083D01*
X375342Y350792D01*
X375300Y350542D01*
X375133Y350292D01*
X374883Y350083D01*
X374592Y350000D01*
X374258Y350083D01*
X373967Y350333D01*
X373800Y350708D01*
X373758Y351125D01*
X373842Y351667D01*
X373967Y351958D01*
X374175Y352250D01*
X374467Y352458D01*
X374758Y352500D01*
X375050Y352417D01*
X375258Y352208D01*
G01X377650Y350000D02*
Y352500D01*
X377150Y352000D01*
G01Y350000D02*
X378150D01*
G01X368800Y342500D02*
Y338500D01*
X376200D01*
G01X385500Y348267D02*
X383000D01*
Y349308D01*
X383125Y349642D01*
X383292Y349850D01*
X383625Y349933D01*
X383958Y349850D01*
X384167Y349600D01*
X384292Y349308D01*
Y348267D01*
G01Y349308D02*
X385500Y349933D01*
G01X385125Y351283D02*
X385333Y351533D01*
X385458Y351825D01*
X385500Y352200D01*
X385417Y352575D01*
X385250Y352867D01*
X384958Y353075D01*
X384625Y353117D01*
X384292Y353033D01*
X384083Y352825D01*
X383917Y352533D01*
X383875Y352242D01*
X383917Y351950D01*
X384083Y351575D01*
X383000Y351700D01*
Y352825D01*
G01X384458Y354508D02*
X384167Y354800D01*
X384000Y355050D01*
X383917Y355383D01*
X384000Y355675D01*
X384167Y355883D01*
X384417Y356050D01*
X384708Y356092D01*
X384958Y356050D01*
X385208Y355883D01*
X385417Y355633D01*
X385500Y355342D01*
X385417Y355008D01*
X385167Y354717D01*
X384792Y354550D01*
X384375Y354508D01*
X383833Y354592D01*
X383542Y354717D01*
X383250Y354925D01*
X383042Y355217D01*
X383000Y355508D01*
X383083Y355800D01*
X383292Y356008D01*
G01X383417Y357608D02*
X383167Y357858D01*
X383042Y358150D01*
X383000Y358483D01*
X383083Y358900D01*
X383292Y359192D01*
X383542Y359275D01*
X383792Y359233D01*
X384000Y359067D01*
X384417Y358233D01*
X384708Y357858D01*
X385125Y357608D01*
X385500Y357525D01*
Y359275D01*
G01X386000Y346450D02*
X382000D01*
Y339050D01*
G01X348017Y302167D02*
Y304667D01*
X349058D01*
X349392Y304542D01*
X349600Y304375D01*
X349683Y304042D01*
X349600Y303709D01*
X349350Y303500D01*
X349058Y303375D01*
X348017D01*
G01X349058D02*
X349683Y302167D01*
G01X352450D02*
Y304667D01*
X350908Y302875D01*
X352992D01*
G01X354258Y303209D02*
X354550Y303500D01*
X354800Y303667D01*
X355133Y303750D01*
X355425Y303667D01*
X355633Y303500D01*
X355800Y303250D01*
X355842Y302959D01*
X355800Y302709D01*
X355633Y302459D01*
X355383Y302250D01*
X355092Y302167D01*
X354758Y302250D01*
X354467Y302500D01*
X354300Y302875D01*
X354258Y303292D01*
X354342Y303834D01*
X354467Y304125D01*
X354675Y304417D01*
X354967Y304625D01*
X355258Y304667D01*
X355550Y304584D01*
X355758Y304375D01*
G01X358150Y302167D02*
Y304667D01*
X357650Y304167D01*
G01Y302167D02*
X358650D01*
G01X355200Y306000D02*
Y310000D01*
X347800D01*
G01X357017Y343667D02*
Y346167D01*
X358058D01*
X358392Y346042D01*
X358600Y345875D01*
X358683Y345542D01*
X358600Y345209D01*
X358350Y345000D01*
X358058Y344875D01*
X357017D01*
G01X358058D02*
X358683Y343667D01*
G01X360033Y344167D02*
X360283Y343875D01*
X360617Y343709D01*
X360992Y343667D01*
X361325Y343709D01*
X361658Y343917D01*
X361867Y344167D01*
X361908Y344417D01*
X361825Y344709D01*
X361533Y344917D01*
X361242Y345000D01*
X360867D01*
G01X361242D02*
X361492Y345125D01*
X361700Y345334D01*
X361783Y345584D01*
X361700Y345834D01*
X361492Y346042D01*
X361117Y346167D01*
X360742Y346125D01*
X360367Y345959D01*
G01X364050Y346167D02*
X363717Y346084D01*
X363467Y345875D01*
X363300Y345625D01*
X363175Y345292D01*
X363133Y344917D01*
X363175Y344542D01*
X363300Y344209D01*
X363467Y343959D01*
X363717Y343750D01*
X364050Y343667D01*
X364383Y343750D01*
X364633Y343959D01*
X364800Y344209D01*
X364925Y344542D01*
X364967Y344917D01*
X364925Y345292D01*
X364800Y345625D01*
X364633Y345875D01*
X364383Y346084D01*
X364050Y346167D01*
G01X366233Y344042D02*
X366483Y343834D01*
X366775Y343709D01*
X367150Y343667D01*
X367525Y343750D01*
X367817Y343917D01*
X368025Y344209D01*
X368067Y344542D01*
X367983Y344875D01*
X367775Y345084D01*
X367483Y345250D01*
X367192Y345292D01*
X366900Y345250D01*
X366525Y345084D01*
X366650Y346167D01*
X367775D01*
G01X363700Y338500D02*
Y342500D01*
X356300D01*
G01X367517Y354000D02*
Y356500D01*
X368558D01*
X368892Y356375D01*
X369100Y356208D01*
X369183Y355875D01*
X369100Y355542D01*
X368850Y355333D01*
X368558Y355208D01*
X367517D01*
G01X368558D02*
X369183Y354000D01*
G01X370533Y354500D02*
X370783Y354208D01*
X371117Y354042D01*
X371492Y354000D01*
X371825Y354042D01*
X372158Y354250D01*
X372367Y354500D01*
X372408Y354750D01*
X372325Y355042D01*
X372033Y355250D01*
X371742Y355333D01*
X371367D01*
G01X371742D02*
X371992Y355458D01*
X372200Y355667D01*
X372283Y355917D01*
X372200Y356167D01*
X371992Y356375D01*
X371617Y356500D01*
X371242Y356458D01*
X370867Y356292D01*
G01X374550Y356500D02*
X374217Y356417D01*
X373967Y356208D01*
X373800Y355958D01*
X373675Y355625D01*
X373633Y355250D01*
X373675Y354875D01*
X373800Y354542D01*
X373967Y354292D01*
X374217Y354083D01*
X374550Y354000D01*
X374883Y354083D01*
X375133Y354292D01*
X375300Y354542D01*
X375425Y354875D01*
X375467Y355250D01*
X375425Y355625D01*
X375300Y355958D01*
X375133Y356208D01*
X374883Y356417D01*
X374550Y356500D01*
G01X376858Y355042D02*
X377150Y355333D01*
X377400Y355500D01*
X377733Y355583D01*
X378025Y355500D01*
X378233Y355333D01*
X378400Y355083D01*
X378442Y354792D01*
X378400Y354542D01*
X378233Y354292D01*
X377983Y354083D01*
X377692Y354000D01*
X377358Y354083D01*
X377067Y354333D01*
X376900Y354708D01*
X376858Y355125D01*
X376942Y355667D01*
X377067Y355958D01*
X377275Y356250D01*
X377567Y356458D01*
X377858Y356500D01*
X378150Y356417D01*
X378358Y356208D01*
G01X376200Y342500D02*
Y346500D01*
X368800D01*
G01X339100Y300367D02*
X336600D01*
Y301408D01*
X336725Y301742D01*
X336892Y301950D01*
X337225Y302033D01*
X337558Y301950D01*
X337767Y301700D01*
X337892Y301408D01*
Y300367D01*
G01Y301408D02*
X339100Y302033D01*
G01X338808Y303592D02*
X339017Y303883D01*
X339100Y304217D01*
X339017Y304550D01*
X338767Y304842D01*
X338392Y305050D01*
X338017Y305133D01*
X337558D01*
X337183Y305050D01*
X336850Y304842D01*
X336683Y304592D01*
X336600Y304300D01*
X336683Y303967D01*
X336850Y303717D01*
X337100Y303550D01*
X337433Y303467D01*
X337725Y303550D01*
X338017Y303758D01*
X338183Y304008D01*
X338225Y304300D01*
X338142Y304633D01*
X337933Y304883D01*
X337558Y305133D01*
G01X339100Y307317D02*
X338558Y307400D01*
X338100Y307525D01*
X337683Y307692D01*
X337225Y307900D01*
X336600Y308233D01*
Y306567D01*
G01X341000Y300300D02*
X345000D01*
Y307700D01*
G01X360017Y306167D02*
Y308667D01*
X361058D01*
X361392Y308542D01*
X361600Y308375D01*
X361683Y308042D01*
X361600Y307709D01*
X361350Y307500D01*
X361058Y307375D01*
X360017D01*
G01X361058D02*
X361683Y306167D01*
G01X363950D02*
Y308667D01*
X363450Y308167D01*
G01Y306167D02*
X364450D01*
G01X366258Y308250D02*
X366508Y308500D01*
X366800Y308625D01*
X367133Y308667D01*
X367550Y308584D01*
X367842Y308375D01*
X367925Y308125D01*
X367883Y307875D01*
X367717Y307667D01*
X366883Y307250D01*
X366508Y306959D01*
X366258Y306542D01*
X366175Y306167D01*
X367925D01*
G01X369358Y308250D02*
X369608Y308500D01*
X369900Y308625D01*
X370233Y308667D01*
X370650Y308584D01*
X370942Y308375D01*
X371025Y308125D01*
X370983Y307875D01*
X370817Y307667D01*
X369983Y307250D01*
X369608Y306959D01*
X369358Y306542D01*
X369275Y306167D01*
X371025D01*
G01X360800Y305200D02*
Y301200D01*
X368200D01*
G01X372517Y309000D02*
Y311500D01*
X373558D01*
X373892Y311375D01*
X374100Y311208D01*
X374183Y310875D01*
X374100Y310542D01*
X373850Y310333D01*
X373558Y310208D01*
X372517D01*
G01X373558D02*
X374183Y309000D01*
G01X376450D02*
Y311500D01*
X375950Y311000D01*
G01Y309000D02*
X376950D01*
G01X378758Y311083D02*
X379008Y311333D01*
X379300Y311458D01*
X379633Y311500D01*
X380050Y311417D01*
X380342Y311208D01*
X380425Y310958D01*
X380383Y310708D01*
X380217Y310500D01*
X379383Y310083D01*
X379008Y309792D01*
X378758Y309375D01*
X378675Y309000D01*
X380425D01*
G01X383150D02*
Y311500D01*
X381608Y309708D01*
X383692D01*
G01X372517Y312700D02*
Y315200D01*
X373558D01*
X373892Y315075D01*
X374100Y314908D01*
X374183Y314575D01*
X374100Y314242D01*
X373850Y314033D01*
X373558Y313908D01*
X372517D01*
G01X373558D02*
X374183Y312700D01*
G01X376450D02*
Y315200D01*
X375950Y314700D01*
G01Y312700D02*
X376950D01*
G01X378758Y314783D02*
X379008Y315033D01*
X379300Y315158D01*
X379633Y315200D01*
X380050Y315117D01*
X380342Y314908D01*
X380425Y314658D01*
X380383Y314408D01*
X380217Y314200D01*
X379383Y313783D01*
X379008Y313492D01*
X378758Y313075D01*
X378675Y312700D01*
X380425D01*
G01X381733Y313075D02*
X381983Y312867D01*
X382275Y312742D01*
X382650Y312700D01*
X383025Y312783D01*
X383317Y312950D01*
X383525Y313242D01*
X383567Y313575D01*
X383483Y313908D01*
X383275Y314117D01*
X382983Y314283D01*
X382692Y314325D01*
X382400Y314283D01*
X382025Y314117D01*
X382150Y315200D01*
X383275D01*
G01X368800Y305200D02*
Y301200D01*
X376200D01*
G01X346000Y334517D02*
X343500D01*
Y335558D01*
X343625Y335892D01*
X343792Y336100D01*
X344125Y336183D01*
X344458Y336100D01*
X344667Y335850D01*
X344792Y335558D01*
Y334517D01*
G01Y335558D02*
X346000Y336183D01*
G01Y338450D02*
X343500D01*
X344000Y337950D01*
G01X346000D02*
Y338950D01*
G01X343917Y340758D02*
X343667Y341008D01*
X343542Y341300D01*
X343500Y341633D01*
X343583Y342050D01*
X343792Y342342D01*
X344042Y342425D01*
X344292Y342383D01*
X344500Y342217D01*
X344917Y341383D01*
X345208Y341008D01*
X345625Y340758D01*
X346000Y340675D01*
Y342425D01*
G01X345708Y343942D02*
X345917Y344233D01*
X346000Y344567D01*
X345917Y344900D01*
X345667Y345192D01*
X345292Y345400D01*
X344917Y345483D01*
X344458D01*
X344083Y345400D01*
X343750Y345192D01*
X343583Y344942D01*
X343500Y344650D01*
X343583Y344317D01*
X343750Y344067D01*
X344000Y343900D01*
X344333Y343817D01*
X344625Y343900D01*
X344917Y344108D01*
X345083Y344358D01*
X345125Y344650D01*
X345042Y344983D01*
X344833Y345233D01*
X344458Y345483D01*
G01X343121Y326050D02*
X347121D01*
Y333450D01*
G01X352517Y318000D02*
Y320500D01*
X353558D01*
X353892Y320375D01*
X354100Y320208D01*
X354183Y319875D01*
X354100Y319542D01*
X353850Y319333D01*
X353558Y319208D01*
X352517D01*
G01X353558D02*
X354183Y318000D01*
G01X356450D02*
Y320500D01*
X355950Y320000D01*
G01Y318000D02*
X356950D01*
G01X358633Y318500D02*
X358883Y318208D01*
X359217Y318042D01*
X359592Y318000D01*
X359925Y318042D01*
X360258Y318250D01*
X360467Y318500D01*
X360508Y318750D01*
X360425Y319042D01*
X360133Y319250D01*
X359842Y319333D01*
X359467D01*
G01X359842D02*
X360092Y319458D01*
X360300Y319667D01*
X360383Y319917D01*
X360300Y320167D01*
X360092Y320375D01*
X359717Y320500D01*
X359342Y320458D01*
X358967Y320292D01*
G01X362650Y320500D02*
X362317Y320417D01*
X362067Y320208D01*
X361900Y319958D01*
X361775Y319625D01*
X361733Y319250D01*
X361775Y318875D01*
X361900Y318542D01*
X362067Y318292D01*
X362317Y318083D01*
X362650Y318000D01*
X362983Y318083D01*
X363233Y318292D01*
X363400Y318542D01*
X363525Y318875D01*
X363567Y319250D01*
X363525Y319625D01*
X363400Y319958D01*
X363233Y320208D01*
X362983Y320417D01*
X362650Y320500D01*
G01X366727Y310654D02*
Y314654D01*
X359327D01*
G01X330517Y328000D02*
Y330500D01*
X331558D01*
X331892Y330375D01*
X332100Y330208D01*
X332183Y329875D01*
X332100Y329542D01*
X331850Y329333D01*
X331558Y329208D01*
X330517D01*
G01X331558D02*
X332183Y328000D01*
G01X334450D02*
Y330500D01*
X333950Y330000D01*
G01Y328000D02*
X334950D01*
G01X336633Y328500D02*
X336883Y328208D01*
X337217Y328042D01*
X337592Y328000D01*
X337925Y328042D01*
X338258Y328250D01*
X338467Y328500D01*
X338508Y328750D01*
X338425Y329042D01*
X338133Y329250D01*
X337842Y329333D01*
X337467D01*
G01X337842D02*
X338092Y329458D01*
X338300Y329667D01*
X338383Y329917D01*
X338300Y330167D01*
X338092Y330375D01*
X337717Y330500D01*
X337342Y330458D01*
X336967Y330292D01*
G01X339858Y330083D02*
X340108Y330333D01*
X340400Y330458D01*
X340733Y330500D01*
X341150Y330417D01*
X341442Y330208D01*
X341525Y329958D01*
X341483Y329708D01*
X341317Y329500D01*
X340483Y329083D01*
X340108Y328792D01*
X339858Y328375D01*
X339775Y328000D01*
X341525D01*
G01X339691Y321717D02*
Y317717D01*
X347091D01*
G01X379834Y318017D02*
X377334D01*
Y319058D01*
X377459Y319392D01*
X377626Y319600D01*
X377959Y319683D01*
X378292Y319600D01*
X378501Y319350D01*
X378626Y319058D01*
Y318017D01*
G01Y319058D02*
X379834Y319683D01*
G01Y321950D02*
X377334D01*
X377834Y321450D01*
G01X379834D02*
Y322450D01*
G01X379334Y324133D02*
X379626Y324383D01*
X379792Y324717D01*
X379834Y325092D01*
X379792Y325425D01*
X379584Y325758D01*
X379334Y325967D01*
X379084Y326008D01*
X378792Y325925D01*
X378584Y325633D01*
X378501Y325342D01*
Y324967D01*
G01Y325342D02*
X378376Y325592D01*
X378167Y325800D01*
X377917Y325883D01*
X377667Y325800D01*
X377459Y325592D01*
X377334Y325217D01*
X377376Y324842D01*
X377542Y324467D01*
G01X379334Y327233D02*
X379626Y327483D01*
X379792Y327817D01*
X379834Y328192D01*
X379792Y328525D01*
X379584Y328858D01*
X379334Y329067D01*
X379084Y329108D01*
X378792Y329025D01*
X378584Y328733D01*
X378501Y328442D01*
Y328067D01*
G01Y328442D02*
X378376Y328692D01*
X378167Y328900D01*
X377917Y328983D01*
X377667Y328900D01*
X377459Y328692D01*
X377334Y328317D01*
X377376Y327942D01*
X377542Y327567D01*
G01X368932Y318300D02*
X372932D01*
Y325700D01*
G01X368517Y332000D02*
Y334500D01*
X369558D01*
X369892Y334375D01*
X370100Y334208D01*
X370183Y333875D01*
X370100Y333542D01*
X369850Y333333D01*
X369558Y333208D01*
X368517D01*
G01X369558D02*
X370183Y332000D01*
G01X371533Y332500D02*
X371783Y332208D01*
X372117Y332042D01*
X372492Y332000D01*
X372825Y332042D01*
X373158Y332250D01*
X373367Y332500D01*
X373408Y332750D01*
X373325Y333042D01*
X373033Y333250D01*
X372742Y333333D01*
X372367D01*
G01X372742D02*
X372992Y333458D01*
X373200Y333667D01*
X373283Y333917D01*
X373200Y334167D01*
X372992Y334375D01*
X372617Y334500D01*
X372242Y334458D01*
X371867Y334292D01*
G01X375550Y334500D02*
X375217Y334417D01*
X374967Y334208D01*
X374800Y333958D01*
X374675Y333625D01*
X374633Y333250D01*
X374675Y332875D01*
X374800Y332542D01*
X374967Y332292D01*
X375217Y332083D01*
X375550Y332000D01*
X375883Y332083D01*
X376133Y332292D01*
X376300Y332542D01*
X376425Y332875D01*
X376467Y333250D01*
X376425Y333625D01*
X376300Y333958D01*
X376133Y334208D01*
X375883Y334417D01*
X375550Y334500D01*
G01X377942Y332292D02*
X378233Y332083D01*
X378567Y332000D01*
X378900Y332083D01*
X379192Y332333D01*
X379400Y332708D01*
X379483Y333083D01*
Y333542D01*
X379400Y333917D01*
X379192Y334250D01*
X378942Y334417D01*
X378650Y334500D01*
X378317Y334417D01*
X378067Y334250D01*
X377900Y334000D01*
X377817Y333667D01*
X377900Y333375D01*
X378108Y333083D01*
X378358Y332917D01*
X378650Y332875D01*
X378983Y332958D01*
X379233Y333167D01*
X379483Y333542D01*
G01X376382Y326503D02*
Y330503D01*
X368982D01*
G01X332017Y312667D02*
Y315167D01*
X333058D01*
X333392Y315042D01*
X333600Y314875D01*
X333683Y314542D01*
X333600Y314209D01*
X333350Y314000D01*
X333058Y313875D01*
X332017D01*
G01X333058D02*
X333683Y312667D01*
G01X335950D02*
Y315167D01*
X335450Y314667D01*
G01Y312667D02*
X336450D01*
G01X338133Y313042D02*
X338383Y312834D01*
X338675Y312709D01*
X339050Y312667D01*
X339425Y312750D01*
X339717Y312917D01*
X339925Y313209D01*
X339967Y313542D01*
X339883Y313875D01*
X339675Y314084D01*
X339383Y314250D01*
X339092Y314292D01*
X338800Y314250D01*
X338425Y314084D01*
X338550Y315167D01*
X339675D01*
G01X342150D02*
X341817Y315084D01*
X341567Y314875D01*
X341400Y314625D01*
X341275Y314292D01*
X341233Y313917D01*
X341275Y313542D01*
X341400Y313209D01*
X341567Y312959D01*
X341817Y312750D01*
X342150Y312667D01*
X342483Y312750D01*
X342733Y312959D01*
X342900Y313209D01*
X343025Y313542D01*
X343067Y313917D01*
X343025Y314292D01*
X342900Y314625D01*
X342733Y314875D01*
X342483Y315084D01*
X342150Y315167D01*
G01X345950Y307823D02*
Y311823D01*
X338550D01*
G01X330517Y332000D02*
Y334500D01*
X331558D01*
X331892Y334375D01*
X332100Y334208D01*
X332183Y333875D01*
X332100Y333542D01*
X331850Y333333D01*
X331558Y333208D01*
X330517D01*
G01X331558D02*
X332183Y332000D01*
G01X333533Y332375D02*
X333783Y332167D01*
X334075Y332042D01*
X334450Y332000D01*
X334825Y332083D01*
X335117Y332250D01*
X335325Y332542D01*
X335367Y332875D01*
X335283Y333208D01*
X335075Y333417D01*
X334783Y333583D01*
X334492Y333625D01*
X334200Y333583D01*
X333825Y333417D01*
X333950Y334500D01*
X335075D01*
G01X338050Y332000D02*
Y334500D01*
X336508Y332708D01*
X338592D01*
G01X339942Y332292D02*
X340233Y332083D01*
X340567Y332000D01*
X340900Y332083D01*
X341192Y332333D01*
X341400Y332708D01*
X341483Y333083D01*
Y333542D01*
X341400Y333917D01*
X341192Y334250D01*
X340942Y334417D01*
X340650Y334500D01*
X340317Y334417D01*
X340067Y334250D01*
X339900Y334000D01*
X339817Y333667D01*
X339900Y333375D01*
X340108Y333083D01*
X340358Y332917D01*
X340650Y332875D01*
X340983Y332958D01*
X341233Y333167D01*
X341483Y333542D01*
G01X339700Y325900D02*
Y321900D01*
X347100D01*
G01X354267Y330959D02*
X354017Y331084D01*
X353725Y331167D01*
X353392D01*
X353017Y331042D01*
X352725Y330834D01*
X352517Y330584D01*
X352350Y330167D01*
X352308Y329792D01*
X352392Y329417D01*
X352517Y329167D01*
X352767Y328917D01*
X353058Y328750D01*
X353350Y328667D01*
X353642D01*
X353933Y328750D01*
X354183Y328875D01*
X354392Y329042D01*
G01X356450Y328667D02*
Y331167D01*
X355950Y330667D01*
G01Y328667D02*
X356950D01*
G01X359550D02*
Y331167D01*
X359050Y330667D01*
G01Y328667D02*
X360050D01*
G01X361858Y330750D02*
X362108Y331000D01*
X362400Y331125D01*
X362733Y331167D01*
X363150Y331084D01*
X363442Y330875D01*
X363525Y330625D01*
X363483Y330375D01*
X363317Y330167D01*
X362483Y329750D01*
X362108Y329459D01*
X361858Y329042D01*
X361775Y328667D01*
X363525D01*
G01X350267Y352792D02*
X350017Y352917D01*
X349725Y353000D01*
X349392D01*
X349017Y352875D01*
X348725Y352667D01*
X348517Y352417D01*
X348350Y352000D01*
X348308Y351625D01*
X348392Y351250D01*
X348517Y351000D01*
X348767Y350750D01*
X349058Y350583D01*
X349350Y350500D01*
X349642D01*
X349933Y350583D01*
X350183Y350708D01*
X350392Y350875D01*
G01X352450Y350500D02*
Y353000D01*
X351950Y352500D01*
G01Y350500D02*
X352950D01*
G01X355550D02*
Y353000D01*
X355050Y352500D01*
G01Y350500D02*
X356050D01*
G01X357733Y351000D02*
X357983Y350708D01*
X358317Y350542D01*
X358692Y350500D01*
X359025Y350542D01*
X359358Y350750D01*
X359567Y351000D01*
X359608Y351250D01*
X359525Y351542D01*
X359233Y351750D01*
X358942Y351833D01*
X358567D01*
G01X358942D02*
X359192Y351958D01*
X359400Y352167D01*
X359483Y352417D01*
X359400Y352667D01*
X359192Y352875D01*
X358817Y353000D01*
X358442Y352958D01*
X358067Y352792D01*
G01X389645Y328741D02*
G02I-1850J0D01*
G01Y318898D02*
G02I-1850J0D01*
G01X324925Y419211D02*
Y432611D01*
G01X334925Y419211D02*
X324925D01*
G01X334925Y432611D02*
Y419211D01*
G01X332531Y414561D02*
X328531D01*
Y407161D01*
G01X341042Y425267D02*
X340917Y425017D01*
X340834Y424725D01*
Y424392D01*
X340959Y424017D01*
X341167Y423725D01*
X341417Y423517D01*
X341834Y423350D01*
X342209Y423308D01*
X342584Y423392D01*
X342834Y423517D01*
X343084Y423767D01*
X343251Y424058D01*
X343334Y424350D01*
Y424642D01*
X343251Y424933D01*
X343126Y425183D01*
X342959Y425392D01*
G01X343334Y427367D02*
X342792Y427450D01*
X342334Y427575D01*
X341917Y427742D01*
X341459Y427950D01*
X340834Y428283D01*
Y426617D01*
G01X342834Y429633D02*
X343126Y429883D01*
X343292Y430217D01*
X343334Y430592D01*
X343292Y430925D01*
X343084Y431258D01*
X342834Y431467D01*
X342584Y431508D01*
X342292Y431425D01*
X342084Y431133D01*
X342001Y430842D01*
Y430467D01*
G01Y430842D02*
X341876Y431092D01*
X341667Y431300D01*
X341417Y431383D01*
X341167Y431300D01*
X340959Y431092D01*
X340834Y430717D01*
X340876Y430342D01*
X341042Y429967D01*
G01X343334Y433650D02*
X340834D01*
X341334Y433150D01*
G01X343334D02*
Y434150D01*
G01X324925Y432611D02*
X334925D01*
G01X326986Y445510D02*
Y441510D01*
X334386D01*
G01X442286Y497030D02*
Y470830D01*
X444236D01*
Y449830D01*
X435036D01*
Y400530D01*
X391736D01*
Y449830D01*
X382536D01*
Y470830D01*
X384486D01*
Y497030D01*
X442286D01*
G01X434990Y-101205D02*
Y-97205D01*
X432523Y-100072D01*
X435857D01*
G01X401228Y-100405D02*
X401628Y-100872D01*
X402162Y-101138D01*
X402762Y-101205D01*
X403295Y-101138D01*
X403828Y-100805D01*
X404162Y-100405D01*
X404228Y-100005D01*
X404095Y-99538D01*
X403628Y-99205D01*
X403162Y-99072D01*
X402562D01*
G01X403162D02*
X403562Y-98872D01*
X403895Y-98538D01*
X404028Y-98138D01*
X403895Y-97738D01*
X403562Y-97405D01*
X402962Y-97205D01*
X402362Y-97272D01*
X401762Y-97538D01*
G01X445950Y57811D02*
Y61811D01*
X447550D01*
X448083Y61611D01*
X448483Y61144D01*
X448616Y60611D01*
X448483Y60078D01*
X448150Y59678D01*
X447550Y59478D01*
X445950D01*
G01X450950Y57811D02*
Y60478D01*
G01Y59944D02*
X451283Y60211D01*
X451616Y60411D01*
X452083Y60478D01*
X452416Y60411D01*
X452816Y60211D01*
G01X455483Y59611D02*
X457616D01*
X457416Y60078D01*
X457083Y60344D01*
X456616Y60478D01*
X456150Y60411D01*
X455750Y60211D01*
X455483Y59744D01*
X455350Y59344D01*
Y58944D01*
X455483Y58544D01*
X455816Y58144D01*
X456216Y57878D01*
X456683Y57811D01*
X457150Y57944D01*
X457616Y58344D01*
G01X460083Y58278D02*
X460416Y58011D01*
X460883Y57811D01*
X461283D01*
X461683Y57944D01*
X461950Y58144D01*
X462083Y58411D01*
X462016Y58811D01*
X461750Y59011D01*
X460550Y59411D01*
X460283Y59878D01*
X460416Y60211D01*
X460683Y60411D01*
X461083Y60478D01*
X461483Y60411D01*
X461883Y60211D01*
G01X464683Y58278D02*
X465016Y58011D01*
X465483Y57811D01*
X465883D01*
X466283Y57944D01*
X466550Y58144D01*
X466683Y58411D01*
X466616Y58811D01*
X466350Y59011D01*
X465150Y59411D01*
X464883Y59878D01*
X465016Y60211D01*
X465283Y60411D01*
X465683Y60478D01*
X466083Y60411D01*
X466483Y60211D01*
G01X473616Y57811D02*
Y61811D01*
X476150D01*
G01X475216Y59878D02*
X473616D01*
G01X479483Y60478D02*
Y57811D01*
G01Y61544D02*
X479350Y61611D01*
Y61744D01*
X479483Y61811D01*
X479616Y61744D01*
Y61611D01*
X479483Y61544D01*
G01X484083Y61811D02*
Y57811D01*
G01X483150Y60478D02*
X485016D01*
G01X411033Y190000D02*
Y188208D01*
X411200Y187833D01*
X411533Y187583D01*
X411950Y187500D01*
X412367Y187583D01*
X412700Y187833D01*
X412867Y188208D01*
Y190000D01*
G01X415050Y187500D02*
Y190000D01*
X414550Y189500D01*
G01Y187500D02*
X415550D01*
G01X387795Y200669D02*
Y206812D01*
G01Y317048D02*
Y210512D01*
G01X389645Y198819D02*
X395788D01*
G01X506024D02*
X399488D01*
G01D02*
G02I-1850J0D01*
G01X406834Y350017D02*
X404334D01*
Y351058D01*
X404459Y351392D01*
X404626Y351600D01*
X404959Y351683D01*
X405292Y351600D01*
X405501Y351350D01*
X405626Y351058D01*
Y350017D01*
G01Y351058D02*
X406834Y351683D01*
G01Y354450D02*
X404334D01*
X406126Y352908D01*
Y354992D01*
G01X404334Y357050D02*
X404417Y356717D01*
X404626Y356467D01*
X404876Y356300D01*
X405209Y356175D01*
X405584Y356133D01*
X405959Y356175D01*
X406292Y356300D01*
X406542Y356467D01*
X406751Y356717D01*
X406834Y357050D01*
X406751Y357383D01*
X406542Y357633D01*
X406292Y357800D01*
X405959Y357925D01*
X405584Y357967D01*
X405209Y357925D01*
X404876Y357800D01*
X404626Y357633D01*
X404417Y357383D01*
X404334Y357050D01*
G01X406334Y359233D02*
X406626Y359483D01*
X406792Y359817D01*
X406834Y360192D01*
X406792Y360525D01*
X406584Y360858D01*
X406334Y361067D01*
X406084Y361108D01*
X405792Y361025D01*
X405584Y360733D01*
X405501Y360442D01*
Y360067D01*
G01Y360442D02*
X405376Y360692D01*
X405167Y360900D01*
X404917Y360983D01*
X404667Y360900D01*
X404459Y360692D01*
X404334Y360317D01*
X404376Y359942D01*
X404542Y359567D01*
G01X410400Y338384D02*
X414400D01*
Y345784D01*
G01X447500Y360517D02*
X445000D01*
Y361558D01*
X445125Y361892D01*
X445292Y362100D01*
X445625Y362183D01*
X445958Y362100D01*
X446167Y361850D01*
X446292Y361558D01*
Y360517D01*
G01Y361558D02*
X447500Y362183D01*
G01Y364450D02*
X445000D01*
X445500Y363950D01*
G01X447500D02*
Y364950D01*
G01Y368050D02*
X445000D01*
X446792Y366508D01*
Y368592D01*
G01X447500Y370567D02*
X446958Y370650D01*
X446500Y370775D01*
X446083Y370942D01*
X445625Y371150D01*
X445000Y371483D01*
Y369817D01*
G01X410834Y350067D02*
X408334D01*
Y351108D01*
X408459Y351442D01*
X408626Y351650D01*
X408959Y351733D01*
X409292Y351650D01*
X409501Y351400D01*
X409626Y351108D01*
Y350067D01*
G01Y351108D02*
X410834Y351733D01*
G01Y354000D02*
X410792Y354292D01*
X410667Y354625D01*
X410459Y354833D01*
X410167Y354917D01*
X409876Y354833D01*
X409626Y354583D01*
X409501Y354208D01*
Y353792D01*
X409417Y353542D01*
X409209Y353333D01*
X408917Y353250D01*
X408626Y353375D01*
X408417Y353667D01*
X408334Y354000D01*
X408417Y354333D01*
X408626Y354625D01*
X408917Y354750D01*
X409209Y354667D01*
X409417Y354458D01*
X409501Y354208D01*
Y353792D01*
X409626Y353417D01*
X409876Y353167D01*
X410167Y353083D01*
X410459Y353167D01*
X410667Y353375D01*
X410792Y353708D01*
X410834Y354000D01*
G01Y357017D02*
X410292Y357100D01*
X409834Y357225D01*
X409417Y357392D01*
X408959Y357600D01*
X408334Y357933D01*
Y356267D01*
G01X418841Y345784D02*
X414841D01*
Y338384D01*
G01X427000Y350517D02*
X424500D01*
Y351558D01*
X424625Y351892D01*
X424792Y352100D01*
X425125Y352183D01*
X425458Y352100D01*
X425667Y351850D01*
X425792Y351558D01*
Y350517D01*
G01Y351558D02*
X427000Y352183D01*
G01Y354450D02*
X424500D01*
X425000Y353950D01*
G01X427000D02*
Y354950D01*
G01X426500Y356633D02*
X426792Y356883D01*
X426958Y357217D01*
X427000Y357592D01*
X426958Y357925D01*
X426750Y358258D01*
X426500Y358467D01*
X426250Y358508D01*
X425958Y358425D01*
X425750Y358133D01*
X425667Y357842D01*
Y357467D01*
G01Y357842D02*
X425542Y358092D01*
X425333Y358300D01*
X425083Y358383D01*
X424833Y358300D01*
X424625Y358092D01*
X424500Y357717D01*
X424542Y357342D01*
X424708Y356967D01*
G01X425958Y359858D02*
X425667Y360150D01*
X425500Y360400D01*
X425417Y360733D01*
X425500Y361025D01*
X425667Y361233D01*
X425917Y361400D01*
X426208Y361442D01*
X426458Y361400D01*
X426708Y361233D01*
X426917Y360983D01*
X427000Y360692D01*
X426917Y360358D01*
X426667Y360067D01*
X426292Y359900D01*
X425875Y359858D01*
X425333Y359942D01*
X425042Y360067D01*
X424750Y360275D01*
X424542Y360567D01*
X424500Y360858D01*
X424583Y361150D01*
X424792Y361358D01*
G01X435500Y338800D02*
X439500D01*
Y346200D01*
G01X418700Y350217D02*
X416200D01*
Y351258D01*
X416325Y351592D01*
X416492Y351800D01*
X416825Y351883D01*
X417158Y351800D01*
X417367Y351550D01*
X417492Y351258D01*
Y350217D01*
G01Y351258D02*
X418700Y351883D01*
G01Y354150D02*
X416200D01*
X416700Y353650D01*
G01X418700D02*
Y354650D01*
G01X416617Y356458D02*
X416367Y356708D01*
X416242Y357000D01*
X416200Y357333D01*
X416283Y357750D01*
X416492Y358042D01*
X416742Y358125D01*
X416992Y358083D01*
X417200Y357917D01*
X417617Y357083D01*
X417908Y356708D01*
X418325Y356458D01*
X418700Y356375D01*
Y358125D01*
G01X416200Y360350D02*
X416283Y360017D01*
X416492Y359767D01*
X416742Y359600D01*
X417075Y359475D01*
X417450Y359433D01*
X417825Y359475D01*
X418158Y359600D01*
X418408Y359767D01*
X418617Y360017D01*
X418700Y360350D01*
X418617Y360683D01*
X418408Y360933D01*
X418158Y361100D01*
X417825Y361225D01*
X417450Y361267D01*
X417075Y361225D01*
X416742Y361100D01*
X416492Y360933D01*
X416283Y360683D01*
X416200Y360350D01*
G01X425700Y338600D02*
X429700D01*
Y346000D01*
G01X428517Y360000D02*
Y362500D01*
X429558D01*
X429892Y362375D01*
X430100Y362208D01*
X430183Y361875D01*
X430100Y361542D01*
X429850Y361333D01*
X429558Y361208D01*
X428517D01*
G01X429558D02*
X430183Y360000D01*
G01X431533Y360375D02*
X431783Y360167D01*
X432075Y360042D01*
X432450Y360000D01*
X432825Y360083D01*
X433117Y360250D01*
X433325Y360542D01*
X433367Y360875D01*
X433283Y361208D01*
X433075Y361417D01*
X432783Y361583D01*
X432492Y361625D01*
X432200Y361583D01*
X431825Y361417D01*
X431950Y362500D01*
X433075D01*
G01X435550Y360000D02*
X435842Y360042D01*
X436175Y360167D01*
X436383Y360375D01*
X436467Y360667D01*
X436383Y360958D01*
X436133Y361208D01*
X435758Y361333D01*
X435342D01*
X435092Y361417D01*
X434883Y361625D01*
X434800Y361917D01*
X434925Y362208D01*
X435217Y362417D01*
X435550Y362500D01*
X435883Y362417D01*
X436175Y362208D01*
X436300Y361917D01*
X436217Y361625D01*
X436008Y361417D01*
X435758Y361333D01*
X435342D01*
X434967Y361208D01*
X434717Y360958D01*
X434633Y360667D01*
X434717Y360375D01*
X434925Y360167D01*
X435258Y360042D01*
X435550Y360000D01*
G01X438650Y362500D02*
X438317Y362417D01*
X438067Y362208D01*
X437900Y361958D01*
X437775Y361625D01*
X437733Y361250D01*
X437775Y360875D01*
X437900Y360542D01*
X438067Y360292D01*
X438317Y360083D01*
X438650Y360000D01*
X438983Y360083D01*
X439233Y360292D01*
X439400Y360542D01*
X439525Y360875D01*
X439567Y361250D01*
X439525Y361625D01*
X439400Y361958D01*
X439233Y362208D01*
X438983Y362417D01*
X438650Y362500D01*
G01X428514Y358373D02*
Y354373D01*
X435914D01*
G01X443500Y360517D02*
X441000D01*
Y361558D01*
X441125Y361892D01*
X441292Y362100D01*
X441625Y362183D01*
X441958Y362100D01*
X442167Y361850D01*
X442292Y361558D01*
Y360517D01*
G01Y361558D02*
X443500Y362183D01*
G01Y364950D02*
X441000D01*
X442792Y363408D01*
Y365492D01*
G01X443125Y366633D02*
X443333Y366883D01*
X443458Y367175D01*
X443500Y367550D01*
X443417Y367925D01*
X443250Y368217D01*
X442958Y368425D01*
X442625Y368467D01*
X442292Y368383D01*
X442083Y368175D01*
X441917Y367883D01*
X441875Y367592D01*
X441917Y367300D01*
X442083Y366925D01*
X441000Y367050D01*
Y368175D01*
G01X443125Y369733D02*
X443333Y369983D01*
X443458Y370275D01*
X443500Y370650D01*
X443417Y371025D01*
X443250Y371317D01*
X442958Y371525D01*
X442625Y371567D01*
X442292Y371483D01*
X442083Y371275D01*
X441917Y370983D01*
X441875Y370692D01*
X441917Y370400D01*
X442083Y370025D01*
X441000Y370150D01*
Y371275D01*
G01X449300Y346200D02*
X445300D01*
Y338800D01*
G01X388067Y348000D02*
Y350500D01*
X389108D01*
X389442Y350375D01*
X389650Y350208D01*
X389733Y349875D01*
X389650Y349542D01*
X389400Y349333D01*
X389108Y349208D01*
X388067D01*
G01X389108D02*
X389733Y348000D01*
G01X391917D02*
X392000Y348542D01*
X392125Y349000D01*
X392292Y349417D01*
X392500Y349875D01*
X392833Y350500D01*
X391167D01*
G01X395017Y348000D02*
X395100Y348542D01*
X395225Y349000D01*
X395392Y349417D01*
X395600Y349875D01*
X395933Y350500D01*
X394267D01*
G01X394349Y338563D02*
Y342563D01*
X386949D01*
G01X400500Y350567D02*
X398000D01*
Y351608D01*
X398125Y351942D01*
X398292Y352150D01*
X398625Y352233D01*
X398958Y352150D01*
X399167Y351900D01*
X399292Y351608D01*
Y350567D01*
G01Y351608D02*
X400500Y352233D01*
G01Y354417D02*
X399958Y354500D01*
X399500Y354625D01*
X399083Y354792D01*
X398625Y355000D01*
X398000Y355333D01*
Y353667D01*
G01X400000Y356683D02*
X400292Y356933D01*
X400458Y357267D01*
X400500Y357642D01*
X400458Y357975D01*
X400250Y358308D01*
X400000Y358517D01*
X399750Y358558D01*
X399458Y358475D01*
X399250Y358183D01*
X399167Y357892D01*
Y357517D01*
G01Y357892D02*
X399042Y358142D01*
X398833Y358350D01*
X398583Y358433D01*
X398333Y358350D01*
X398125Y358142D01*
X398000Y357767D01*
X398042Y357392D01*
X398208Y357017D01*
G01X398300Y339700D02*
X402300D01*
Y347100D01*
G01X387795Y326891D02*
Y320748D01*
G01X389645Y328741D02*
X395788D01*
G01X506024D02*
X399488D01*
G01D02*
G02I-1850J0D01*
G01X420700Y351350D02*
X423200D01*
G01X420700Y350392D02*
Y352308D01*
G01X423200Y353617D02*
X420700D01*
Y354617D01*
X420825Y354950D01*
X421117Y355200D01*
X421450Y355283D01*
X421783Y355200D01*
X422033Y354992D01*
X422158Y354617D01*
Y353617D01*
G01X422825Y356633D02*
X423033Y356883D01*
X423158Y357175D01*
X423200Y357550D01*
X423117Y357925D01*
X422950Y358217D01*
X422658Y358425D01*
X422325Y358467D01*
X421992Y358383D01*
X421783Y358175D01*
X421617Y357883D01*
X421575Y357592D01*
X421617Y357300D01*
X421783Y356925D01*
X420700Y357050D01*
Y358175D01*
G01X421117Y359858D02*
X420867Y360108D01*
X420742Y360400D01*
X420700Y360733D01*
X420783Y361150D01*
X420992Y361442D01*
X421242Y361525D01*
X421492Y361483D01*
X421700Y361317D01*
X422117Y360483D01*
X422408Y360108D01*
X422825Y359858D01*
X423200Y359775D01*
Y361525D01*
G01X448912Y361455D02*
X451412D01*
G01X448912Y360497D02*
Y362413D01*
G01X451412Y363722D02*
X448912D01*
Y364722D01*
X449037Y365055D01*
X449329Y365305D01*
X449662Y365388D01*
X449995Y365305D01*
X450245Y365097D01*
X450370Y364722D01*
Y363722D01*
G01X451412Y368155D02*
X448912D01*
X450704Y366613D01*
Y368697D01*
G01X451037Y369838D02*
X451245Y370088D01*
X451370Y370380D01*
X451412Y370755D01*
X451329Y371130D01*
X451162Y371422D01*
X450870Y371630D01*
X450537Y371672D01*
X450204Y371588D01*
X449995Y371380D01*
X449829Y371088D01*
X449787Y370797D01*
X449829Y370505D01*
X449995Y370130D01*
X448912Y370255D01*
Y371380D01*
G01X412550Y350850D02*
X415050D01*
G01X412550Y349892D02*
Y351808D01*
G01X415050Y353117D02*
X412550D01*
Y354117D01*
X412675Y354450D01*
X412967Y354700D01*
X413300Y354783D01*
X413633Y354700D01*
X413883Y354492D01*
X414008Y354117D01*
Y353117D01*
G01X414550Y356133D02*
X414842Y356383D01*
X415008Y356717D01*
X415050Y357092D01*
X415008Y357425D01*
X414800Y357758D01*
X414550Y357967D01*
X414300Y358008D01*
X414008Y357925D01*
X413800Y357633D01*
X413717Y357342D01*
Y356967D01*
G01Y357342D02*
X413592Y357592D01*
X413383Y357800D01*
X413133Y357883D01*
X412883Y357800D01*
X412675Y357592D01*
X412550Y357217D01*
X412592Y356842D01*
X412758Y356467D01*
G01X414758Y359442D02*
X414967Y359733D01*
X415050Y360067D01*
X414967Y360400D01*
X414717Y360692D01*
X414342Y360900D01*
X413967Y360983D01*
X413508D01*
X413133Y360900D01*
X412800Y360692D01*
X412633Y360442D01*
X412550Y360150D01*
X412633Y359817D01*
X412800Y359567D01*
X413050Y359400D01*
X413383Y359317D01*
X413675Y359400D01*
X413967Y359608D01*
X414133Y359858D01*
X414175Y360150D01*
X414092Y360483D01*
X413883Y360733D01*
X413508Y360983D01*
G01X406717Y395500D02*
Y398000D01*
X407800Y395917D01*
X408883Y398000D01*
Y395500D01*
G01X410025Y395833D02*
X410358Y395625D01*
X410733Y395500D01*
X411067D01*
X411400Y395625D01*
X411650Y395833D01*
X411775Y396125D01*
X411692Y396417D01*
X411483Y396667D01*
X411108Y396833D01*
X410608Y396917D01*
X410317Y397083D01*
X410192Y397375D01*
X410275Y397667D01*
X410483Y397875D01*
X410775Y398000D01*
X411067D01*
X411358Y397917D01*
X411608Y397708D01*
G01X412958Y395500D02*
X414000Y398000D01*
X415042Y395500D01*
G01X414667Y396375D02*
X413333D01*
G01X416225Y395833D02*
X416558Y395625D01*
X416933Y395500D01*
X417267D01*
X417600Y395625D01*
X417850Y395833D01*
X417975Y396125D01*
X417892Y396417D01*
X417683Y396667D01*
X417308Y396833D01*
X416808Y396917D01*
X416517Y397083D01*
X416392Y397375D01*
X416475Y397667D01*
X416683Y397875D01*
X416975Y398000D01*
X417267D01*
X417558Y397917D01*
X417808Y397708D01*
G01X420200Y395500D02*
Y398000D01*
X419700Y397500D01*
G01Y395500D02*
X420700D01*
G01X412834Y363350D02*
X415334D01*
G01X412834Y362392D02*
Y364308D01*
G01X415334Y365617D02*
X412834D01*
Y366617D01*
X412959Y366950D01*
X413251Y367200D01*
X413584Y367283D01*
X413917Y367200D01*
X414167Y366992D01*
X414292Y366617D01*
Y365617D01*
G01X415334Y370050D02*
X412834D01*
X414626Y368508D01*
Y370592D01*
G01X412834Y372650D02*
X412917Y372317D01*
X413126Y372067D01*
X413376Y371900D01*
X413709Y371775D01*
X414084Y371733D01*
X414459Y371775D01*
X414792Y371900D01*
X415042Y372067D01*
X415251Y372317D01*
X415334Y372650D01*
X415251Y372983D01*
X415042Y373233D01*
X414792Y373400D01*
X414459Y373525D01*
X414084Y373567D01*
X413709Y373525D01*
X413376Y373400D01*
X413126Y373233D01*
X412917Y372983D01*
X412834Y372650D01*
G01X432019Y472630D02*
Y468630D01*
X430419D01*
X429886Y468830D01*
X429486Y469297D01*
X429353Y469830D01*
X429486Y470363D01*
X429819Y470763D01*
X430419Y470963D01*
X432019D01*
G01X427019Y472630D02*
Y469963D01*
G01Y470497D02*
X426686Y470230D01*
X426353Y470030D01*
X425886Y469963D01*
X425553Y470030D01*
X425153Y470230D01*
G01X422486Y470830D02*
X420353D01*
X420553Y470363D01*
X420886Y470097D01*
X421353Y469963D01*
X421819Y470030D01*
X422219Y470230D01*
X422486Y470697D01*
X422619Y471097D01*
Y471497D01*
X422486Y471897D01*
X422153Y472297D01*
X421753Y472563D01*
X421286Y472630D01*
X420819Y472497D01*
X420353Y472097D01*
G01X417886Y472163D02*
X417553Y472430D01*
X417086Y472630D01*
X416686D01*
X416286Y472497D01*
X416019Y472297D01*
X415886Y472030D01*
X415953Y471630D01*
X416219Y471430D01*
X417419Y471030D01*
X417686Y470563D01*
X417553Y470230D01*
X417286Y470030D01*
X416886Y469963D01*
X416486Y470030D01*
X416086Y470230D01*
G01X413286Y472163D02*
X412953Y472430D01*
X412486Y472630D01*
X412086D01*
X411686Y472497D01*
X411419Y472297D01*
X411286Y472030D01*
X411353Y471630D01*
X411619Y471430D01*
X412819Y471030D01*
X413086Y470563D01*
X412953Y470230D01*
X412686Y470030D01*
X412286Y469963D01*
X411886Y470030D01*
X411486Y470230D01*
G01X404353Y472630D02*
Y468630D01*
X401819D01*
G01X402753Y470563D02*
X404353D01*
G01X398486Y469963D02*
Y472630D01*
G01Y468897D02*
X398619Y468830D01*
Y468697D01*
X398486Y468630D01*
X398353Y468697D01*
Y468830D01*
X398486Y468897D01*
G01X393886Y468630D02*
Y472630D01*
G01X394819Y469963D02*
X392953D01*
G01X495914Y-99538D02*
X496381Y-99072D01*
X496781Y-98805D01*
X497314Y-98672D01*
X497781Y-98805D01*
X498114Y-99072D01*
X498381Y-99472D01*
X498448Y-99938D01*
X498381Y-100338D01*
X498114Y-100738D01*
X497714Y-101072D01*
X497248Y-101205D01*
X496714Y-101072D01*
X496248Y-100672D01*
X495981Y-100072D01*
X495914Y-99405D01*
X496048Y-98538D01*
X496248Y-98072D01*
X496581Y-97605D01*
X497048Y-97272D01*
X497514Y-97205D01*
X497981Y-97338D01*
X498314Y-97672D01*
G01X464219Y-100605D02*
X464619Y-100938D01*
X465086Y-101138D01*
X465686Y-101205D01*
X466286Y-101072D01*
X466753Y-100805D01*
X467086Y-100338D01*
X467153Y-99805D01*
X467019Y-99272D01*
X466686Y-98938D01*
X466219Y-98672D01*
X465753Y-98605D01*
X465286Y-98672D01*
X464686Y-98938D01*
X464886Y-97205D01*
X466686D01*
G01X457971Y-9163D02*
X458504Y-9496D01*
X459104Y-9696D01*
X459638D01*
X460171Y-9496D01*
X460571Y-9163D01*
X460771Y-8696D01*
X460638Y-8229D01*
X460304Y-7829D01*
X459704Y-7563D01*
X458904Y-7429D01*
X458438Y-7163D01*
X458238Y-6696D01*
X458371Y-6229D01*
X458704Y-5896D01*
X459171Y-5696D01*
X459638D01*
X460104Y-5829D01*
X460504Y-6163D01*
G01X463971Y-9696D02*
Y-5696D01*
G01X468571Y-7029D02*
Y-9696D01*
G01Y-5963D02*
X468438Y-5896D01*
Y-5763D01*
X468571Y-5696D01*
X468704Y-5763D01*
Y-5896D01*
X468571Y-5963D01*
G01X473171Y-5696D02*
Y-9696D01*
G01X472238Y-7029D02*
X474104D01*
G01X453671Y85657D02*
X453421Y85782D01*
X453129Y85865D01*
X452796D01*
X452421Y85740D01*
X452129Y85532D01*
X451921Y85282D01*
X451754Y84865D01*
X451712Y84490D01*
X451796Y84115D01*
X451921Y83865D01*
X452171Y83615D01*
X452462Y83448D01*
X452754Y83365D01*
X453046D01*
X453337Y83448D01*
X453587Y83573D01*
X453796Y83740D01*
G01X454896Y83365D02*
Y85865D01*
X456812Y83365D01*
Y85865D01*
G01X458162Y85448D02*
X458412Y85698D01*
X458704Y85823D01*
X459037Y85865D01*
X459454Y85782D01*
X459746Y85573D01*
X459829Y85323D01*
X459787Y85073D01*
X459621Y84865D01*
X458787Y84448D01*
X458412Y84157D01*
X458162Y83740D01*
X458079Y83365D01*
X459829D01*
G01X453137Y173067D02*
X453012Y172817D01*
X452929Y172525D01*
Y172192D01*
X453054Y171817D01*
X453262Y171525D01*
X453512Y171317D01*
X453929Y171150D01*
X454304Y171108D01*
X454679Y171192D01*
X454929Y171317D01*
X455179Y171567D01*
X455346Y171858D01*
X455429Y172150D01*
Y172442D01*
X455346Y172733D01*
X455221Y172983D01*
X455054Y173192D01*
G01X455429Y175750D02*
X452929D01*
X454721Y174208D01*
Y176292D01*
G01X455429Y178350D02*
X455387Y178642D01*
X455262Y178975D01*
X455054Y179183D01*
X454762Y179267D01*
X454471Y179183D01*
X454221Y178933D01*
X454096Y178558D01*
Y178142D01*
X454012Y177892D01*
X453804Y177683D01*
X453512Y177600D01*
X453221Y177725D01*
X453012Y178017D01*
X452929Y178350D01*
X453012Y178683D01*
X453221Y178975D01*
X453512Y179100D01*
X453804Y179017D01*
X454012Y178808D01*
X454096Y178558D01*
Y178142D01*
X454221Y177767D01*
X454471Y177517D01*
X454762Y177433D01*
X455054Y177517D01*
X455262Y177725D01*
X455387Y178058D01*
X455429Y178350D01*
G01X449457Y173237D02*
X449332Y172987D01*
X449249Y172695D01*
Y172362D01*
X449374Y171987D01*
X449582Y171695D01*
X449832Y171487D01*
X450249Y171320D01*
X450624Y171278D01*
X450999Y171362D01*
X451249Y171487D01*
X451499Y171737D01*
X451666Y172028D01*
X451749Y172320D01*
Y172612D01*
X451666Y172903D01*
X451541Y173153D01*
X451374Y173362D01*
G01X451749Y175920D02*
X449249D01*
X451041Y174378D01*
Y176462D01*
G01X451749Y178437D02*
X451207Y178520D01*
X450749Y178645D01*
X450332Y178812D01*
X449874Y179020D01*
X449249Y179353D01*
Y177687D01*
G01X463258Y173067D02*
X463133Y172817D01*
X463050Y172525D01*
Y172192D01*
X463175Y171817D01*
X463383Y171525D01*
X463633Y171317D01*
X464050Y171150D01*
X464425Y171108D01*
X464800Y171192D01*
X465050Y171317D01*
X465300Y171567D01*
X465467Y171858D01*
X465550Y172150D01*
Y172442D01*
X465467Y172733D01*
X465342Y172983D01*
X465175Y173192D01*
G01X465550Y175750D02*
X463050D01*
X464842Y174208D01*
Y176292D01*
G01X464508Y177558D02*
X464217Y177850D01*
X464050Y178100D01*
X463967Y178433D01*
X464050Y178725D01*
X464217Y178933D01*
X464467Y179100D01*
X464758Y179142D01*
X465008Y179100D01*
X465258Y178933D01*
X465467Y178683D01*
X465550Y178392D01*
X465467Y178058D01*
X465217Y177767D01*
X464842Y177600D01*
X464425Y177558D01*
X463883Y177642D01*
X463592Y177767D01*
X463300Y177975D01*
X463092Y178267D01*
X463050Y178558D01*
X463133Y178850D01*
X463342Y179058D01*
G01X459203Y173179D02*
X459078Y172929D01*
X458995Y172637D01*
Y172304D01*
X459120Y171929D01*
X459328Y171637D01*
X459578Y171429D01*
X459995Y171262D01*
X460370Y171220D01*
X460745Y171304D01*
X460995Y171429D01*
X461245Y171679D01*
X461412Y171970D01*
X461495Y172262D01*
Y172554D01*
X461412Y172845D01*
X461287Y173095D01*
X461120Y173304D01*
G01X461495Y175862D02*
X458995D01*
X460787Y174320D01*
Y176404D01*
G01X461120Y177545D02*
X461328Y177795D01*
X461453Y178087D01*
X461495Y178462D01*
X461412Y178837D01*
X461245Y179129D01*
X460953Y179337D01*
X460620Y179379D01*
X460287Y179295D01*
X460078Y179087D01*
X459912Y178795D01*
X459870Y178504D01*
X459912Y178212D01*
X460078Y177837D01*
X458995Y177962D01*
Y179087D01*
G01X473258Y173067D02*
X473133Y172817D01*
X473050Y172525D01*
Y172192D01*
X473175Y171817D01*
X473383Y171525D01*
X473633Y171317D01*
X474050Y171150D01*
X474425Y171108D01*
X474800Y171192D01*
X475050Y171317D01*
X475300Y171567D01*
X475467Y171858D01*
X475550Y172150D01*
Y172442D01*
X475467Y172733D01*
X475342Y172983D01*
X475175Y173192D01*
G01X475550Y175750D02*
X473050D01*
X474842Y174208D01*
Y176292D01*
G01X475550Y178850D02*
X473050D01*
X474842Y177308D01*
Y179392D01*
G01X469328Y173121D02*
X469203Y172871D01*
X469120Y172579D01*
Y172246D01*
X469245Y171871D01*
X469453Y171579D01*
X469703Y171371D01*
X470120Y171204D01*
X470495Y171162D01*
X470870Y171246D01*
X471120Y171371D01*
X471370Y171621D01*
X471537Y171912D01*
X471620Y172204D01*
Y172496D01*
X471537Y172787D01*
X471412Y173037D01*
X471245Y173246D01*
G01X471620Y175804D02*
X469120D01*
X470912Y174262D01*
Y176346D01*
G01X471120Y177487D02*
X471412Y177737D01*
X471578Y178071D01*
X471620Y178446D01*
X471578Y178779D01*
X471370Y179112D01*
X471120Y179321D01*
X470870Y179362D01*
X470578Y179279D01*
X470370Y178987D01*
X470287Y178696D01*
Y178321D01*
G01Y178696D02*
X470162Y178946D01*
X469953Y179154D01*
X469703Y179237D01*
X469453Y179154D01*
X469245Y178946D01*
X469120Y178571D01*
X469162Y178196D01*
X469328Y177821D01*
G01X483258Y173067D02*
X483133Y172817D01*
X483050Y172525D01*
Y172192D01*
X483175Y171817D01*
X483383Y171525D01*
X483633Y171317D01*
X484050Y171150D01*
X484425Y171108D01*
X484800Y171192D01*
X485050Y171317D01*
X485300Y171567D01*
X485467Y171858D01*
X485550Y172150D01*
Y172442D01*
X485467Y172733D01*
X485342Y172983D01*
X485175Y173192D01*
G01X485550Y175750D02*
X483050D01*
X484842Y174208D01*
Y176292D01*
G01X483467Y177558D02*
X483217Y177808D01*
X483092Y178100D01*
X483050Y178433D01*
X483133Y178850D01*
X483342Y179142D01*
X483592Y179225D01*
X483842Y179183D01*
X484050Y179017D01*
X484467Y178183D01*
X484758Y177808D01*
X485175Y177558D01*
X485550Y177475D01*
Y179225D01*
G01X479453Y173063D02*
X479328Y172813D01*
X479245Y172521D01*
Y172188D01*
X479370Y171813D01*
X479578Y171521D01*
X479828Y171313D01*
X480245Y171146D01*
X480620Y171104D01*
X480995Y171188D01*
X481245Y171313D01*
X481495Y171563D01*
X481662Y171854D01*
X481745Y172146D01*
Y172438D01*
X481662Y172729D01*
X481537Y172979D01*
X481370Y173188D01*
G01X481745Y175746D02*
X479245D01*
X481037Y174204D01*
Y176288D01*
G01X481745Y178346D02*
X479245D01*
X479745Y177846D01*
G01X481745D02*
Y178846D01*
G01X515867Y198819D02*
X509724D01*
G01D02*
G02I-1850J0D01*
G01X476300Y364400D02*
Y360400D01*
X483700D01*
G01X467996Y349012D02*
X471996D01*
Y356412D01*
G01X475797Y356638D02*
Y360638D01*
X468397D01*
G01X463328Y360516D02*
X460828D01*
Y361557D01*
X460953Y361891D01*
X461120Y362099D01*
X461453Y362182D01*
X461786Y362099D01*
X461995Y361849D01*
X462120Y361557D01*
Y360516D01*
G01Y361557D02*
X463328Y362182D01*
G01X462828Y363532D02*
X463120Y363782D01*
X463286Y364116D01*
X463328Y364491D01*
X463286Y364824D01*
X463078Y365157D01*
X462828Y365366D01*
X462578Y365407D01*
X462286Y365324D01*
X462078Y365032D01*
X461995Y364741D01*
Y364366D01*
G01Y364741D02*
X461870Y364991D01*
X461661Y365199D01*
X461411Y365282D01*
X461161Y365199D01*
X460953Y364991D01*
X460828Y364616D01*
X460870Y364241D01*
X461036Y363866D01*
G01X463328Y367549D02*
X463286Y367841D01*
X463161Y368174D01*
X462953Y368382D01*
X462661Y368466D01*
X462370Y368382D01*
X462120Y368132D01*
X461995Y367757D01*
Y367341D01*
X461911Y367091D01*
X461703Y366882D01*
X461411Y366799D01*
X461120Y366924D01*
X460911Y367216D01*
X460828Y367549D01*
X460911Y367882D01*
X461120Y368174D01*
X461411Y368299D01*
X461703Y368216D01*
X461911Y368007D01*
X461995Y367757D01*
Y367341D01*
X462120Y366966D01*
X462370Y366716D01*
X462661Y366632D01*
X462953Y366716D01*
X463161Y366924D01*
X463286Y367257D01*
X463328Y367549D01*
G01X474296Y346200D02*
X470296D01*
Y338800D01*
G01X472200Y352800D02*
Y348800D01*
X479600D01*
G01X449400Y338800D02*
X453400D01*
Y346200D01*
G01X455500Y360517D02*
X453000D01*
Y361558D01*
X453125Y361892D01*
X453292Y362100D01*
X453625Y362183D01*
X453958Y362100D01*
X454167Y361850D01*
X454292Y361558D01*
Y360517D01*
G01Y361558D02*
X455500Y362183D01*
G01Y364450D02*
X453000D01*
X453500Y363950D01*
G01X455500D02*
Y364950D01*
G01Y368050D02*
X453000D01*
X454792Y366508D01*
Y368592D01*
G01X455500Y371150D02*
X453000D01*
X454792Y369608D01*
Y371692D01*
G01X458327Y338801D02*
X462327D01*
Y346201D01*
G01X459500Y360517D02*
X457000D01*
Y361558D01*
X457125Y361892D01*
X457292Y362100D01*
X457625Y362183D01*
X457958Y362100D01*
X458167Y361850D01*
X458292Y361558D01*
Y360517D01*
G01Y361558D02*
X459500Y362183D01*
G01Y364450D02*
X457000D01*
X457500Y363950D01*
G01X459500D02*
Y364950D01*
G01Y368050D02*
X457000D01*
X458792Y366508D01*
Y368592D01*
G01X457417Y369858D02*
X457167Y370108D01*
X457042Y370400D01*
X457000Y370733D01*
X457083Y371150D01*
X457292Y371442D01*
X457542Y371525D01*
X457792Y371483D01*
X458000Y371317D01*
X458417Y370483D01*
X458708Y370108D01*
X459125Y369858D01*
X459500Y369775D01*
Y371525D01*
G01X462327Y338801D02*
X466327D01*
Y346201D01*
G01X480427Y352974D02*
X484427D01*
Y360374D01*
G01X484627Y352974D02*
X488627D01*
Y360374D01*
G01X508200Y357700D02*
X504200D01*
Y350300D01*
G01X501700Y357700D02*
X497700D01*
Y350300D01*
G01X495200Y357700D02*
X491200D01*
Y350300D01*
G01X495900Y339900D02*
X499900D01*
Y347300D01*
G01X500700Y339900D02*
X504700D01*
Y347300D01*
G01X505337Y339863D02*
X509337D01*
Y347263D01*
G01X510754Y339784D02*
X514754D01*
Y347184D01*
G01X476298Y352854D02*
X480298D01*
Y360254D01*
G01X467500Y360567D02*
X465000D01*
Y361608D01*
X465125Y361942D01*
X465292Y362150D01*
X465625Y362233D01*
X465958Y362150D01*
X466167Y361900D01*
X466292Y361608D01*
Y360567D01*
G01Y361608D02*
X467500Y362233D01*
G01Y364500D02*
X467458Y364792D01*
X467333Y365125D01*
X467125Y365333D01*
X466833Y365417D01*
X466542Y365333D01*
X466292Y365083D01*
X466167Y364708D01*
Y364292D01*
X466083Y364042D01*
X465875Y363833D01*
X465583Y363750D01*
X465292Y363875D01*
X465083Y364167D01*
X465000Y364500D01*
X465083Y364833D01*
X465292Y365125D01*
X465583Y365250D01*
X465875Y365167D01*
X466083Y364958D01*
X466167Y364708D01*
Y364292D01*
X466292Y363917D01*
X466542Y363667D01*
X466833Y363583D01*
X467125Y363667D01*
X467333Y363875D01*
X467458Y364208D01*
X467500Y364500D01*
G01X467000Y366683D02*
X467292Y366933D01*
X467458Y367267D01*
X467500Y367642D01*
X467458Y367975D01*
X467250Y368308D01*
X467000Y368517D01*
X466750Y368558D01*
X466458Y368475D01*
X466250Y368183D01*
X466167Y367892D01*
Y367517D01*
G01Y367892D02*
X466042Y368142D01*
X465833Y368350D01*
X465583Y368433D01*
X465333Y368350D01*
X465125Y368142D01*
X465000Y367767D01*
X465042Y367392D01*
X465208Y367017D01*
G01X478500Y346200D02*
X474500D01*
Y338800D01*
G01X478700D02*
X482700D01*
Y346200D01*
G01X515867Y328741D02*
X509724D01*
G01D02*
G02I-1850J0D01*
G01X477017Y391000D02*
Y393500D01*
X478058D01*
X478392Y393375D01*
X478600Y393208D01*
X478683Y392875D01*
X478600Y392542D01*
X478350Y392333D01*
X478058Y392208D01*
X477017D01*
G01X478058D02*
X478683Y391000D01*
G01X480033Y391375D02*
X480283Y391167D01*
X480575Y391042D01*
X480950Y391000D01*
X481325Y391083D01*
X481617Y391250D01*
X481825Y391542D01*
X481867Y391875D01*
X481783Y392208D01*
X481575Y392417D01*
X481283Y392583D01*
X480992Y392625D01*
X480700Y392583D01*
X480325Y392417D01*
X480450Y393500D01*
X481575D01*
G01X483258Y392042D02*
X483550Y392333D01*
X483800Y392500D01*
X484133Y392583D01*
X484425Y392500D01*
X484633Y392333D01*
X484800Y392083D01*
X484842Y391792D01*
X484800Y391542D01*
X484633Y391292D01*
X484383Y391083D01*
X484092Y391000D01*
X483758Y391083D01*
X483467Y391333D01*
X483300Y391708D01*
X483258Y392125D01*
X483342Y392667D01*
X483467Y392958D01*
X483675Y393250D01*
X483967Y393458D01*
X484258Y393500D01*
X484550Y393417D01*
X484758Y393208D01*
G01X487650Y391000D02*
Y393500D01*
X486108Y391708D01*
X488192D01*
G01X467500Y374567D02*
X465000D01*
Y375608D01*
X465125Y375942D01*
X465292Y376150D01*
X465625Y376233D01*
X465958Y376150D01*
X466167Y375900D01*
X466292Y375608D01*
Y374567D01*
G01Y375608D02*
X467500Y376233D01*
G01Y379000D02*
X465000D01*
X466792Y377458D01*
Y379542D01*
G01X466458Y380808D02*
X466167Y381100D01*
X466000Y381350D01*
X465917Y381683D01*
X466000Y381975D01*
X466167Y382183D01*
X466417Y382350D01*
X466708Y382392D01*
X466958Y382350D01*
X467208Y382183D01*
X467417Y381933D01*
X467500Y381642D01*
X467417Y381308D01*
X467167Y381017D01*
X466792Y380850D01*
X466375Y380808D01*
X465833Y380892D01*
X465542Y381017D01*
X465250Y381225D01*
X465042Y381517D01*
X465000Y381808D01*
X465083Y382100D01*
X465292Y382308D01*
G01X461067Y384000D02*
Y386500D01*
X462108D01*
X462442Y386375D01*
X462650Y386208D01*
X462733Y385875D01*
X462650Y385542D01*
X462400Y385333D01*
X462108Y385208D01*
X461067D01*
G01X462108D02*
X462733Y384000D01*
G01X465500D02*
Y386500D01*
X463958Y384708D01*
X466042D01*
G01X468600Y384000D02*
Y386500D01*
X467058Y384708D01*
X469142D01*
G01X512500Y377067D02*
X510000D01*
Y378108D01*
X510125Y378442D01*
X510292Y378650D01*
X510625Y378733D01*
X510958Y378650D01*
X511167Y378400D01*
X511292Y378108D01*
Y377067D01*
G01Y378108D02*
X512500Y378733D01*
G01X512000Y380083D02*
X512292Y380333D01*
X512458Y380667D01*
X512500Y381042D01*
X512458Y381375D01*
X512250Y381708D01*
X512000Y381917D01*
X511750Y381958D01*
X511458Y381875D01*
X511250Y381583D01*
X511167Y381292D01*
Y380917D01*
G01Y381292D02*
X511042Y381542D01*
X510833Y381750D01*
X510583Y381833D01*
X510333Y381750D01*
X510125Y381542D01*
X510000Y381167D01*
X510042Y380792D01*
X510208Y380417D01*
G01X512208Y383392D02*
X512417Y383683D01*
X512500Y384017D01*
X512417Y384350D01*
X512167Y384642D01*
X511792Y384850D01*
X511417Y384933D01*
X510958D01*
X510583Y384850D01*
X510250Y384642D01*
X510083Y384392D01*
X510000Y384100D01*
X510083Y383767D01*
X510250Y383517D01*
X510500Y383350D01*
X510833Y383267D01*
X511125Y383350D01*
X511417Y383558D01*
X511583Y383808D01*
X511625Y384100D01*
X511542Y384433D01*
X511333Y384683D01*
X510958Y384933D01*
G01X469567Y374500D02*
Y377000D01*
X470608D01*
X470942Y376875D01*
X471150Y376708D01*
X471233Y376375D01*
X471150Y376042D01*
X470900Y375833D01*
X470608Y375708D01*
X469567D01*
G01X470608D02*
X471233Y374500D01*
G01X472583Y375000D02*
X472833Y374708D01*
X473167Y374542D01*
X473542Y374500D01*
X473875Y374542D01*
X474208Y374750D01*
X474417Y375000D01*
X474458Y375250D01*
X474375Y375542D01*
X474083Y375750D01*
X473792Y375833D01*
X473417D01*
G01X473792D02*
X474042Y375958D01*
X474250Y376167D01*
X474333Y376417D01*
X474250Y376667D01*
X474042Y376875D01*
X473667Y377000D01*
X473292Y376958D01*
X472917Y376792D01*
G01X475683Y375000D02*
X475933Y374708D01*
X476267Y374542D01*
X476642Y374500D01*
X476975Y374542D01*
X477308Y374750D01*
X477517Y375000D01*
X477558Y375250D01*
X477475Y375542D01*
X477183Y375750D01*
X476892Y375833D01*
X476517D01*
G01X476892D02*
X477142Y375958D01*
X477350Y376167D01*
X477433Y376417D01*
X477350Y376667D01*
X477142Y376875D01*
X476767Y377000D01*
X476392Y376958D01*
X476017Y376792D01*
G01X483427Y378191D02*
X480927D01*
Y379232D01*
X481052Y379566D01*
X481219Y379774D01*
X481552Y379857D01*
X481885Y379774D01*
X482094Y379524D01*
X482219Y379232D01*
Y378191D01*
G01Y379232D02*
X483427Y379857D01*
G01Y382124D02*
X480927D01*
X481427Y381624D01*
G01X483427D02*
Y382624D01*
G01X481344Y384432D02*
X481094Y384682D01*
X480969Y384974D01*
X480927Y385307D01*
X481010Y385724D01*
X481219Y386016D01*
X481469Y386099D01*
X481719Y386057D01*
X481927Y385891D01*
X482344Y385057D01*
X482635Y384682D01*
X483052Y384432D01*
X483427Y384349D01*
Y386099D01*
G01Y388324D02*
X483385Y388616D01*
X483260Y388949D01*
X483052Y389157D01*
X482760Y389241D01*
X482469Y389157D01*
X482219Y388907D01*
X482094Y388532D01*
Y388116D01*
X482010Y387866D01*
X481802Y387657D01*
X481510Y387574D01*
X481219Y387699D01*
X481010Y387991D01*
X480927Y388324D01*
X481010Y388657D01*
X481219Y388949D01*
X481510Y389074D01*
X481802Y388991D01*
X482010Y388782D01*
X482094Y388532D01*
Y388116D01*
X482219Y387741D01*
X482469Y387491D01*
X482760Y387407D01*
X483052Y387491D01*
X483260Y387699D01*
X483385Y388032D01*
X483427Y388324D01*
G01X487627Y378191D02*
X485127D01*
Y379232D01*
X485252Y379566D01*
X485419Y379774D01*
X485752Y379857D01*
X486085Y379774D01*
X486294Y379524D01*
X486419Y379232D01*
Y378191D01*
G01Y379232D02*
X487627Y379857D01*
G01Y382124D02*
X485127D01*
X485627Y381624D01*
G01X487627D02*
Y382624D01*
G01X485544Y384432D02*
X485294Y384682D01*
X485169Y384974D01*
X485127Y385307D01*
X485210Y385724D01*
X485419Y386016D01*
X485669Y386099D01*
X485919Y386057D01*
X486127Y385891D01*
X486544Y385057D01*
X486835Y384682D01*
X487252Y384432D01*
X487627Y384349D01*
Y386099D01*
G01X486585Y387532D02*
X486294Y387824D01*
X486127Y388074D01*
X486044Y388407D01*
X486127Y388699D01*
X486294Y388907D01*
X486544Y389074D01*
X486835Y389116D01*
X487085Y389074D01*
X487335Y388907D01*
X487544Y388657D01*
X487627Y388366D01*
X487544Y388032D01*
X487294Y387741D01*
X486919Y387574D01*
X486502Y387532D01*
X485960Y387616D01*
X485669Y387741D01*
X485377Y387949D01*
X485169Y388241D01*
X485127Y388532D01*
X485210Y388824D01*
X485419Y389032D01*
G01X508500Y377167D02*
X506000D01*
Y378208D01*
X506125Y378542D01*
X506292Y378750D01*
X506625Y378833D01*
X506958Y378750D01*
X507167Y378500D01*
X507292Y378208D01*
Y377167D01*
G01Y378208D02*
X508500Y378833D01*
G01Y381100D02*
X506000D01*
X506500Y380600D01*
G01X508500D02*
Y381600D01*
G01Y384200D02*
X506000D01*
X506500Y383700D01*
G01X508500D02*
Y384700D01*
G01X508208Y386592D02*
X508417Y386883D01*
X508500Y387217D01*
X508417Y387550D01*
X508167Y387842D01*
X507792Y388050D01*
X507417Y388133D01*
X506958D01*
X506583Y388050D01*
X506250Y387842D01*
X506083Y387592D01*
X506000Y387300D01*
X506083Y386967D01*
X506250Y386717D01*
X506500Y386550D01*
X506833Y386467D01*
X507125Y386550D01*
X507417Y386758D01*
X507583Y387008D01*
X507625Y387300D01*
X507542Y387633D01*
X507333Y387883D01*
X506958Y388133D01*
G01X500500Y377517D02*
X498000D01*
Y378558D01*
X498125Y378892D01*
X498292Y379100D01*
X498625Y379183D01*
X498958Y379100D01*
X499167Y378850D01*
X499292Y378558D01*
Y377517D01*
G01Y378558D02*
X500500Y379183D01*
G01Y381450D02*
X498000D01*
X498500Y380950D01*
G01X500500D02*
Y381950D01*
G01Y384550D02*
X498000D01*
X498500Y384050D01*
G01X500500D02*
Y385050D01*
G01Y387650D02*
X500458Y387942D01*
X500333Y388275D01*
X500125Y388483D01*
X499833Y388567D01*
X499542Y388483D01*
X499292Y388233D01*
X499167Y387858D01*
Y387442D01*
X499083Y387192D01*
X498875Y386983D01*
X498583Y386900D01*
X498292Y387025D01*
X498083Y387317D01*
X498000Y387650D01*
X498083Y387983D01*
X498292Y388275D01*
X498583Y388400D01*
X498875Y388317D01*
X499083Y388108D01*
X499167Y387858D01*
Y387442D01*
X499292Y387067D01*
X499542Y386817D01*
X499833Y386733D01*
X500125Y386817D01*
X500333Y387025D01*
X500458Y387358D01*
X500500Y387650D01*
G01X504500Y377317D02*
X502000D01*
Y378358D01*
X502125Y378692D01*
X502292Y378900D01*
X502625Y378983D01*
X502958Y378900D01*
X503167Y378650D01*
X503292Y378358D01*
Y377317D01*
G01Y378358D02*
X504500Y378983D01*
G01Y381250D02*
X502000D01*
X502500Y380750D01*
G01X504500D02*
Y381750D01*
G01Y384350D02*
X502000D01*
X502500Y383850D01*
G01X504500D02*
Y384850D01*
G01Y387367D02*
X503958Y387450D01*
X503500Y387575D01*
X503083Y387742D01*
X502625Y387950D01*
X502000Y388283D01*
Y386617D01*
G01X496834Y381317D02*
X494334D01*
Y382358D01*
X494459Y382692D01*
X494626Y382900D01*
X494959Y382983D01*
X495292Y382900D01*
X495501Y382650D01*
X495626Y382358D01*
Y381317D01*
G01Y382358D02*
X496834Y382983D01*
G01Y385250D02*
X494334D01*
X494834Y384750D01*
G01X496834D02*
Y385750D01*
G01Y388350D02*
X494334D01*
X494834Y387850D01*
G01X496834D02*
Y388850D01*
G01X495792Y390658D02*
X495501Y390950D01*
X495334Y391200D01*
X495251Y391533D01*
X495334Y391825D01*
X495501Y392033D01*
X495751Y392200D01*
X496042Y392242D01*
X496292Y392200D01*
X496542Y392033D01*
X496751Y391783D01*
X496834Y391492D01*
X496751Y391158D01*
X496501Y390867D01*
X496126Y390700D01*
X495709Y390658D01*
X495167Y390742D01*
X494876Y390867D01*
X494584Y391075D01*
X494376Y391367D01*
X494334Y391658D01*
X494417Y391950D01*
X494626Y392158D01*
G01X492700Y377517D02*
X490200D01*
Y378558D01*
X490325Y378892D01*
X490492Y379100D01*
X490825Y379183D01*
X491158Y379100D01*
X491367Y378850D01*
X491492Y378558D01*
Y377517D01*
G01Y378558D02*
X492700Y379183D01*
G01Y381450D02*
X490200D01*
X490700Y380950D01*
G01X492700D02*
Y381950D01*
G01Y384550D02*
X490200D01*
X490700Y384050D01*
G01X492700D02*
Y385050D01*
G01X492200Y386733D02*
X492492Y386983D01*
X492658Y387317D01*
X492700Y387692D01*
X492658Y388025D01*
X492450Y388358D01*
X492200Y388567D01*
X491950Y388608D01*
X491658Y388525D01*
X491450Y388233D01*
X491367Y387942D01*
Y387567D01*
G01Y387942D02*
X491242Y388192D01*
X491033Y388400D01*
X490783Y388483D01*
X490533Y388400D01*
X490325Y388192D01*
X490200Y387817D01*
X490242Y387442D01*
X490408Y387067D01*
G01X493500Y364517D02*
X491000D01*
Y365558D01*
X491125Y365892D01*
X491292Y366100D01*
X491625Y366183D01*
X491958Y366100D01*
X492167Y365850D01*
X492292Y365558D01*
Y364517D01*
G01Y365558D02*
X493500Y366183D01*
G01Y368450D02*
X491000D01*
X491500Y367950D01*
G01X493500D02*
Y368950D01*
G01X491000Y371550D02*
X491083Y371217D01*
X491292Y370967D01*
X491542Y370800D01*
X491875Y370675D01*
X492250Y370633D01*
X492625Y370675D01*
X492958Y370800D01*
X493208Y370967D01*
X493417Y371217D01*
X493500Y371550D01*
X493417Y371883D01*
X493208Y372133D01*
X492958Y372300D01*
X492625Y372425D01*
X492250Y372467D01*
X491875Y372425D01*
X491542Y372300D01*
X491292Y372133D01*
X491083Y371883D01*
X491000Y371550D01*
G01X493000Y373733D02*
X493292Y373983D01*
X493458Y374317D01*
X493500Y374692D01*
X493458Y375025D01*
X493250Y375358D01*
X493000Y375567D01*
X492750Y375608D01*
X492458Y375525D01*
X492250Y375233D01*
X492167Y374942D01*
Y374567D01*
G01Y374942D02*
X492042Y375192D01*
X491833Y375400D01*
X491583Y375483D01*
X491333Y375400D01*
X491125Y375192D01*
X491000Y374817D01*
X491042Y374442D01*
X491208Y374067D01*
G01X497500Y364517D02*
X495000D01*
Y365558D01*
X495125Y365892D01*
X495292Y366100D01*
X495625Y366183D01*
X495958Y366100D01*
X496167Y365850D01*
X496292Y365558D01*
Y364517D01*
G01Y365558D02*
X497500Y366183D01*
G01Y368450D02*
X495000D01*
X495500Y367950D01*
G01X497500D02*
Y368950D01*
G01X495000Y371550D02*
X495083Y371217D01*
X495292Y370967D01*
X495542Y370800D01*
X495875Y370675D01*
X496250Y370633D01*
X496625Y370675D01*
X496958Y370800D01*
X497208Y370967D01*
X497417Y371217D01*
X497500Y371550D01*
X497417Y371883D01*
X497208Y372133D01*
X496958Y372300D01*
X496625Y372425D01*
X496250Y372467D01*
X495875Y372425D01*
X495542Y372300D01*
X495292Y372133D01*
X495083Y371883D01*
X495000Y371550D01*
G01X495417Y373858D02*
X495167Y374108D01*
X495042Y374400D01*
X495000Y374733D01*
X495083Y375150D01*
X495292Y375442D01*
X495542Y375525D01*
X495792Y375483D01*
X496000Y375317D01*
X496417Y374483D01*
X496708Y374108D01*
X497125Y373858D01*
X497500Y373775D01*
Y375525D01*
G01X501337Y364580D02*
X498837D01*
Y365621D01*
X498962Y365955D01*
X499129Y366163D01*
X499462Y366246D01*
X499795Y366163D01*
X500004Y365913D01*
X500129Y365621D01*
Y364580D01*
G01Y365621D02*
X501337Y366246D01*
G01Y368513D02*
X498837D01*
X499337Y368013D01*
G01X501337D02*
Y369013D01*
G01X498837Y371613D02*
X498920Y371280D01*
X499129Y371030D01*
X499379Y370863D01*
X499712Y370738D01*
X500087Y370696D01*
X500462Y370738D01*
X500795Y370863D01*
X501045Y371030D01*
X501254Y371280D01*
X501337Y371613D01*
X501254Y371946D01*
X501045Y372196D01*
X500795Y372363D01*
X500462Y372488D01*
X500087Y372530D01*
X499712Y372488D01*
X499379Y372363D01*
X499129Y372196D01*
X498920Y371946D01*
X498837Y371613D01*
G01X501337Y374713D02*
X498837D01*
X499337Y374213D01*
G01X501337D02*
Y375213D01*
G01X505254Y364501D02*
X502754D01*
Y365542D01*
X502879Y365876D01*
X503046Y366084D01*
X503379Y366167D01*
X503712Y366084D01*
X503921Y365834D01*
X504046Y365542D01*
Y364501D01*
G01Y365542D02*
X505254Y366167D01*
G01Y368434D02*
X502754D01*
X503254Y367934D01*
G01X505254D02*
Y368934D01*
G01X502754Y371534D02*
X502837Y371201D01*
X503046Y370951D01*
X503296Y370784D01*
X503629Y370659D01*
X504004Y370617D01*
X504379Y370659D01*
X504712Y370784D01*
X504962Y370951D01*
X505171Y371201D01*
X505254Y371534D01*
X505171Y371867D01*
X504962Y372117D01*
X504712Y372284D01*
X504379Y372409D01*
X504004Y372451D01*
X503629Y372409D01*
X503296Y372284D01*
X503046Y372117D01*
X502837Y371867D01*
X502754Y371534D01*
G01Y374634D02*
X502837Y374301D01*
X503046Y374051D01*
X503296Y373884D01*
X503629Y373759D01*
X504004Y373717D01*
X504379Y373759D01*
X504712Y373884D01*
X504962Y374051D01*
X505171Y374301D01*
X505254Y374634D01*
X505171Y374967D01*
X504962Y375217D01*
X504712Y375384D01*
X504379Y375509D01*
X504004Y375551D01*
X503629Y375509D01*
X503296Y375384D01*
X503046Y375217D01*
X502837Y374967D01*
X502754Y374634D01*
G01X479298Y378071D02*
X476798D01*
Y379112D01*
X476923Y379446D01*
X477090Y379654D01*
X477423Y379737D01*
X477756Y379654D01*
X477965Y379404D01*
X478090Y379112D01*
Y378071D01*
G01Y379112D02*
X479298Y379737D01*
G01X477215Y381212D02*
X476965Y381462D01*
X476840Y381754D01*
X476798Y382087D01*
X476881Y382504D01*
X477090Y382796D01*
X477340Y382879D01*
X477590Y382837D01*
X477798Y382671D01*
X478215Y381837D01*
X478506Y381462D01*
X478923Y381212D01*
X479298Y381129D01*
Y382879D01*
G01X476798Y385104D02*
X476881Y384771D01*
X477090Y384521D01*
X477340Y384354D01*
X477673Y384229D01*
X478048Y384187D01*
X478423Y384229D01*
X478756Y384354D01*
X479006Y384521D01*
X479215Y384771D01*
X479298Y385104D01*
X479215Y385437D01*
X479006Y385687D01*
X478756Y385854D01*
X478423Y385979D01*
X478048Y386021D01*
X477673Y385979D01*
X477340Y385854D01*
X477090Y385687D01*
X476881Y385437D01*
X476798Y385104D01*
G01X478256Y387412D02*
X477965Y387704D01*
X477798Y387954D01*
X477715Y388287D01*
X477798Y388579D01*
X477965Y388787D01*
X478215Y388954D01*
X478506Y388996D01*
X478756Y388954D01*
X479006Y388787D01*
X479215Y388537D01*
X479298Y388246D01*
X479215Y387912D01*
X478965Y387621D01*
X478590Y387454D01*
X478173Y387412D01*
X477631Y387496D01*
X477340Y387621D01*
X477048Y387829D01*
X476840Y388121D01*
X476798Y388412D01*
X476881Y388704D01*
X477090Y388912D01*
G01X477017Y395000D02*
Y397500D01*
X478058D01*
X478392Y397375D01*
X478600Y397208D01*
X478683Y396875D01*
X478600Y396542D01*
X478350Y396333D01*
X478058Y396208D01*
X477017D01*
G01X478058D02*
X478683Y395000D01*
G01X480033Y395500D02*
X480283Y395208D01*
X480617Y395042D01*
X480992Y395000D01*
X481325Y395042D01*
X481658Y395250D01*
X481867Y395500D01*
X481908Y395750D01*
X481825Y396042D01*
X481533Y396250D01*
X481242Y396333D01*
X480867D01*
G01X481242D02*
X481492Y396458D01*
X481700Y396667D01*
X481783Y396917D01*
X481700Y397167D01*
X481492Y397375D01*
X481117Y397500D01*
X480742Y397458D01*
X480367Y397292D01*
G01X484050Y397500D02*
X483717Y397417D01*
X483467Y397208D01*
X483300Y396958D01*
X483175Y396625D01*
X483133Y396250D01*
X483175Y395875D01*
X483300Y395542D01*
X483467Y395292D01*
X483717Y395083D01*
X484050Y395000D01*
X484383Y395083D01*
X484633Y395292D01*
X484800Y395542D01*
X484925Y395875D01*
X484967Y396250D01*
X484925Y396625D01*
X484800Y396958D01*
X484633Y397208D01*
X484383Y397417D01*
X484050Y397500D01*
G01X487150Y395000D02*
X487442Y395042D01*
X487775Y395167D01*
X487983Y395375D01*
X488067Y395667D01*
X487983Y395958D01*
X487733Y396208D01*
X487358Y396333D01*
X486942D01*
X486692Y396417D01*
X486483Y396625D01*
X486400Y396917D01*
X486525Y397208D01*
X486817Y397417D01*
X487150Y397500D01*
X487483Y397417D01*
X487775Y397208D01*
X487900Y396917D01*
X487817Y396625D01*
X487608Y396417D01*
X487358Y396333D01*
X486942D01*
X486567Y396208D01*
X486317Y395958D01*
X486233Y395667D01*
X486317Y395375D01*
X486525Y395167D01*
X486858Y395042D01*
X487150Y395000D01*
G01X476300Y368800D02*
Y364800D01*
X483700D01*
G01X471500Y362517D02*
X469000D01*
Y363558D01*
X469125Y363892D01*
X469292Y364100D01*
X469625Y364183D01*
X469958Y364100D01*
X470167Y363850D01*
X470292Y363558D01*
Y362517D01*
G01Y363558D02*
X471500Y364183D01*
G01Y366450D02*
X469000D01*
X469500Y365950D01*
G01X471500D02*
Y366950D01*
G01X471000Y368633D02*
X471292Y368883D01*
X471458Y369217D01*
X471500Y369592D01*
X471458Y369925D01*
X471250Y370258D01*
X471000Y370467D01*
X470750Y370508D01*
X470458Y370425D01*
X470250Y370133D01*
X470167Y369842D01*
Y369467D01*
G01Y369842D02*
X470042Y370092D01*
X469833Y370300D01*
X469583Y370383D01*
X469333Y370300D01*
X469125Y370092D01*
X469000Y369717D01*
X469042Y369342D01*
X469208Y368967D01*
G01X471500Y372650D02*
X469000D01*
X469500Y372150D01*
G01X471500D02*
Y373150D01*
G01X461000Y372350D02*
X463500D01*
G01X461000Y371392D02*
Y373308D01*
G01X463500Y374617D02*
X461000D01*
Y375617D01*
X461125Y375950D01*
X461417Y376200D01*
X461750Y376283D01*
X462083Y376200D01*
X462333Y375992D01*
X462458Y375617D01*
Y374617D01*
G01X463125Y377633D02*
X463333Y377883D01*
X463458Y378175D01*
X463500Y378550D01*
X463417Y378925D01*
X463250Y379217D01*
X462958Y379425D01*
X462625Y379467D01*
X462292Y379383D01*
X462083Y379175D01*
X461917Y378883D01*
X461875Y378592D01*
X461917Y378300D01*
X462083Y377925D01*
X461000Y378050D01*
Y379175D01*
G01Y381650D02*
X461083Y381317D01*
X461292Y381067D01*
X461542Y380900D01*
X461875Y380775D01*
X462250Y380733D01*
X462625Y380775D01*
X462958Y380900D01*
X463208Y381067D01*
X463417Y381317D01*
X463500Y381650D01*
X463417Y381983D01*
X463208Y382233D01*
X462958Y382400D01*
X462625Y382525D01*
X462250Y382567D01*
X461875Y382525D01*
X461542Y382400D01*
X461292Y382233D01*
X461083Y381983D01*
X461000Y381650D01*
G01X486333Y364850D02*
X488833D01*
G01X486333Y363892D02*
Y365808D01*
G01X488833Y367117D02*
X486333D01*
Y368117D01*
X486458Y368450D01*
X486750Y368700D01*
X487083Y368783D01*
X487416Y368700D01*
X487666Y368492D01*
X487791Y368117D01*
Y367117D01*
G01X488833Y371550D02*
X486333D01*
X488125Y370008D01*
Y372092D01*
G01X488833Y374650D02*
X486333D01*
X488125Y373108D01*
Y375192D01*
G01X506800Y365200D02*
X509300D01*
G01X506800Y364242D02*
Y366158D01*
G01X509300Y367467D02*
X506800D01*
Y368467D01*
X506925Y368800D01*
X507217Y369050D01*
X507550Y369133D01*
X507883Y369050D01*
X508133Y368842D01*
X508258Y368467D01*
Y367467D01*
G01X508800Y370483D02*
X509092Y370733D01*
X509258Y371067D01*
X509300Y371442D01*
X509258Y371775D01*
X509050Y372108D01*
X508800Y372317D01*
X508550Y372358D01*
X508258Y372275D01*
X508050Y371983D01*
X507967Y371692D01*
Y371317D01*
G01Y371692D02*
X507842Y371942D01*
X507633Y372150D01*
X507383Y372233D01*
X507133Y372150D01*
X506925Y371942D01*
X506800Y371567D01*
X506842Y371192D01*
X507008Y370817D01*
G01X508925Y373583D02*
X509133Y373833D01*
X509258Y374125D01*
X509300Y374500D01*
X509217Y374875D01*
X509050Y375167D01*
X508758Y375375D01*
X508425Y375417D01*
X508092Y375333D01*
X507883Y375125D01*
X507717Y374833D01*
X507675Y374542D01*
X507717Y374250D01*
X507883Y373875D01*
X506800Y374000D01*
Y375125D01*
G01X511000Y364850D02*
X513500D01*
G01X511000Y363892D02*
Y365808D01*
G01X513500Y367117D02*
X511000D01*
Y368117D01*
X511125Y368450D01*
X511417Y368700D01*
X511750Y368783D01*
X512083Y368700D01*
X512333Y368492D01*
X512458Y368117D01*
Y367117D01*
G01X513500Y371050D02*
X511000D01*
X511500Y370550D01*
G01X513500D02*
Y371550D01*
G01Y374150D02*
X513458Y374442D01*
X513333Y374775D01*
X513125Y374983D01*
X512833Y375067D01*
X512542Y374983D01*
X512292Y374733D01*
X512167Y374358D01*
Y373942D01*
X512083Y373692D01*
X511875Y373483D01*
X511583Y373400D01*
X511292Y373525D01*
X511083Y373817D01*
X511000Y374150D01*
X511083Y374483D01*
X511292Y374775D01*
X511583Y374900D01*
X511875Y374817D01*
X512083Y374608D01*
X512167Y374358D01*
Y373942D01*
X512292Y373567D01*
X512542Y373317D01*
X512833Y373233D01*
X513125Y373317D01*
X513333Y373525D01*
X513458Y373858D01*
X513500Y374150D01*
G01X468300Y433700D02*
Y431200D01*
G01X467342Y433700D02*
X469258D01*
G01X470567Y431200D02*
Y433700D01*
X471567D01*
X471900Y433575D01*
X472150Y433283D01*
X472233Y432950D01*
X472150Y432617D01*
X471942Y432367D01*
X471567Y432242D01*
X470567D01*
G01X474500Y431200D02*
Y433700D01*
X474000Y433200D01*
G01Y431200D02*
X475000D01*
G01X476683Y431575D02*
X476933Y431367D01*
X477225Y431242D01*
X477600Y431200D01*
X477975Y431283D01*
X478267Y431450D01*
X478475Y431742D01*
X478517Y432075D01*
X478433Y432408D01*
X478225Y432617D01*
X477933Y432783D01*
X477642Y432825D01*
X477350Y432783D01*
X476975Y432617D01*
X477100Y433700D01*
X478225D01*
G01X480700Y431200D02*
Y433700D01*
X480200Y433200D01*
G01Y431200D02*
X481200D01*
G01X495600Y433700D02*
Y431200D01*
G01X494642Y433700D02*
X496558D01*
G01X497867Y431200D02*
Y433700D01*
X498867D01*
X499200Y433575D01*
X499450Y433283D01*
X499533Y432950D01*
X499450Y432617D01*
X499242Y432367D01*
X498867Y432242D01*
X497867D01*
G01X501800Y431200D02*
Y433700D01*
X501300Y433200D01*
G01Y431200D02*
X502300D01*
G01X503983Y431575D02*
X504233Y431367D01*
X504525Y431242D01*
X504900Y431200D01*
X505275Y431283D01*
X505567Y431450D01*
X505775Y431742D01*
X505817Y432075D01*
X505733Y432408D01*
X505525Y432617D01*
X505233Y432783D01*
X504942Y432825D01*
X504650Y432783D01*
X504275Y432617D01*
X504400Y433700D01*
X505525D01*
G01X507208Y433283D02*
X507458Y433533D01*
X507750Y433658D01*
X508083Y433700D01*
X508500Y433617D01*
X508792Y433408D01*
X508875Y433158D01*
X508833Y432908D01*
X508667Y432700D01*
X507833Y432283D01*
X507458Y431992D01*
X507208Y431575D01*
X507125Y431200D01*
X508875D01*
G01X468300Y428900D02*
Y426400D01*
G01X467342Y428900D02*
X469258D01*
G01X470567Y426400D02*
Y428900D01*
X471567D01*
X471900Y428775D01*
X472150Y428483D01*
X472233Y428150D01*
X472150Y427817D01*
X471942Y427567D01*
X471567Y427442D01*
X470567D01*
G01X474500Y426400D02*
Y428900D01*
X474000Y428400D01*
G01Y426400D02*
X475000D01*
G01X476683Y426775D02*
X476933Y426567D01*
X477225Y426442D01*
X477600Y426400D01*
X477975Y426483D01*
X478267Y426650D01*
X478475Y426942D01*
X478517Y427275D01*
X478433Y427608D01*
X478225Y427817D01*
X477933Y427983D01*
X477642Y428025D01*
X477350Y427983D01*
X476975Y427817D01*
X477100Y428900D01*
X478225D01*
G01X479783Y426900D02*
X480033Y426608D01*
X480367Y426442D01*
X480742Y426400D01*
X481075Y426442D01*
X481408Y426650D01*
X481617Y426900D01*
X481658Y427150D01*
X481575Y427442D01*
X481283Y427650D01*
X480992Y427733D01*
X480617D01*
G01X480992D02*
X481242Y427858D01*
X481450Y428067D01*
X481533Y428317D01*
X481450Y428567D01*
X481242Y428775D01*
X480867Y428900D01*
X480492Y428858D01*
X480117Y428692D01*
G01X495600Y428900D02*
Y426400D01*
G01X494642Y428900D02*
X496558D01*
G01X497867Y426400D02*
Y428900D01*
X498867D01*
X499200Y428775D01*
X499450Y428483D01*
X499533Y428150D01*
X499450Y427817D01*
X499242Y427567D01*
X498867Y427442D01*
X497867D01*
G01X501800Y426400D02*
Y428900D01*
X501300Y428400D01*
G01Y426400D02*
X502300D01*
G01X504108Y427442D02*
X504400Y427733D01*
X504650Y427900D01*
X504983Y427983D01*
X505275Y427900D01*
X505483Y427733D01*
X505650Y427483D01*
X505692Y427192D01*
X505650Y426942D01*
X505483Y426692D01*
X505233Y426483D01*
X504942Y426400D01*
X504608Y426483D01*
X504317Y426733D01*
X504150Y427108D01*
X504108Y427525D01*
X504192Y428067D01*
X504317Y428358D01*
X504525Y428650D01*
X504817Y428858D01*
X505108Y428900D01*
X505400Y428817D01*
X505608Y428608D01*
G01X507917Y426400D02*
X508000Y426942D01*
X508125Y427400D01*
X508292Y427817D01*
X508500Y428275D01*
X508833Y428900D01*
X507167D01*
G01X495650Y444300D02*
Y441800D01*
G01X494692Y444300D02*
X496608D01*
G01X497917Y441800D02*
Y444300D01*
X498917D01*
X499250Y444175D01*
X499500Y443883D01*
X499583Y443550D01*
X499500Y443217D01*
X499292Y442967D01*
X498917Y442842D01*
X497917D01*
G01X501058Y443883D02*
X501308Y444133D01*
X501600Y444258D01*
X501933Y444300D01*
X502350Y444217D01*
X502642Y444008D01*
X502725Y443758D01*
X502683Y443508D01*
X502517Y443300D01*
X501683Y442883D01*
X501308Y442592D01*
X501058Y442175D01*
X500975Y441800D01*
X502725D01*
G01X504950D02*
Y444300D01*
X504450Y443800D01*
G01Y441800D02*
X505450D01*
G01X468350Y443800D02*
Y441300D01*
G01X467392Y443800D02*
X469308D01*
G01X470617Y441300D02*
Y443800D01*
X471617D01*
X471950Y443675D01*
X472200Y443383D01*
X472283Y443050D01*
X472200Y442717D01*
X471992Y442467D01*
X471617Y442342D01*
X470617D01*
G01X473758Y443383D02*
X474008Y443633D01*
X474300Y443758D01*
X474633Y443800D01*
X475050Y443717D01*
X475342Y443508D01*
X475425Y443258D01*
X475383Y443008D01*
X475217Y442800D01*
X474383Y442383D01*
X474008Y442092D01*
X473758Y441675D01*
X473675Y441300D01*
X475425D01*
G01X476858Y443383D02*
X477108Y443633D01*
X477400Y443758D01*
X477733Y443800D01*
X478150Y443717D01*
X478442Y443508D01*
X478525Y443258D01*
X478483Y443008D01*
X478317Y442800D01*
X477483Y442383D01*
X477108Y442092D01*
X476858Y441675D01*
X476775Y441300D01*
X478525D01*
G01X467850Y439000D02*
Y436500D01*
G01X466892Y439000D02*
X468808D01*
G01X470117Y436500D02*
Y439000D01*
X471117D01*
X471450Y438875D01*
X471700Y438583D01*
X471783Y438250D01*
X471700Y437917D01*
X471492Y437667D01*
X471117Y437542D01*
X470117D01*
G01X473258Y438583D02*
X473508Y438833D01*
X473800Y438958D01*
X474133Y439000D01*
X474550Y438917D01*
X474842Y438708D01*
X474925Y438458D01*
X474883Y438208D01*
X474717Y438000D01*
X473883Y437583D01*
X473508Y437292D01*
X473258Y436875D01*
X473175Y436500D01*
X474925D01*
G01X476233Y437000D02*
X476483Y436708D01*
X476817Y436542D01*
X477192Y436500D01*
X477525Y436542D01*
X477858Y436750D01*
X478067Y437000D01*
X478108Y437250D01*
X478025Y437542D01*
X477733Y437750D01*
X477442Y437833D01*
X477067D01*
G01X477442D02*
X477692Y437958D01*
X477900Y438167D01*
X477983Y438417D01*
X477900Y438667D01*
X477692Y438875D01*
X477317Y439000D01*
X476942Y438958D01*
X476567Y438792D01*
G01X495650Y439000D02*
Y436500D01*
G01X494692Y439000D02*
X496608D01*
G01X497917Y436500D02*
Y439000D01*
X498917D01*
X499250Y438875D01*
X499500Y438583D01*
X499583Y438250D01*
X499500Y437917D01*
X499292Y437667D01*
X498917Y437542D01*
X497917D01*
G01X501058Y438583D02*
X501308Y438833D01*
X501600Y438958D01*
X501933Y439000D01*
X502350Y438917D01*
X502642Y438708D01*
X502725Y438458D01*
X502683Y438208D01*
X502517Y438000D01*
X501683Y437583D01*
X501308Y437292D01*
X501058Y436875D01*
X500975Y436500D01*
X502725D01*
G01X505450D02*
Y439000D01*
X503908Y437208D01*
X505992D01*
G01X569767Y178292D02*
X569517Y178417D01*
X569225Y178500D01*
X568892D01*
X568517Y178375D01*
X568225Y178167D01*
X568017Y177917D01*
X567850Y177500D01*
X567808Y177125D01*
X567892Y176750D01*
X568017Y176500D01*
X568267Y176250D01*
X568558Y176083D01*
X568850Y176000D01*
X569142D01*
X569433Y176083D01*
X569683Y176208D01*
X569892Y176375D01*
G01X571033Y176500D02*
X571283Y176208D01*
X571617Y176042D01*
X571992Y176000D01*
X572325Y176042D01*
X572658Y176250D01*
X572867Y176500D01*
X572908Y176750D01*
X572825Y177042D01*
X572533Y177250D01*
X572242Y177333D01*
X571867D01*
G01X572242D02*
X572492Y177458D01*
X572700Y177667D01*
X572783Y177917D01*
X572700Y178167D01*
X572492Y178375D01*
X572117Y178500D01*
X571742Y178458D01*
X571367Y178292D01*
G01X574133Y176500D02*
X574383Y176208D01*
X574717Y176042D01*
X575092Y176000D01*
X575425Y176042D01*
X575758Y176250D01*
X575967Y176500D01*
X576008Y176750D01*
X575925Y177042D01*
X575633Y177250D01*
X575342Y177333D01*
X574967D01*
G01X575342D02*
X575592Y177458D01*
X575800Y177667D01*
X575883Y177917D01*
X575800Y178167D01*
X575592Y178375D01*
X575217Y178500D01*
X574842Y178458D01*
X574467Y178292D01*
G01X578067Y176000D02*
X578150Y176542D01*
X578275Y177000D01*
X578442Y177417D01*
X578650Y177875D01*
X578983Y178500D01*
X577317D01*
G01X574715Y155982D02*
X574465Y156107D01*
X574173Y156190D01*
X573840D01*
X573465Y156065D01*
X573173Y155857D01*
X572965Y155607D01*
X572798Y155190D01*
X572756Y154815D01*
X572840Y154440D01*
X572965Y154190D01*
X573215Y153940D01*
X573506Y153773D01*
X573798Y153690D01*
X574090D01*
X574381Y153773D01*
X574631Y153898D01*
X574840Y154065D01*
G01X575981Y154190D02*
X576231Y153898D01*
X576565Y153732D01*
X576940Y153690D01*
X577273Y153732D01*
X577606Y153940D01*
X577815Y154190D01*
X577856Y154440D01*
X577773Y154732D01*
X577481Y154940D01*
X577190Y155023D01*
X576815D01*
G01X577190D02*
X577440Y155148D01*
X577648Y155357D01*
X577731Y155607D01*
X577648Y155857D01*
X577440Y156065D01*
X577065Y156190D01*
X576690Y156148D01*
X576315Y155982D01*
G01X579081Y154190D02*
X579331Y153898D01*
X579665Y153732D01*
X580040Y153690D01*
X580373Y153732D01*
X580706Y153940D01*
X580915Y154190D01*
X580956Y154440D01*
X580873Y154732D01*
X580581Y154940D01*
X580290Y155023D01*
X579915D01*
G01X580290D02*
X580540Y155148D01*
X580748Y155357D01*
X580831Y155607D01*
X580748Y155857D01*
X580540Y156065D01*
X580165Y156190D01*
X579790Y156148D01*
X579415Y155982D01*
G01X582306Y154732D02*
X582598Y155023D01*
X582848Y155190D01*
X583181Y155273D01*
X583473Y155190D01*
X583681Y155023D01*
X583848Y154773D01*
X583890Y154482D01*
X583848Y154232D01*
X583681Y153982D01*
X583431Y153773D01*
X583140Y153690D01*
X582806Y153773D01*
X582515Y154023D01*
X582348Y154398D01*
X582306Y154815D01*
X582390Y155357D01*
X582515Y155648D01*
X582723Y155940D01*
X583015Y156148D01*
X583306Y156190D01*
X583598Y156107D01*
X583806Y155898D01*
G01X572215Y165982D02*
X571965Y166107D01*
X571673Y166190D01*
X571340D01*
X570965Y166065D01*
X570673Y165857D01*
X570465Y165607D01*
X570298Y165190D01*
X570256Y164815D01*
X570340Y164440D01*
X570465Y164190D01*
X570715Y163940D01*
X571006Y163773D01*
X571298Y163690D01*
X571590D01*
X571881Y163773D01*
X572131Y163898D01*
X572340Y164065D01*
G01X573481Y164190D02*
X573731Y163898D01*
X574065Y163732D01*
X574440Y163690D01*
X574773Y163732D01*
X575106Y163940D01*
X575315Y164190D01*
X575356Y164440D01*
X575273Y164732D01*
X574981Y164940D01*
X574690Y165023D01*
X574315D01*
G01X574690D02*
X574940Y165148D01*
X575148Y165357D01*
X575231Y165607D01*
X575148Y165857D01*
X574940Y166065D01*
X574565Y166190D01*
X574190Y166148D01*
X573815Y165982D01*
G01X576581Y164190D02*
X576831Y163898D01*
X577165Y163732D01*
X577540Y163690D01*
X577873Y163732D01*
X578206Y163940D01*
X578415Y164190D01*
X578456Y164440D01*
X578373Y164732D01*
X578081Y164940D01*
X577790Y165023D01*
X577415D01*
G01X577790D02*
X578040Y165148D01*
X578248Y165357D01*
X578331Y165607D01*
X578248Y165857D01*
X578040Y166065D01*
X577665Y166190D01*
X577290Y166148D01*
X576915Y165982D01*
G01X579681Y164190D02*
X579931Y163898D01*
X580265Y163732D01*
X580640Y163690D01*
X580973Y163732D01*
X581306Y163940D01*
X581515Y164190D01*
X581556Y164440D01*
X581473Y164732D01*
X581181Y164940D01*
X580890Y165023D01*
X580515D01*
G01X580890D02*
X581140Y165148D01*
X581348Y165357D01*
X581431Y165607D01*
X581348Y165857D01*
X581140Y166065D01*
X580765Y166190D01*
X580390Y166148D01*
X580015Y165982D01*
G01X566167Y120692D02*
X565917Y120817D01*
X565625Y120900D01*
X565292D01*
X564917Y120775D01*
X564625Y120567D01*
X564417Y120317D01*
X564250Y119900D01*
X564208Y119525D01*
X564292Y119150D01*
X564417Y118900D01*
X564667Y118650D01*
X564958Y118483D01*
X565250Y118400D01*
X565542D01*
X565833Y118483D01*
X566083Y118608D01*
X566292Y118775D01*
G01X567433Y118900D02*
X567683Y118608D01*
X568017Y118442D01*
X568392Y118400D01*
X568725Y118442D01*
X569058Y118650D01*
X569267Y118900D01*
X569308Y119150D01*
X569225Y119442D01*
X568933Y119650D01*
X568642Y119733D01*
X568267D01*
G01X568642D02*
X568892Y119858D01*
X569100Y120067D01*
X569183Y120317D01*
X569100Y120567D01*
X568892Y120775D01*
X568517Y120900D01*
X568142Y120858D01*
X567767Y120692D01*
G01X570658Y120483D02*
X570908Y120733D01*
X571200Y120858D01*
X571533Y120900D01*
X571950Y120817D01*
X572242Y120608D01*
X572325Y120358D01*
X572283Y120108D01*
X572117Y119900D01*
X571283Y119483D01*
X570908Y119192D01*
X570658Y118775D01*
X570575Y118400D01*
X572325D01*
G01X574550D02*
X574842Y118442D01*
X575175Y118567D01*
X575383Y118775D01*
X575467Y119067D01*
X575383Y119358D01*
X575133Y119608D01*
X574758Y119733D01*
X574342D01*
X574092Y119817D01*
X573883Y120025D01*
X573800Y120317D01*
X573925Y120608D01*
X574217Y120817D01*
X574550Y120900D01*
X574883Y120817D01*
X575175Y120608D01*
X575300Y120317D01*
X575217Y120025D01*
X575008Y119817D01*
X574758Y119733D01*
X574342D01*
X573967Y119608D01*
X573717Y119358D01*
X573633Y119067D01*
X573717Y118775D01*
X573925Y118567D01*
X574258Y118442D01*
X574550Y118400D01*
G01X566167Y124692D02*
X565917Y124817D01*
X565625Y124900D01*
X565292D01*
X564917Y124775D01*
X564625Y124567D01*
X564417Y124317D01*
X564250Y123900D01*
X564208Y123525D01*
X564292Y123150D01*
X564417Y122900D01*
X564667Y122650D01*
X564958Y122483D01*
X565250Y122400D01*
X565542D01*
X565833Y122483D01*
X566083Y122608D01*
X566292Y122775D01*
G01X567433Y122900D02*
X567683Y122608D01*
X568017Y122442D01*
X568392Y122400D01*
X568725Y122442D01*
X569058Y122650D01*
X569267Y122900D01*
X569308Y123150D01*
X569225Y123442D01*
X568933Y123650D01*
X568642Y123733D01*
X568267D01*
G01X568642D02*
X568892Y123858D01*
X569100Y124067D01*
X569183Y124317D01*
X569100Y124567D01*
X568892Y124775D01*
X568517Y124900D01*
X568142Y124858D01*
X567767Y124692D01*
G01X570658Y124483D02*
X570908Y124733D01*
X571200Y124858D01*
X571533Y124900D01*
X571950Y124817D01*
X572242Y124608D01*
X572325Y124358D01*
X572283Y124108D01*
X572117Y123900D01*
X571283Y123483D01*
X570908Y123192D01*
X570658Y122775D01*
X570575Y122400D01*
X572325D01*
G01X574467D02*
X574550Y122942D01*
X574675Y123400D01*
X574842Y123817D01*
X575050Y124275D01*
X575383Y124900D01*
X573717D01*
G01X574267Y220292D02*
X574017Y220417D01*
X573725Y220500D01*
X573392D01*
X573017Y220375D01*
X572725Y220167D01*
X572517Y219917D01*
X572350Y219500D01*
X572308Y219125D01*
X572392Y218750D01*
X572517Y218500D01*
X572767Y218250D01*
X573058Y218083D01*
X573350Y218000D01*
X573642D01*
X573933Y218083D01*
X574183Y218208D01*
X574392Y218375D01*
G01X575533Y218500D02*
X575783Y218208D01*
X576117Y218042D01*
X576492Y218000D01*
X576825Y218042D01*
X577158Y218250D01*
X577367Y218500D01*
X577408Y218750D01*
X577325Y219042D01*
X577033Y219250D01*
X576742Y219333D01*
X576367D01*
G01X576742D02*
X576992Y219458D01*
X577200Y219667D01*
X577283Y219917D01*
X577200Y220167D01*
X576992Y220375D01*
X576617Y220500D01*
X576242Y220458D01*
X575867Y220292D01*
G01X580050Y218000D02*
Y220500D01*
X578508Y218708D01*
X580592D01*
G01X583150Y218000D02*
Y220500D01*
X581608Y218708D01*
X583692D01*
G01X574267Y224292D02*
X574017Y224417D01*
X573725Y224500D01*
X573392D01*
X573017Y224375D01*
X572725Y224167D01*
X572517Y223917D01*
X572350Y223500D01*
X572308Y223125D01*
X572392Y222750D01*
X572517Y222500D01*
X572767Y222250D01*
X573058Y222083D01*
X573350Y222000D01*
X573642D01*
X573933Y222083D01*
X574183Y222208D01*
X574392Y222375D01*
G01X575533Y222500D02*
X575783Y222208D01*
X576117Y222042D01*
X576492Y222000D01*
X576825Y222042D01*
X577158Y222250D01*
X577367Y222500D01*
X577408Y222750D01*
X577325Y223042D01*
X577033Y223250D01*
X576742Y223333D01*
X576367D01*
G01X576742D02*
X576992Y223458D01*
X577200Y223667D01*
X577283Y223917D01*
X577200Y224167D01*
X576992Y224375D01*
X576617Y224500D01*
X576242Y224458D01*
X575867Y224292D01*
G01X580050Y222000D02*
Y224500D01*
X578508Y222708D01*
X580592D01*
G01X581733Y222500D02*
X581983Y222208D01*
X582317Y222042D01*
X582692Y222000D01*
X583025Y222042D01*
X583358Y222250D01*
X583567Y222500D01*
X583608Y222750D01*
X583525Y223042D01*
X583233Y223250D01*
X582942Y223333D01*
X582567D01*
G01X582942D02*
X583192Y223458D01*
X583400Y223667D01*
X583483Y223917D01*
X583400Y224167D01*
X583192Y224375D01*
X582817Y224500D01*
X582442Y224458D01*
X582067Y224292D01*
G01X571117Y205342D02*
X570867Y205467D01*
X570575Y205550D01*
X570242D01*
X569867Y205425D01*
X569575Y205217D01*
X569367Y204967D01*
X569200Y204550D01*
X569158Y204175D01*
X569242Y203800D01*
X569367Y203550D01*
X569617Y203300D01*
X569908Y203133D01*
X570200Y203050D01*
X570492D01*
X570783Y203133D01*
X571033Y203258D01*
X571242Y203425D01*
G01X572383Y203550D02*
X572633Y203258D01*
X572967Y203092D01*
X573342Y203050D01*
X573675Y203092D01*
X574008Y203300D01*
X574217Y203550D01*
X574258Y203800D01*
X574175Y204092D01*
X573883Y204300D01*
X573592Y204383D01*
X573217D01*
G01X573592D02*
X573842Y204508D01*
X574050Y204717D01*
X574133Y204967D01*
X574050Y205217D01*
X573842Y205425D01*
X573467Y205550D01*
X573092Y205508D01*
X572717Y205342D01*
G01X576900Y203050D02*
Y205550D01*
X575358Y203758D01*
X577442D01*
G01X578708Y205133D02*
X578958Y205383D01*
X579250Y205508D01*
X579583Y205550D01*
X580000Y205467D01*
X580292Y205258D01*
X580375Y205008D01*
X580333Y204758D01*
X580167Y204550D01*
X579333Y204133D01*
X578958Y203842D01*
X578708Y203425D01*
X578625Y203050D01*
X580375D01*
G01X571117Y209842D02*
X570867Y209967D01*
X570575Y210050D01*
X570242D01*
X569867Y209925D01*
X569575Y209717D01*
X569367Y209467D01*
X569200Y209050D01*
X569158Y208675D01*
X569242Y208300D01*
X569367Y208050D01*
X569617Y207800D01*
X569908Y207633D01*
X570200Y207550D01*
X570492D01*
X570783Y207633D01*
X571033Y207758D01*
X571242Y207925D01*
G01X572383Y208050D02*
X572633Y207758D01*
X572967Y207592D01*
X573342Y207550D01*
X573675Y207592D01*
X574008Y207800D01*
X574217Y208050D01*
X574258Y208300D01*
X574175Y208592D01*
X573883Y208800D01*
X573592Y208883D01*
X573217D01*
G01X573592D02*
X573842Y209008D01*
X574050Y209217D01*
X574133Y209467D01*
X574050Y209717D01*
X573842Y209925D01*
X573467Y210050D01*
X573092Y210008D01*
X572717Y209842D01*
G01X576900Y207550D02*
Y210050D01*
X575358Y208258D01*
X577442D01*
G01X579500Y207550D02*
Y210050D01*
X579000Y209550D01*
G01Y207550D02*
X580000D01*
G01X567267Y189692D02*
X567017Y189817D01*
X566725Y189900D01*
X566392D01*
X566017Y189775D01*
X565725Y189567D01*
X565517Y189317D01*
X565350Y188900D01*
X565308Y188525D01*
X565392Y188150D01*
X565517Y187900D01*
X565767Y187650D01*
X566058Y187483D01*
X566350Y187400D01*
X566642D01*
X566933Y187483D01*
X567183Y187608D01*
X567392Y187775D01*
G01X568533Y187900D02*
X568783Y187608D01*
X569117Y187442D01*
X569492Y187400D01*
X569825Y187442D01*
X570158Y187650D01*
X570367Y187900D01*
X570408Y188150D01*
X570325Y188442D01*
X570033Y188650D01*
X569742Y188733D01*
X569367D01*
G01X569742D02*
X569992Y188858D01*
X570200Y189067D01*
X570283Y189317D01*
X570200Y189567D01*
X569992Y189775D01*
X569617Y189900D01*
X569242Y189858D01*
X568867Y189692D01*
G01X573050Y187400D02*
Y189900D01*
X571508Y188108D01*
X573592D01*
G01X575650Y189900D02*
X575317Y189817D01*
X575067Y189608D01*
X574900Y189358D01*
X574775Y189025D01*
X574733Y188650D01*
X574775Y188275D01*
X574900Y187942D01*
X575067Y187692D01*
X575317Y187483D01*
X575650Y187400D01*
X575983Y187483D01*
X576233Y187692D01*
X576400Y187942D01*
X576525Y188275D01*
X576567Y188650D01*
X576525Y189025D01*
X576400Y189358D01*
X576233Y189608D01*
X575983Y189817D01*
X575650Y189900D01*
G01X567267Y193692D02*
X567017Y193817D01*
X566725Y193900D01*
X566392D01*
X566017Y193775D01*
X565725Y193567D01*
X565517Y193317D01*
X565350Y192900D01*
X565308Y192525D01*
X565392Y192150D01*
X565517Y191900D01*
X565767Y191650D01*
X566058Y191483D01*
X566350Y191400D01*
X566642D01*
X566933Y191483D01*
X567183Y191608D01*
X567392Y191775D01*
G01X568533Y191900D02*
X568783Y191608D01*
X569117Y191442D01*
X569492Y191400D01*
X569825Y191442D01*
X570158Y191650D01*
X570367Y191900D01*
X570408Y192150D01*
X570325Y192442D01*
X570033Y192650D01*
X569742Y192733D01*
X569367D01*
G01X569742D02*
X569992Y192858D01*
X570200Y193067D01*
X570283Y193317D01*
X570200Y193567D01*
X569992Y193775D01*
X569617Y193900D01*
X569242Y193858D01*
X568867Y193692D01*
G01X571633Y191900D02*
X571883Y191608D01*
X572217Y191442D01*
X572592Y191400D01*
X572925Y191442D01*
X573258Y191650D01*
X573467Y191900D01*
X573508Y192150D01*
X573425Y192442D01*
X573133Y192650D01*
X572842Y192733D01*
X572467D01*
G01X572842D02*
X573092Y192858D01*
X573300Y193067D01*
X573383Y193317D01*
X573300Y193567D01*
X573092Y193775D01*
X572717Y193900D01*
X572342Y193858D01*
X571967Y193692D01*
G01X574942Y191692D02*
X575233Y191483D01*
X575567Y191400D01*
X575900Y191483D01*
X576192Y191733D01*
X576400Y192108D01*
X576483Y192483D01*
Y192942D01*
X576400Y193317D01*
X576192Y193650D01*
X575942Y193817D01*
X575650Y193900D01*
X575317Y193817D01*
X575067Y193650D01*
X574900Y193400D01*
X574817Y193067D01*
X574900Y192775D01*
X575108Y192483D01*
X575358Y192317D01*
X575650Y192275D01*
X575983Y192358D01*
X576233Y192567D01*
X576483Y192942D01*
G01X517717Y200669D02*
Y206812D01*
G01Y317048D02*
Y210512D01*
G01X519567Y198819D02*
G02I-1850J0D01*
G01Y208662D02*
G02I-1850J0D01*
G01X560569Y262592D02*
X560319Y262717D01*
X560027Y262800D01*
X559694D01*
X559319Y262675D01*
X559027Y262467D01*
X558819Y262217D01*
X558652Y261800D01*
X558610Y261425D01*
X558694Y261050D01*
X558819Y260800D01*
X559069Y260550D01*
X559360Y260383D01*
X559652Y260300D01*
X559944D01*
X560235Y260383D01*
X560485Y260508D01*
X560694Y260675D01*
G01X563252Y260300D02*
Y262800D01*
X561710Y261008D01*
X563794D01*
G01X565852Y262800D02*
X565519Y262717D01*
X565269Y262508D01*
X565102Y262258D01*
X564977Y261925D01*
X564935Y261550D01*
X564977Y261175D01*
X565102Y260842D01*
X565269Y260592D01*
X565519Y260383D01*
X565852Y260300D01*
X566185Y260383D01*
X566435Y260592D01*
X566602Y260842D01*
X566727Y261175D01*
X566769Y261550D01*
X566727Y261925D01*
X566602Y262258D01*
X566435Y262508D01*
X566185Y262717D01*
X565852Y262800D01*
G01X560604Y258542D02*
X560354Y258667D01*
X560062Y258750D01*
X559729D01*
X559354Y258625D01*
X559062Y258417D01*
X558854Y258167D01*
X558687Y257750D01*
X558645Y257375D01*
X558729Y257000D01*
X558854Y256750D01*
X559104Y256500D01*
X559395Y256333D01*
X559687Y256250D01*
X559979D01*
X560270Y256333D01*
X560520Y256458D01*
X560729Y256625D01*
G01X561870Y256750D02*
X562120Y256458D01*
X562454Y256292D01*
X562829Y256250D01*
X563162Y256292D01*
X563495Y256500D01*
X563704Y256750D01*
X563745Y257000D01*
X563662Y257292D01*
X563370Y257500D01*
X563079Y257583D01*
X562704D01*
G01X563079D02*
X563329Y257708D01*
X563537Y257917D01*
X563620Y258167D01*
X563537Y258417D01*
X563329Y258625D01*
X562954Y258750D01*
X562579Y258708D01*
X562204Y258542D01*
G01X565179Y256542D02*
X565470Y256333D01*
X565804Y256250D01*
X566137Y256333D01*
X566429Y256583D01*
X566637Y256958D01*
X566720Y257333D01*
Y257792D01*
X566637Y258167D01*
X566429Y258500D01*
X566179Y258667D01*
X565887Y258750D01*
X565554Y258667D01*
X565304Y258500D01*
X565137Y258250D01*
X565054Y257917D01*
X565137Y257625D01*
X565345Y257333D01*
X565595Y257167D01*
X565887Y257125D01*
X566220Y257208D01*
X566470Y257417D01*
X566720Y257792D01*
G01X558969Y272580D02*
X558719Y272705D01*
X558427Y272788D01*
X558094D01*
X557719Y272663D01*
X557427Y272455D01*
X557219Y272205D01*
X557052Y271788D01*
X557010Y271413D01*
X557094Y271038D01*
X557219Y270788D01*
X557469Y270538D01*
X557760Y270371D01*
X558052Y270288D01*
X558344D01*
X558635Y270371D01*
X558885Y270496D01*
X559094Y270663D01*
G01X560235Y270788D02*
X560485Y270496D01*
X560819Y270330D01*
X561194Y270288D01*
X561527Y270330D01*
X561860Y270538D01*
X562069Y270788D01*
X562110Y271038D01*
X562027Y271330D01*
X561735Y271538D01*
X561444Y271621D01*
X561069D01*
G01X561444D02*
X561694Y271746D01*
X561902Y271955D01*
X561985Y272205D01*
X561902Y272455D01*
X561694Y272663D01*
X561319Y272788D01*
X560944Y272746D01*
X560569Y272580D01*
G01X564252Y270288D02*
X564544Y270330D01*
X564877Y270455D01*
X565085Y270663D01*
X565169Y270955D01*
X565085Y271246D01*
X564835Y271496D01*
X564460Y271621D01*
X564044D01*
X563794Y271705D01*
X563585Y271913D01*
X563502Y272205D01*
X563627Y272496D01*
X563919Y272705D01*
X564252Y272788D01*
X564585Y272705D01*
X564877Y272496D01*
X565002Y272205D01*
X564919Y271913D01*
X564710Y271705D01*
X564460Y271621D01*
X564044D01*
X563669Y271496D01*
X563419Y271246D01*
X563335Y270955D01*
X563419Y270663D01*
X563627Y270455D01*
X563960Y270330D01*
X564252Y270288D01*
G01X558969Y268580D02*
X558719Y268705D01*
X558427Y268788D01*
X558094D01*
X557719Y268663D01*
X557427Y268455D01*
X557219Y268205D01*
X557052Y267788D01*
X557010Y267413D01*
X557094Y267038D01*
X557219Y266788D01*
X557469Y266538D01*
X557760Y266371D01*
X558052Y266288D01*
X558344D01*
X558635Y266371D01*
X558885Y266496D01*
X559094Y266663D01*
G01X560235Y266788D02*
X560485Y266496D01*
X560819Y266330D01*
X561194Y266288D01*
X561527Y266330D01*
X561860Y266538D01*
X562069Y266788D01*
X562110Y267038D01*
X562027Y267330D01*
X561735Y267538D01*
X561444Y267621D01*
X561069D01*
G01X561444D02*
X561694Y267746D01*
X561902Y267955D01*
X561985Y268205D01*
X561902Y268455D01*
X561694Y268663D01*
X561319Y268788D01*
X560944Y268746D01*
X560569Y268580D01*
G01X564169Y266288D02*
X564252Y266830D01*
X564377Y267288D01*
X564544Y267705D01*
X564752Y268163D01*
X565085Y268788D01*
X563419D01*
G01X558079Y281951D02*
X557829Y282076D01*
X557537Y282159D01*
X557204D01*
X556829Y282034D01*
X556537Y281826D01*
X556329Y281576D01*
X556162Y281159D01*
X556120Y280784D01*
X556204Y280409D01*
X556329Y280159D01*
X556579Y279909D01*
X556870Y279742D01*
X557162Y279659D01*
X557454D01*
X557745Y279742D01*
X557995Y279867D01*
X558204Y280034D01*
G01X559345Y280159D02*
X559595Y279867D01*
X559929Y279701D01*
X560304Y279659D01*
X560637Y279701D01*
X560970Y279909D01*
X561179Y280159D01*
X561220Y280409D01*
X561137Y280701D01*
X560845Y280909D01*
X560554Y280992D01*
X560179D01*
G01X560554D02*
X560804Y281117D01*
X561012Y281326D01*
X561095Y281576D01*
X561012Y281826D01*
X560804Y282034D01*
X560429Y282159D01*
X560054Y282117D01*
X559679Y281951D01*
G01X562570Y280701D02*
X562862Y280992D01*
X563112Y281159D01*
X563445Y281242D01*
X563737Y281159D01*
X563945Y280992D01*
X564112Y280742D01*
X564154Y280451D01*
X564112Y280201D01*
X563945Y279951D01*
X563695Y279742D01*
X563404Y279659D01*
X563070Y279742D01*
X562779Y279992D01*
X562612Y280367D01*
X562570Y280784D01*
X562654Y281326D01*
X562779Y281617D01*
X562987Y281909D01*
X563279Y282117D01*
X563570Y282159D01*
X563862Y282076D01*
X564070Y281867D01*
G01X558044Y278101D02*
X557794Y278226D01*
X557502Y278309D01*
X557169D01*
X556794Y278184D01*
X556502Y277976D01*
X556294Y277726D01*
X556127Y277309D01*
X556085Y276934D01*
X556169Y276559D01*
X556294Y276309D01*
X556544Y276059D01*
X556835Y275892D01*
X557127Y275809D01*
X557419D01*
X557710Y275892D01*
X557960Y276017D01*
X558169Y276184D01*
G01X559310Y276309D02*
X559560Y276017D01*
X559894Y275851D01*
X560269Y275809D01*
X560602Y275851D01*
X560935Y276059D01*
X561144Y276309D01*
X561185Y276559D01*
X561102Y276851D01*
X560810Y277059D01*
X560519Y277142D01*
X560144D01*
G01X560519D02*
X560769Y277267D01*
X560977Y277476D01*
X561060Y277726D01*
X560977Y277976D01*
X560769Y278184D01*
X560394Y278309D01*
X560019Y278267D01*
X559644Y278101D01*
G01X562410Y276184D02*
X562660Y275976D01*
X562952Y275851D01*
X563327Y275809D01*
X563702Y275892D01*
X563994Y276059D01*
X564202Y276351D01*
X564244Y276684D01*
X564160Y277017D01*
X563952Y277226D01*
X563660Y277392D01*
X563369Y277434D01*
X563077Y277392D01*
X562702Y277226D01*
X562827Y278309D01*
X563952D01*
G01X559758Y291338D02*
X559508Y291463D01*
X559216Y291546D01*
X558883D01*
X558508Y291421D01*
X558216Y291213D01*
X558008Y290963D01*
X557841Y290546D01*
X557799Y290171D01*
X557883Y289796D01*
X558008Y289546D01*
X558258Y289296D01*
X558549Y289129D01*
X558841Y289046D01*
X559133D01*
X559424Y289129D01*
X559674Y289254D01*
X559883Y289421D01*
G01X561024Y289546D02*
X561274Y289254D01*
X561608Y289088D01*
X561983Y289046D01*
X562316Y289088D01*
X562649Y289296D01*
X562858Y289546D01*
X562899Y289796D01*
X562816Y290088D01*
X562524Y290296D01*
X562233Y290379D01*
X561858D01*
G01X562233D02*
X562483Y290504D01*
X562691Y290713D01*
X562774Y290963D01*
X562691Y291213D01*
X562483Y291421D01*
X562108Y291546D01*
X561733Y291504D01*
X561358Y291338D01*
G01X565541Y289046D02*
Y291546D01*
X563999Y289754D01*
X566083D01*
G01X559723Y287188D02*
X559473Y287313D01*
X559181Y287396D01*
X558848D01*
X558473Y287271D01*
X558181Y287063D01*
X557973Y286813D01*
X557806Y286396D01*
X557764Y286021D01*
X557848Y285646D01*
X557973Y285396D01*
X558223Y285146D01*
X558514Y284979D01*
X558806Y284896D01*
X559098D01*
X559389Y284979D01*
X559639Y285104D01*
X559848Y285271D01*
G01X560989Y285396D02*
X561239Y285104D01*
X561573Y284938D01*
X561948Y284896D01*
X562281Y284938D01*
X562614Y285146D01*
X562823Y285396D01*
X562864Y285646D01*
X562781Y285938D01*
X562489Y286146D01*
X562198Y286229D01*
X561823D01*
G01X562198D02*
X562448Y286354D01*
X562656Y286563D01*
X562739Y286813D01*
X562656Y287063D01*
X562448Y287271D01*
X562073Y287396D01*
X561698Y287354D01*
X561323Y287188D01*
G01X564089Y285396D02*
X564339Y285104D01*
X564673Y284938D01*
X565048Y284896D01*
X565381Y284938D01*
X565714Y285146D01*
X565923Y285396D01*
X565964Y285646D01*
X565881Y285938D01*
X565589Y286146D01*
X565298Y286229D01*
X564923D01*
G01X565298D02*
X565548Y286354D01*
X565756Y286563D01*
X565839Y286813D01*
X565756Y287063D01*
X565548Y287271D01*
X565173Y287396D01*
X564798Y287354D01*
X564423Y287188D01*
G01X533580Y267159D02*
X533330Y267284D01*
X533038Y267367D01*
X532705D01*
X532330Y267242D01*
X532038Y267034D01*
X531830Y266784D01*
X531663Y266367D01*
X531621Y265992D01*
X531705Y265617D01*
X531830Y265367D01*
X532080Y265117D01*
X532371Y264950D01*
X532663Y264867D01*
X532955D01*
X533246Y264950D01*
X533496Y265075D01*
X533705Y265242D01*
G01X534971Y265909D02*
X535263Y266200D01*
X535513Y266367D01*
X535846Y266450D01*
X536138Y266367D01*
X536346Y266200D01*
X536513Y265950D01*
X536555Y265659D01*
X536513Y265409D01*
X536346Y265159D01*
X536096Y264950D01*
X535805Y264867D01*
X535471Y264950D01*
X535180Y265200D01*
X535013Y265575D01*
X534971Y265992D01*
X535055Y266534D01*
X535180Y266825D01*
X535388Y267117D01*
X535680Y267325D01*
X535971Y267367D01*
X536263Y267284D01*
X536471Y267075D01*
G01X538863Y264867D02*
X539155Y264909D01*
X539488Y265034D01*
X539696Y265242D01*
X539780Y265534D01*
X539696Y265825D01*
X539446Y266075D01*
X539071Y266200D01*
X538655D01*
X538405Y266284D01*
X538196Y266492D01*
X538113Y266784D01*
X538238Y267075D01*
X538530Y267284D01*
X538863Y267367D01*
X539196Y267284D01*
X539488Y267075D01*
X539613Y266784D01*
X539530Y266492D01*
X539321Y266284D01*
X539071Y266200D01*
X538655D01*
X538280Y266075D01*
X538030Y265825D01*
X537946Y265534D01*
X538030Y265242D01*
X538238Y265034D01*
X538571Y264909D01*
X538863Y264867D01*
G01X541046Y265367D02*
X541296Y265075D01*
X541630Y264909D01*
X542005Y264867D01*
X542338Y264909D01*
X542671Y265117D01*
X542880Y265367D01*
X542921Y265617D01*
X542838Y265909D01*
X542546Y266117D01*
X542255Y266200D01*
X541880D01*
G01X542255D02*
X542505Y266325D01*
X542713Y266534D01*
X542796Y266784D01*
X542713Y267034D01*
X542505Y267242D01*
X542130Y267367D01*
X541755Y267325D01*
X541380Y267159D01*
G01X533580Y263159D02*
X533330Y263284D01*
X533038Y263367D01*
X532705D01*
X532330Y263242D01*
X532038Y263034D01*
X531830Y262784D01*
X531663Y262367D01*
X531621Y261992D01*
X531705Y261617D01*
X531830Y261367D01*
X532080Y261117D01*
X532371Y260950D01*
X532663Y260867D01*
X532955D01*
X533246Y260950D01*
X533496Y261075D01*
X533705Y261242D01*
G01X534971Y261909D02*
X535263Y262200D01*
X535513Y262367D01*
X535846Y262450D01*
X536138Y262367D01*
X536346Y262200D01*
X536513Y261950D01*
X536555Y261659D01*
X536513Y261409D01*
X536346Y261159D01*
X536096Y260950D01*
X535805Y260867D01*
X535471Y260950D01*
X535180Y261200D01*
X535013Y261575D01*
X534971Y261992D01*
X535055Y262534D01*
X535180Y262825D01*
X535388Y263117D01*
X535680Y263325D01*
X535971Y263367D01*
X536263Y263284D01*
X536471Y263075D01*
G01X538863Y260867D02*
X539155Y260909D01*
X539488Y261034D01*
X539696Y261242D01*
X539780Y261534D01*
X539696Y261825D01*
X539446Y262075D01*
X539071Y262200D01*
X538655D01*
X538405Y262284D01*
X538196Y262492D01*
X538113Y262784D01*
X538238Y263075D01*
X538530Y263284D01*
X538863Y263367D01*
X539196Y263284D01*
X539488Y263075D01*
X539613Y262784D01*
X539530Y262492D01*
X539321Y262284D01*
X539071Y262200D01*
X538655D01*
X538280Y262075D01*
X538030Y261825D01*
X537946Y261534D01*
X538030Y261242D01*
X538238Y261034D01*
X538571Y260909D01*
X538863Y260867D01*
G01X541171Y262950D02*
X541421Y263200D01*
X541713Y263325D01*
X542046Y263367D01*
X542463Y263284D01*
X542755Y263075D01*
X542838Y262825D01*
X542796Y262575D01*
X542630Y262367D01*
X541796Y261950D01*
X541421Y261659D01*
X541171Y261242D01*
X541088Y260867D01*
X542838D01*
G01X533215Y276700D02*
X532965Y276825D01*
X532673Y276908D01*
X532340D01*
X531965Y276783D01*
X531673Y276575D01*
X531465Y276325D01*
X531298Y275908D01*
X531256Y275533D01*
X531340Y275158D01*
X531465Y274908D01*
X531715Y274658D01*
X532006Y274491D01*
X532298Y274408D01*
X532590D01*
X532881Y274491D01*
X533131Y274616D01*
X533340Y274783D01*
G01X534606Y275450D02*
X534898Y275741D01*
X535148Y275908D01*
X535481Y275991D01*
X535773Y275908D01*
X535981Y275741D01*
X536148Y275491D01*
X536190Y275200D01*
X536148Y274950D01*
X535981Y274700D01*
X535731Y274491D01*
X535440Y274408D01*
X535106Y274491D01*
X534815Y274741D01*
X534648Y275116D01*
X534606Y275533D01*
X534690Y276075D01*
X534815Y276366D01*
X535023Y276658D01*
X535315Y276866D01*
X535606Y276908D01*
X535898Y276825D01*
X536106Y276616D01*
G01X538498Y274408D02*
X538790Y274450D01*
X539123Y274575D01*
X539331Y274783D01*
X539415Y275075D01*
X539331Y275366D01*
X539081Y275616D01*
X538706Y275741D01*
X538290D01*
X538040Y275825D01*
X537831Y276033D01*
X537748Y276325D01*
X537873Y276616D01*
X538165Y276825D01*
X538498Y276908D01*
X538831Y276825D01*
X539123Y276616D01*
X539248Y276325D01*
X539165Y276033D01*
X538956Y275825D01*
X538706Y275741D01*
X538290D01*
X537915Y275616D01*
X537665Y275366D01*
X537581Y275075D01*
X537665Y274783D01*
X537873Y274575D01*
X538206Y274450D01*
X538498Y274408D01*
G01X541598D02*
Y276908D01*
X541098Y276408D01*
G01Y274408D02*
X542098D01*
G01X533215Y272700D02*
X532965Y272825D01*
X532673Y272908D01*
X532340D01*
X531965Y272783D01*
X531673Y272575D01*
X531465Y272325D01*
X531298Y271908D01*
X531256Y271533D01*
X531340Y271158D01*
X531465Y270908D01*
X531715Y270658D01*
X532006Y270491D01*
X532298Y270408D01*
X532590D01*
X532881Y270491D01*
X533131Y270616D01*
X533340Y270783D01*
G01X534606Y271450D02*
X534898Y271741D01*
X535148Y271908D01*
X535481Y271991D01*
X535773Y271908D01*
X535981Y271741D01*
X536148Y271491D01*
X536190Y271200D01*
X536148Y270950D01*
X535981Y270700D01*
X535731Y270491D01*
X535440Y270408D01*
X535106Y270491D01*
X534815Y270741D01*
X534648Y271116D01*
X534606Y271533D01*
X534690Y272075D01*
X534815Y272366D01*
X535023Y272658D01*
X535315Y272866D01*
X535606Y272908D01*
X535898Y272825D01*
X536106Y272616D01*
G01X538498Y270408D02*
X538790Y270450D01*
X539123Y270575D01*
X539331Y270783D01*
X539415Y271075D01*
X539331Y271366D01*
X539081Y271616D01*
X538706Y271741D01*
X538290D01*
X538040Y271825D01*
X537831Y272033D01*
X537748Y272325D01*
X537873Y272616D01*
X538165Y272825D01*
X538498Y272908D01*
X538831Y272825D01*
X539123Y272616D01*
X539248Y272325D01*
X539165Y272033D01*
X538956Y271825D01*
X538706Y271741D01*
X538290D01*
X537915Y271616D01*
X537665Y271366D01*
X537581Y271075D01*
X537665Y270783D01*
X537873Y270575D01*
X538206Y270450D01*
X538498Y270408D01*
G01X541598Y272908D02*
X541265Y272825D01*
X541015Y272616D01*
X540848Y272366D01*
X540723Y272033D01*
X540681Y271658D01*
X540723Y271283D01*
X540848Y270950D01*
X541015Y270700D01*
X541265Y270491D01*
X541598Y270408D01*
X541931Y270491D01*
X542181Y270700D01*
X542348Y270950D01*
X542473Y271283D01*
X542515Y271658D01*
X542473Y272033D01*
X542348Y272366D01*
X542181Y272616D01*
X541931Y272825D01*
X541598Y272908D01*
G01X533795Y282317D02*
X533545Y282442D01*
X533253Y282525D01*
X532920D01*
X532545Y282400D01*
X532253Y282192D01*
X532045Y281942D01*
X531878Y281525D01*
X531836Y281150D01*
X531920Y280775D01*
X532045Y280525D01*
X532295Y280275D01*
X532586Y280108D01*
X532878Y280025D01*
X533170D01*
X533461Y280108D01*
X533711Y280233D01*
X533920Y280400D01*
G01X535186Y281067D02*
X535478Y281358D01*
X535728Y281525D01*
X536061Y281608D01*
X536353Y281525D01*
X536561Y281358D01*
X536728Y281108D01*
X536770Y280817D01*
X536728Y280567D01*
X536561Y280317D01*
X536311Y280108D01*
X536020Y280025D01*
X535686Y280108D01*
X535395Y280358D01*
X535228Y280733D01*
X535186Y281150D01*
X535270Y281692D01*
X535395Y281983D01*
X535603Y282275D01*
X535895Y282483D01*
X536186Y282525D01*
X536478Y282442D01*
X536686Y282233D01*
G01X538995Y280025D02*
X539078Y280567D01*
X539203Y281025D01*
X539370Y281442D01*
X539578Y281900D01*
X539911Y282525D01*
X538245D01*
G01X542178Y280025D02*
X542470Y280067D01*
X542803Y280192D01*
X543011Y280400D01*
X543095Y280692D01*
X543011Y280983D01*
X542761Y281233D01*
X542386Y281358D01*
X541970D01*
X541720Y281442D01*
X541511Y281650D01*
X541428Y281942D01*
X541553Y282233D01*
X541845Y282442D01*
X542178Y282525D01*
X542511Y282442D01*
X542803Y282233D01*
X542928Y281942D01*
X542845Y281650D01*
X542636Y281442D01*
X542386Y281358D01*
X541970D01*
X541595Y281233D01*
X541345Y280983D01*
X541261Y280692D01*
X541345Y280400D01*
X541553Y280192D01*
X541886Y280067D01*
X542178Y280025D01*
G01X533767Y294279D02*
X533517Y294404D01*
X533225Y294487D01*
X532892D01*
X532517Y294362D01*
X532225Y294154D01*
X532017Y293904D01*
X531850Y293487D01*
X531808Y293112D01*
X531892Y292737D01*
X532017Y292487D01*
X532267Y292237D01*
X532558Y292070D01*
X532850Y291987D01*
X533142D01*
X533433Y292070D01*
X533683Y292195D01*
X533892Y292362D01*
G01X535158Y293029D02*
X535450Y293320D01*
X535700Y293487D01*
X536033Y293570D01*
X536325Y293487D01*
X536533Y293320D01*
X536700Y293070D01*
X536742Y292779D01*
X536700Y292529D01*
X536533Y292279D01*
X536283Y292070D01*
X535992Y291987D01*
X535658Y292070D01*
X535367Y292320D01*
X535200Y292695D01*
X535158Y293112D01*
X535242Y293654D01*
X535367Y293945D01*
X535575Y294237D01*
X535867Y294445D01*
X536158Y294487D01*
X536450Y294404D01*
X536658Y294195D01*
G01X538967Y291987D02*
X539050Y292529D01*
X539175Y292987D01*
X539342Y293404D01*
X539550Y293862D01*
X539883Y294487D01*
X538217D01*
G01X542067Y291987D02*
X542150Y292529D01*
X542275Y292987D01*
X542442Y293404D01*
X542650Y293862D01*
X542983Y294487D01*
X541317D01*
G01X533795Y286317D02*
X533545Y286442D01*
X533253Y286525D01*
X532920D01*
X532545Y286400D01*
X532253Y286192D01*
X532045Y285942D01*
X531878Y285525D01*
X531836Y285150D01*
X531920Y284775D01*
X532045Y284525D01*
X532295Y284275D01*
X532586Y284108D01*
X532878Y284025D01*
X533170D01*
X533461Y284108D01*
X533711Y284233D01*
X533920Y284400D01*
G01X535186Y285067D02*
X535478Y285358D01*
X535728Y285525D01*
X536061Y285608D01*
X536353Y285525D01*
X536561Y285358D01*
X536728Y285108D01*
X536770Y284817D01*
X536728Y284567D01*
X536561Y284317D01*
X536311Y284108D01*
X536020Y284025D01*
X535686Y284108D01*
X535395Y284358D01*
X535228Y284733D01*
X535186Y285150D01*
X535270Y285692D01*
X535395Y285983D01*
X535603Y286275D01*
X535895Y286483D01*
X536186Y286525D01*
X536478Y286442D01*
X536686Y286233D01*
G01X538995Y284025D02*
X539078Y284567D01*
X539203Y285025D01*
X539370Y285442D01*
X539578Y285900D01*
X539911Y286525D01*
X538245D01*
G01X541470Y284317D02*
X541761Y284108D01*
X542095Y284025D01*
X542428Y284108D01*
X542720Y284358D01*
X542928Y284733D01*
X543011Y285108D01*
Y285567D01*
X542928Y285942D01*
X542720Y286275D01*
X542470Y286442D01*
X542178Y286525D01*
X541845Y286442D01*
X541595Y286275D01*
X541428Y286025D01*
X541345Y285692D01*
X541428Y285400D01*
X541636Y285108D01*
X541886Y284942D01*
X542178Y284900D01*
X542511Y284983D01*
X542761Y285192D01*
X543011Y285567D01*
G01X533767Y290279D02*
X533517Y290404D01*
X533225Y290487D01*
X532892D01*
X532517Y290362D01*
X532225Y290154D01*
X532017Y289904D01*
X531850Y289487D01*
X531808Y289112D01*
X531892Y288737D01*
X532017Y288487D01*
X532267Y288237D01*
X532558Y288070D01*
X532850Y287987D01*
X533142D01*
X533433Y288070D01*
X533683Y288195D01*
X533892Y288362D01*
G01X535158Y289029D02*
X535450Y289320D01*
X535700Y289487D01*
X536033Y289570D01*
X536325Y289487D01*
X536533Y289320D01*
X536700Y289070D01*
X536742Y288779D01*
X536700Y288529D01*
X536533Y288279D01*
X536283Y288070D01*
X535992Y287987D01*
X535658Y288070D01*
X535367Y288320D01*
X535200Y288695D01*
X535158Y289112D01*
X535242Y289654D01*
X535367Y289945D01*
X535575Y290237D01*
X535867Y290445D01*
X536158Y290487D01*
X536450Y290404D01*
X536658Y290195D01*
G01X539050Y287987D02*
Y290487D01*
X538550Y289987D01*
G01Y287987D02*
X539550D01*
G01X542150Y290487D02*
X541817Y290404D01*
X541567Y290195D01*
X541400Y289945D01*
X541275Y289612D01*
X541233Y289237D01*
X541275Y288862D01*
X541400Y288529D01*
X541567Y288279D01*
X541817Y288070D01*
X542150Y287987D01*
X542483Y288070D01*
X542733Y288279D01*
X542900Y288529D01*
X543025Y288862D01*
X543067Y289237D01*
X543025Y289612D01*
X542900Y289945D01*
X542733Y290195D01*
X542483Y290404D01*
X542150Y290487D01*
G01X557517Y352000D02*
Y354500D01*
X558558D01*
X558892Y354375D01*
X559100Y354208D01*
X559183Y353875D01*
X559100Y353542D01*
X558850Y353333D01*
X558558Y353208D01*
X557517D01*
G01X558558D02*
X559183Y352000D01*
G01X560658Y354083D02*
X560908Y354333D01*
X561200Y354458D01*
X561533Y354500D01*
X561950Y354417D01*
X562242Y354208D01*
X562325Y353958D01*
X562283Y353708D01*
X562117Y353500D01*
X561283Y353083D01*
X560908Y352792D01*
X560658Y352375D01*
X560575Y352000D01*
X562325D01*
G01X564550D02*
X564842Y352042D01*
X565175Y352167D01*
X565383Y352375D01*
X565467Y352667D01*
X565383Y352958D01*
X565133Y353208D01*
X564758Y353333D01*
X564342D01*
X564092Y353417D01*
X563883Y353625D01*
X563800Y353917D01*
X563925Y354208D01*
X564217Y354417D01*
X564550Y354500D01*
X564883Y354417D01*
X565175Y354208D01*
X565300Y353917D01*
X565217Y353625D01*
X565008Y353417D01*
X564758Y353333D01*
X564342D01*
X563967Y353208D01*
X563717Y352958D01*
X563633Y352667D01*
X563717Y352375D01*
X563925Y352167D01*
X564258Y352042D01*
X564550Y352000D01*
G01X566942Y352292D02*
X567233Y352083D01*
X567567Y352000D01*
X567900Y352083D01*
X568192Y352333D01*
X568400Y352708D01*
X568483Y353083D01*
Y353542D01*
X568400Y353917D01*
X568192Y354250D01*
X567942Y354417D01*
X567650Y354500D01*
X567317Y354417D01*
X567067Y354250D01*
X566900Y354000D01*
X566817Y353667D01*
X566900Y353375D01*
X567108Y353083D01*
X567358Y352917D01*
X567650Y352875D01*
X567983Y352958D01*
X568233Y353167D01*
X568483Y353542D01*
G01X557517Y356000D02*
Y358500D01*
X558558D01*
X558892Y358375D01*
X559100Y358208D01*
X559183Y357875D01*
X559100Y357542D01*
X558850Y357333D01*
X558558Y357208D01*
X557517D01*
G01X558558D02*
X559183Y356000D01*
G01X560658Y358083D02*
X560908Y358333D01*
X561200Y358458D01*
X561533Y358500D01*
X561950Y358417D01*
X562242Y358208D01*
X562325Y357958D01*
X562283Y357708D01*
X562117Y357500D01*
X561283Y357083D01*
X560908Y356792D01*
X560658Y356375D01*
X560575Y356000D01*
X562325D01*
G01X563842Y356292D02*
X564133Y356083D01*
X564467Y356000D01*
X564800Y356083D01*
X565092Y356333D01*
X565300Y356708D01*
X565383Y357083D01*
Y357542D01*
X565300Y357917D01*
X565092Y358250D01*
X564842Y358417D01*
X564550Y358500D01*
X564217Y358417D01*
X563967Y358250D01*
X563800Y358000D01*
X563717Y357667D01*
X563800Y357375D01*
X564008Y357083D01*
X564258Y356917D01*
X564550Y356875D01*
X564883Y356958D01*
X565133Y357167D01*
X565383Y357542D01*
G01X567650Y358500D02*
X567317Y358417D01*
X567067Y358208D01*
X566900Y357958D01*
X566775Y357625D01*
X566733Y357250D01*
X566775Y356875D01*
X566900Y356542D01*
X567067Y356292D01*
X567317Y356083D01*
X567650Y356000D01*
X567983Y356083D01*
X568233Y356292D01*
X568400Y356542D01*
X568525Y356875D01*
X568567Y357250D01*
X568525Y357625D01*
X568400Y357958D01*
X568233Y358208D01*
X567983Y358417D01*
X567650Y358500D01*
G01X520000Y349450D02*
X524000D01*
Y356850D01*
G01X534394Y354382D02*
X531894D01*
Y355423D01*
X532019Y355757D01*
X532186Y355965D01*
X532519Y356048D01*
X532852Y355965D01*
X533061Y355715D01*
X533186Y355423D01*
Y354382D01*
G01Y355423D02*
X534394Y356048D01*
G01X533352Y357523D02*
X533061Y357815D01*
X532894Y358065D01*
X532811Y358398D01*
X532894Y358690D01*
X533061Y358898D01*
X533311Y359065D01*
X533602Y359107D01*
X533852Y359065D01*
X534102Y358898D01*
X534311Y358648D01*
X534394Y358357D01*
X534311Y358023D01*
X534061Y357732D01*
X533686Y357565D01*
X533269Y357523D01*
X532727Y357607D01*
X532436Y357732D01*
X532144Y357940D01*
X531936Y358232D01*
X531894Y358523D01*
X531977Y358815D01*
X532186Y359023D01*
G01X534102Y360707D02*
X534311Y360998D01*
X534394Y361332D01*
X534311Y361665D01*
X534061Y361957D01*
X533686Y362165D01*
X533311Y362248D01*
X532852D01*
X532477Y362165D01*
X532144Y361957D01*
X531977Y361707D01*
X531894Y361415D01*
X531977Y361082D01*
X532144Y360832D01*
X532394Y360665D01*
X532727Y360582D01*
X533019Y360665D01*
X533311Y360873D01*
X533477Y361123D01*
X533519Y361415D01*
X533436Y361748D01*
X533227Y361998D01*
X532852Y362248D01*
G01X534894Y353015D02*
X530894D01*
Y345615D01*
G01X530394Y354382D02*
X527894D01*
Y355423D01*
X528019Y355757D01*
X528186Y355965D01*
X528519Y356048D01*
X528852Y355965D01*
X529061Y355715D01*
X529186Y355423D01*
Y354382D01*
G01Y355423D02*
X530394Y356048D01*
G01X529352Y357523D02*
X529061Y357815D01*
X528894Y358065D01*
X528811Y358398D01*
X528894Y358690D01*
X529061Y358898D01*
X529311Y359065D01*
X529602Y359107D01*
X529852Y359065D01*
X530102Y358898D01*
X530311Y358648D01*
X530394Y358357D01*
X530311Y358023D01*
X530061Y357732D01*
X529686Y357565D01*
X529269Y357523D01*
X528727Y357607D01*
X528436Y357732D01*
X528144Y357940D01*
X527936Y358232D01*
X527894Y358523D01*
X527977Y358815D01*
X528186Y359023D01*
G01X530394Y361415D02*
X530352Y361707D01*
X530227Y362040D01*
X530019Y362248D01*
X529727Y362332D01*
X529436Y362248D01*
X529186Y361998D01*
X529061Y361623D01*
Y361207D01*
X528977Y360957D01*
X528769Y360748D01*
X528477Y360665D01*
X528186Y360790D01*
X527977Y361082D01*
X527894Y361415D01*
X527977Y361748D01*
X528186Y362040D01*
X528477Y362165D01*
X528769Y362082D01*
X528977Y361873D01*
X529061Y361623D01*
Y361207D01*
X529186Y360832D01*
X529436Y360582D01*
X529727Y360498D01*
X530019Y360582D01*
X530227Y360790D01*
X530352Y361123D01*
X530394Y361415D01*
G01X530894Y353015D02*
X526894D01*
Y345615D01*
G01X527682Y326179D02*
Y328679D01*
X528723D01*
X529057Y328554D01*
X529265Y328387D01*
X529348Y328054D01*
X529265Y327721D01*
X529015Y327512D01*
X528723Y327387D01*
X527682D01*
G01X528723D02*
X529348Y326179D01*
G01X530823Y327221D02*
X531115Y327512D01*
X531365Y327679D01*
X531698Y327762D01*
X531990Y327679D01*
X532198Y327512D01*
X532365Y327262D01*
X532407Y326971D01*
X532365Y326721D01*
X532198Y326471D01*
X531948Y326262D01*
X531657Y326179D01*
X531323Y326262D01*
X531032Y326512D01*
X530865Y326887D01*
X530823Y327304D01*
X530907Y327846D01*
X531032Y328137D01*
X531240Y328429D01*
X531532Y328637D01*
X531823Y328679D01*
X532115Y328596D01*
X532323Y328387D01*
G01X533923Y328262D02*
X534173Y328512D01*
X534465Y328637D01*
X534798Y328679D01*
X535215Y328596D01*
X535507Y328387D01*
X535590Y328137D01*
X535548Y327887D01*
X535382Y327679D01*
X534548Y327262D01*
X534173Y326971D01*
X533923Y326554D01*
X533840Y326179D01*
X535590D01*
G01X533315Y333679D02*
Y337679D01*
X525915D01*
G01X558834Y330067D02*
X556334D01*
Y331108D01*
X556459Y331442D01*
X556626Y331650D01*
X556959Y331733D01*
X557292Y331650D01*
X557501Y331400D01*
X557626Y331108D01*
Y330067D01*
G01Y331108D02*
X558834Y331733D01*
G01X557792Y333208D02*
X557501Y333500D01*
X557334Y333750D01*
X557251Y334083D01*
X557334Y334375D01*
X557501Y334583D01*
X557751Y334750D01*
X558042Y334792D01*
X558292Y334750D01*
X558542Y334583D01*
X558751Y334333D01*
X558834Y334042D01*
X558751Y333708D01*
X558501Y333417D01*
X558126Y333250D01*
X557709Y333208D01*
X557167Y333292D01*
X556876Y333417D01*
X556584Y333625D01*
X556376Y333917D01*
X556334Y334208D01*
X556417Y334500D01*
X556626Y334708D01*
G01X558834Y337100D02*
X556334D01*
X556834Y336600D01*
G01X558834D02*
Y337600D01*
G01X537336Y337222D02*
X533336D01*
Y329822D01*
G01X527682Y322179D02*
Y324679D01*
X528723D01*
X529057Y324554D01*
X529265Y324387D01*
X529348Y324054D01*
X529265Y323721D01*
X529015Y323512D01*
X528723Y323387D01*
X527682D01*
G01X528723D02*
X529348Y322179D01*
G01X530823Y323221D02*
X531115Y323512D01*
X531365Y323679D01*
X531698Y323762D01*
X531990Y323679D01*
X532198Y323512D01*
X532365Y323262D01*
X532407Y322971D01*
X532365Y322721D01*
X532198Y322471D01*
X531948Y322262D01*
X531657Y322179D01*
X531323Y322262D01*
X531032Y322512D01*
X530865Y322887D01*
X530823Y323304D01*
X530907Y323846D01*
X531032Y324137D01*
X531240Y324429D01*
X531532Y324637D01*
X531823Y324679D01*
X532115Y324596D01*
X532323Y324387D01*
G01X534715Y324679D02*
X534382Y324596D01*
X534132Y324387D01*
X533965Y324137D01*
X533840Y323804D01*
X533798Y323429D01*
X533840Y323054D01*
X533965Y322721D01*
X534132Y322471D01*
X534382Y322262D01*
X534715Y322179D01*
X535048Y322262D01*
X535298Y322471D01*
X535465Y322721D01*
X535590Y323054D01*
X535632Y323429D01*
X535590Y323804D01*
X535465Y324137D01*
X535298Y324387D01*
X535048Y324596D01*
X534715Y324679D01*
G01X533315Y329679D02*
Y333679D01*
X525915D01*
G01X562834Y330067D02*
X560334D01*
Y331108D01*
X560459Y331442D01*
X560626Y331650D01*
X560959Y331733D01*
X561292Y331650D01*
X561501Y331400D01*
X561626Y331108D01*
Y330067D01*
G01Y331108D02*
X562834Y331733D01*
G01X562459Y333083D02*
X562667Y333333D01*
X562792Y333625D01*
X562834Y334000D01*
X562751Y334375D01*
X562584Y334667D01*
X562292Y334875D01*
X561959Y334917D01*
X561626Y334833D01*
X561417Y334625D01*
X561251Y334333D01*
X561209Y334042D01*
X561251Y333750D01*
X561417Y333375D01*
X560334Y333500D01*
Y334625D01*
G01X562834Y337100D02*
X562792Y337392D01*
X562667Y337725D01*
X562459Y337933D01*
X562167Y338017D01*
X561876Y337933D01*
X561626Y337683D01*
X561501Y337308D01*
Y336892D01*
X561417Y336642D01*
X561209Y336433D01*
X560917Y336350D01*
X560626Y336475D01*
X560417Y336767D01*
X560334Y337100D01*
X560417Y337433D01*
X560626Y337725D01*
X560917Y337850D01*
X561209Y337767D01*
X561417Y337558D01*
X561501Y337308D01*
Y336892D01*
X561626Y336517D01*
X561876Y336267D01*
X562167Y336183D01*
X562459Y336267D01*
X562667Y336475D01*
X562792Y336808D01*
X562834Y337100D01*
G01X543714Y337203D02*
X539714D01*
Y329803D01*
G01X566834Y330067D02*
X564334D01*
Y331108D01*
X564459Y331442D01*
X564626Y331650D01*
X564959Y331733D01*
X565292Y331650D01*
X565501Y331400D01*
X565626Y331108D01*
Y330067D01*
G01Y331108D02*
X566834Y331733D01*
G01X566459Y333083D02*
X566667Y333333D01*
X566792Y333625D01*
X566834Y334000D01*
X566751Y334375D01*
X566584Y334667D01*
X566292Y334875D01*
X565959Y334917D01*
X565626Y334833D01*
X565417Y334625D01*
X565251Y334333D01*
X565209Y334042D01*
X565251Y333750D01*
X565417Y333375D01*
X564334Y333500D01*
Y334625D01*
G01Y337100D02*
X564417Y336767D01*
X564626Y336517D01*
X564876Y336350D01*
X565209Y336225D01*
X565584Y336183D01*
X565959Y336225D01*
X566292Y336350D01*
X566542Y336517D01*
X566751Y336767D01*
X566834Y337100D01*
X566751Y337433D01*
X566542Y337683D01*
X566292Y337850D01*
X565959Y337975D01*
X565584Y338017D01*
X565209Y337975D01*
X564876Y337850D01*
X564626Y337683D01*
X564417Y337433D01*
X564334Y337100D01*
G01X549315Y337188D02*
X545315D01*
Y329788D01*
G01X570834Y330067D02*
X568334D01*
Y331108D01*
X568459Y331442D01*
X568626Y331650D01*
X568959Y331733D01*
X569292Y331650D01*
X569501Y331400D01*
X569626Y331108D01*
Y330067D01*
G01Y331108D02*
X570834Y331733D01*
G01Y334500D02*
X568334D01*
X570126Y332958D01*
Y335042D01*
G01X570834Y337100D02*
X570792Y337392D01*
X570667Y337725D01*
X570459Y337933D01*
X570167Y338017D01*
X569876Y337933D01*
X569626Y337683D01*
X569501Y337308D01*
Y336892D01*
X569417Y336642D01*
X569209Y336433D01*
X568917Y336350D01*
X568626Y336475D01*
X568417Y336767D01*
X568334Y337100D01*
X568417Y337433D01*
X568626Y337725D01*
X568917Y337850D01*
X569209Y337767D01*
X569417Y337558D01*
X569501Y337308D01*
Y336892D01*
X569626Y336517D01*
X569876Y336267D01*
X570167Y336183D01*
X570459Y336267D01*
X570667Y336475D01*
X570792Y336808D01*
X570834Y337100D01*
G01X553394Y337188D02*
X549394D01*
Y329788D01*
G01X520000Y356850D02*
X516000D01*
Y349450D01*
G01Y357000D02*
X512000D01*
Y349600D01*
G01X570517Y355000D02*
Y357500D01*
X571558D01*
X571892Y357375D01*
X572100Y357208D01*
X572183Y356875D01*
X572100Y356542D01*
X571850Y356333D01*
X571558Y356208D01*
X570517D01*
G01X571558D02*
X572183Y355000D01*
G01X573533Y355500D02*
X573783Y355208D01*
X574117Y355042D01*
X574492Y355000D01*
X574825Y355042D01*
X575158Y355250D01*
X575367Y355500D01*
X575408Y355750D01*
X575325Y356042D01*
X575033Y356250D01*
X574742Y356333D01*
X574367D01*
G01X574742D02*
X574992Y356458D01*
X575200Y356667D01*
X575283Y356917D01*
X575200Y357167D01*
X574992Y357375D01*
X574617Y357500D01*
X574242Y357458D01*
X573867Y357292D01*
G01X576633Y355500D02*
X576883Y355208D01*
X577217Y355042D01*
X577592Y355000D01*
X577925Y355042D01*
X578258Y355250D01*
X578467Y355500D01*
X578508Y355750D01*
X578425Y356042D01*
X578133Y356250D01*
X577842Y356333D01*
X577467D01*
G01X577842D02*
X578092Y356458D01*
X578300Y356667D01*
X578383Y356917D01*
X578300Y357167D01*
X578092Y357375D01*
X577717Y357500D01*
X577342Y357458D01*
X576967Y357292D01*
G01X579733Y355500D02*
X579983Y355208D01*
X580317Y355042D01*
X580692Y355000D01*
X581025Y355042D01*
X581358Y355250D01*
X581567Y355500D01*
X581608Y355750D01*
X581525Y356042D01*
X581233Y356250D01*
X580942Y356333D01*
X580567D01*
G01X580942D02*
X581192Y356458D01*
X581400Y356667D01*
X581483Y356917D01*
X581400Y357167D01*
X581192Y357375D01*
X580817Y357500D01*
X580442Y357458D01*
X580067Y357292D01*
G01X517717Y326891D02*
Y320748D01*
G01X519567Y328741D02*
G02I-1850J0D01*
G01Y318898D02*
G02I-1850J0D01*
G01X562517Y374000D02*
Y376500D01*
X563558D01*
X563892Y376375D01*
X564100Y376208D01*
X564183Y375875D01*
X564100Y375542D01*
X563850Y375333D01*
X563558Y375208D01*
X562517D01*
G01X563558D02*
X564183Y374000D01*
G01X565658Y376083D02*
X565908Y376333D01*
X566200Y376458D01*
X566533Y376500D01*
X566950Y376417D01*
X567242Y376208D01*
X567325Y375958D01*
X567283Y375708D01*
X567117Y375500D01*
X566283Y375083D01*
X565908Y374792D01*
X565658Y374375D01*
X565575Y374000D01*
X567325D01*
G01X568842Y374292D02*
X569133Y374083D01*
X569467Y374000D01*
X569800Y374083D01*
X570092Y374333D01*
X570300Y374708D01*
X570383Y375083D01*
Y375542D01*
X570300Y375917D01*
X570092Y376250D01*
X569842Y376417D01*
X569550Y376500D01*
X569217Y376417D01*
X568967Y376250D01*
X568800Y376000D01*
X568717Y375667D01*
X568800Y375375D01*
X569008Y375083D01*
X569258Y374917D01*
X569550Y374875D01*
X569883Y374958D01*
X570133Y375167D01*
X570383Y375542D01*
G01X573150Y374000D02*
Y376500D01*
X571608Y374708D01*
X573692D01*
G01X563017Y370000D02*
Y372500D01*
X564058D01*
X564392Y372375D01*
X564600Y372208D01*
X564683Y371875D01*
X564600Y371542D01*
X564350Y371333D01*
X564058Y371208D01*
X563017D01*
G01X564058D02*
X564683Y370000D01*
G01X566158Y372083D02*
X566408Y372333D01*
X566700Y372458D01*
X567033Y372500D01*
X567450Y372417D01*
X567742Y372208D01*
X567825Y371958D01*
X567783Y371708D01*
X567617Y371500D01*
X566783Y371083D01*
X566408Y370792D01*
X566158Y370375D01*
X566075Y370000D01*
X567825D01*
G01X569342Y370292D02*
X569633Y370083D01*
X569967Y370000D01*
X570300Y370083D01*
X570592Y370333D01*
X570800Y370708D01*
X570883Y371083D01*
Y371542D01*
X570800Y371917D01*
X570592Y372250D01*
X570342Y372417D01*
X570050Y372500D01*
X569717Y372417D01*
X569467Y372250D01*
X569300Y372000D01*
X569217Y371667D01*
X569300Y371375D01*
X569508Y371083D01*
X569758Y370917D01*
X570050Y370875D01*
X570383Y370958D01*
X570633Y371167D01*
X570883Y371542D01*
G01X572233Y370375D02*
X572483Y370167D01*
X572775Y370042D01*
X573150Y370000D01*
X573525Y370083D01*
X573817Y370250D01*
X574025Y370542D01*
X574067Y370875D01*
X573983Y371208D01*
X573775Y371417D01*
X573483Y371583D01*
X573192Y371625D01*
X572900Y371583D01*
X572525Y371417D01*
X572650Y372500D01*
X573775D01*
G01X516767Y406792D02*
X516517Y406917D01*
X516225Y407000D01*
X515892D01*
X515517Y406875D01*
X515225Y406667D01*
X515017Y406417D01*
X514850Y406000D01*
X514808Y405625D01*
X514892Y405250D01*
X515017Y405000D01*
X515267Y404750D01*
X515558Y404583D01*
X515850Y404500D01*
X516142D01*
X516433Y404583D01*
X516683Y404708D01*
X516892Y404875D01*
G01X518158Y405542D02*
X518450Y405833D01*
X518700Y406000D01*
X519033Y406083D01*
X519325Y406000D01*
X519533Y405833D01*
X519700Y405583D01*
X519742Y405292D01*
X519700Y405042D01*
X519533Y404792D01*
X519283Y404583D01*
X518992Y404500D01*
X518658Y404583D01*
X518367Y404833D01*
X518200Y405208D01*
X518158Y405625D01*
X518242Y406167D01*
X518367Y406458D01*
X518575Y406750D01*
X518867Y406958D01*
X519158Y407000D01*
X519450Y406917D01*
X519658Y406708D01*
G01X521342Y404792D02*
X521633Y404583D01*
X521967Y404500D01*
X522300Y404583D01*
X522592Y404833D01*
X522800Y405208D01*
X522883Y405583D01*
Y406042D01*
X522800Y406417D01*
X522592Y406750D01*
X522342Y406917D01*
X522050Y407000D01*
X521717Y406917D01*
X521467Y406750D01*
X521300Y406500D01*
X521217Y406167D01*
X521300Y405875D01*
X521508Y405583D01*
X521758Y405417D01*
X522050Y405375D01*
X522383Y405458D01*
X522633Y405667D01*
X522883Y406042D01*
G01X524233Y405000D02*
X524483Y404708D01*
X524817Y404542D01*
X525192Y404500D01*
X525525Y404542D01*
X525858Y404750D01*
X526067Y405000D01*
X526108Y405250D01*
X526025Y405542D01*
X525733Y405750D01*
X525442Y405833D01*
X525067D01*
G01X525442D02*
X525692Y405958D01*
X525900Y406167D01*
X525983Y406417D01*
X525900Y406667D01*
X525692Y406875D01*
X525317Y407000D01*
X524942Y406958D01*
X524567Y406792D01*
G01X546500Y385017D02*
X544000D01*
Y386058D01*
X544125Y386392D01*
X544292Y386600D01*
X544625Y386683D01*
X544958Y386600D01*
X545167Y386350D01*
X545292Y386058D01*
Y385017D01*
G01Y386058D02*
X546500Y386683D01*
G01Y388950D02*
X544000D01*
X544500Y388450D01*
G01X546500D02*
Y389450D01*
G01X546000Y391133D02*
X546292Y391383D01*
X546458Y391717D01*
X546500Y392092D01*
X546458Y392425D01*
X546250Y392758D01*
X546000Y392967D01*
X545750Y393008D01*
X545458Y392925D01*
X545250Y392633D01*
X545167Y392342D01*
Y391967D01*
G01Y392342D02*
X545042Y392592D01*
X544833Y392800D01*
X544583Y392883D01*
X544333Y392800D01*
X544125Y392592D01*
X544000Y392217D01*
X544042Y391842D01*
X544208Y391467D01*
G01X546500Y395650D02*
X544000D01*
X545792Y394108D01*
Y396192D01*
G01X539834Y385067D02*
X542334D01*
Y386733D01*
G01X541834Y388083D02*
X542126Y388333D01*
X542292Y388667D01*
X542334Y389042D01*
X542292Y389375D01*
X542084Y389708D01*
X541834Y389917D01*
X541584Y389958D01*
X541292Y389875D01*
X541084Y389583D01*
X541001Y389292D01*
Y388917D01*
G01Y389292D02*
X540876Y389542D01*
X540667Y389750D01*
X540417Y389833D01*
X540167Y389750D01*
X539959Y389542D01*
X539834Y389167D01*
X539876Y388792D01*
X540042Y388417D01*
G01X541959Y391183D02*
X542167Y391433D01*
X542292Y391725D01*
X542334Y392100D01*
X542251Y392475D01*
X542084Y392767D01*
X541792Y392975D01*
X541459Y393017D01*
X541126Y392933D01*
X540917Y392725D01*
X540751Y392433D01*
X540709Y392142D01*
X540751Y391850D01*
X540917Y391475D01*
X539834Y391600D01*
Y392725D01*
G01X556500Y402700D02*
X563500D01*
Y389300D01*
X556500D01*
Y402700D01*
G01X516767Y411192D02*
X516517Y411317D01*
X516225Y411400D01*
X515892D01*
X515517Y411275D01*
X515225Y411067D01*
X515017Y410817D01*
X514850Y410400D01*
X514808Y410025D01*
X514892Y409650D01*
X515017Y409400D01*
X515267Y409150D01*
X515558Y408983D01*
X515850Y408900D01*
X516142D01*
X516433Y408983D01*
X516683Y409108D01*
X516892Y409275D01*
G01X518158Y409942D02*
X518450Y410233D01*
X518700Y410400D01*
X519033Y410483D01*
X519325Y410400D01*
X519533Y410233D01*
X519700Y409983D01*
X519742Y409692D01*
X519700Y409442D01*
X519533Y409192D01*
X519283Y408983D01*
X518992Y408900D01*
X518658Y408983D01*
X518367Y409233D01*
X518200Y409608D01*
X518158Y410025D01*
X518242Y410567D01*
X518367Y410858D01*
X518575Y411150D01*
X518867Y411358D01*
X519158Y411400D01*
X519450Y411317D01*
X519658Y411108D01*
G01X521342Y409192D02*
X521633Y408983D01*
X521967Y408900D01*
X522300Y408983D01*
X522592Y409233D01*
X522800Y409608D01*
X522883Y409983D01*
Y410442D01*
X522800Y410817D01*
X522592Y411150D01*
X522342Y411317D01*
X522050Y411400D01*
X521717Y411317D01*
X521467Y411150D01*
X521300Y410900D01*
X521217Y410567D01*
X521300Y410275D01*
X521508Y409983D01*
X521758Y409817D01*
X522050Y409775D01*
X522383Y409858D01*
X522633Y410067D01*
X522883Y410442D01*
G01X524233Y409275D02*
X524483Y409067D01*
X524775Y408942D01*
X525150Y408900D01*
X525525Y408983D01*
X525817Y409150D01*
X526025Y409442D01*
X526067Y409775D01*
X525983Y410108D01*
X525775Y410317D01*
X525483Y410483D01*
X525192Y410525D01*
X524900Y410483D01*
X524525Y410317D01*
X524650Y411400D01*
X525775D01*
G01X516767Y415792D02*
X516517Y415917D01*
X516225Y416000D01*
X515892D01*
X515517Y415875D01*
X515225Y415667D01*
X515017Y415417D01*
X514850Y415000D01*
X514808Y414625D01*
X514892Y414250D01*
X515017Y414000D01*
X515267Y413750D01*
X515558Y413583D01*
X515850Y413500D01*
X516142D01*
X516433Y413583D01*
X516683Y413708D01*
X516892Y413875D01*
G01X518158Y414542D02*
X518450Y414833D01*
X518700Y415000D01*
X519033Y415083D01*
X519325Y415000D01*
X519533Y414833D01*
X519700Y414583D01*
X519742Y414292D01*
X519700Y414042D01*
X519533Y413792D01*
X519283Y413583D01*
X518992Y413500D01*
X518658Y413583D01*
X518367Y413833D01*
X518200Y414208D01*
X518158Y414625D01*
X518242Y415167D01*
X518367Y415458D01*
X518575Y415750D01*
X518867Y415958D01*
X519158Y416000D01*
X519450Y415917D01*
X519658Y415708D01*
G01X521342Y413792D02*
X521633Y413583D01*
X521967Y413500D01*
X522300Y413583D01*
X522592Y413833D01*
X522800Y414208D01*
X522883Y414583D01*
Y415042D01*
X522800Y415417D01*
X522592Y415750D01*
X522342Y415917D01*
X522050Y416000D01*
X521717Y415917D01*
X521467Y415750D01*
X521300Y415500D01*
X521217Y415167D01*
X521300Y414875D01*
X521508Y414583D01*
X521758Y414417D01*
X522050Y414375D01*
X522383Y414458D01*
X522633Y414667D01*
X522883Y415042D01*
G01X525650Y413500D02*
Y416000D01*
X524108Y414208D01*
X526192D01*
G01X548708Y386767D02*
X548583Y386517D01*
X548500Y386225D01*
Y385892D01*
X548625Y385517D01*
X548833Y385225D01*
X549083Y385017D01*
X549500Y384850D01*
X549875Y384808D01*
X550250Y384892D01*
X550500Y385017D01*
X550750Y385267D01*
X550917Y385558D01*
X551000Y385850D01*
Y386142D01*
X550917Y386433D01*
X550792Y386683D01*
X550625Y386892D01*
G01X551000Y388867D02*
X550458Y388950D01*
X550000Y389075D01*
X549583Y389242D01*
X549125Y389450D01*
X548500Y389783D01*
Y388117D01*
G01X548917Y391258D02*
X548667Y391508D01*
X548542Y391800D01*
X548500Y392133D01*
X548583Y392550D01*
X548792Y392842D01*
X549042Y392925D01*
X549292Y392883D01*
X549500Y392717D01*
X549917Y391883D01*
X550208Y391508D01*
X550625Y391258D01*
X551000Y391175D01*
Y392925D01*
G01X548500Y395150D02*
X548583Y394817D01*
X548792Y394567D01*
X549042Y394400D01*
X549375Y394275D01*
X549750Y394233D01*
X550125Y394275D01*
X550458Y394400D01*
X550708Y394567D01*
X550917Y394817D01*
X551000Y395150D01*
X550917Y395483D01*
X550708Y395733D01*
X550458Y395900D01*
X550125Y396025D01*
X549750Y396067D01*
X549375Y396025D01*
X549042Y395900D01*
X548792Y395733D01*
X548583Y395483D01*
X548500Y395150D01*
G01X569500Y387200D02*
Y392700D01*
G01X577500Y387200D02*
X569500D01*
G01Y404800D02*
X577500D01*
G01X569500Y399300D02*
Y404800D01*
G01X552708Y386767D02*
X552583Y386517D01*
X552500Y386225D01*
Y385892D01*
X552625Y385517D01*
X552833Y385225D01*
X553083Y385017D01*
X553500Y384850D01*
X553875Y384808D01*
X554250Y384892D01*
X554500Y385017D01*
X554750Y385267D01*
X554917Y385558D01*
X555000Y385850D01*
Y386142D01*
X554917Y386433D01*
X554792Y386683D01*
X554625Y386892D01*
G01X555000Y388867D02*
X554458Y388950D01*
X554000Y389075D01*
X553583Y389242D01*
X553125Y389450D01*
X552500Y389783D01*
Y388117D01*
G01X555000Y392050D02*
X552500D01*
X553000Y391550D01*
G01X555000D02*
Y392550D01*
G01X554708Y394442D02*
X554917Y394733D01*
X555000Y395067D01*
X554917Y395400D01*
X554667Y395692D01*
X554292Y395900D01*
X553917Y395983D01*
X553458D01*
X553083Y395900D01*
X552750Y395692D01*
X552583Y395442D01*
X552500Y395150D01*
X552583Y394817D01*
X552750Y394567D01*
X553000Y394400D01*
X553333Y394317D01*
X553625Y394400D01*
X553917Y394608D01*
X554083Y394858D01*
X554125Y395150D01*
X554042Y395483D01*
X553833Y395733D01*
X553458Y395983D01*
G01X515000Y364850D02*
X517500D01*
G01X515000Y363892D02*
Y365808D01*
G01X517500Y367117D02*
X515000D01*
Y368117D01*
X515125Y368450D01*
X515417Y368700D01*
X515750Y368783D01*
X516083Y368700D01*
X516333Y368492D01*
X516458Y368117D01*
Y367117D01*
G01X517500Y371050D02*
X515000D01*
X515500Y370550D01*
G01X517500D02*
Y371550D01*
G01Y374067D02*
X516958Y374150D01*
X516500Y374275D01*
X516083Y374442D01*
X515625Y374650D01*
X515000Y374983D01*
Y373317D01*
G01X530500Y404567D02*
X528000D01*
Y405608D01*
X528125Y405942D01*
X528292Y406150D01*
X528625Y406233D01*
X528958Y406150D01*
X529167Y405900D01*
X529292Y405608D01*
Y404567D01*
G01Y405608D02*
X530500Y406233D01*
G01X528417Y407708D02*
X528167Y407958D01*
X528042Y408250D01*
X528000Y408583D01*
X528083Y409000D01*
X528292Y409292D01*
X528542Y409375D01*
X528792Y409333D01*
X529000Y409167D01*
X529417Y408333D01*
X529708Y407958D01*
X530125Y407708D01*
X530500Y407625D01*
Y409375D01*
G01Y412100D02*
X528000D01*
X529792Y410558D01*
Y412642D01*
G01X541706Y406182D02*
Y411382D01*
G01X548706Y406182D02*
Y413982D01*
G01X541706Y406182D02*
X548706D01*
G01X541706Y419582D02*
Y410882D01*
G01X548706Y419582D02*
X541706D01*
G01X548706Y413182D02*
Y419582D01*
G01X534706Y404399D02*
X532206D01*
Y405440D01*
X532331Y405774D01*
X532498Y405982D01*
X532831Y406065D01*
X533164Y405982D01*
X533373Y405732D01*
X533498Y405440D01*
Y404399D01*
G01Y405440D02*
X534706Y406065D01*
G01X534206Y407415D02*
X534498Y407665D01*
X534664Y407999D01*
X534706Y408374D01*
X534664Y408707D01*
X534456Y409040D01*
X534206Y409249D01*
X533956Y409290D01*
X533664Y409207D01*
X533456Y408915D01*
X533373Y408624D01*
Y408249D01*
G01Y408624D02*
X533248Y408874D01*
X533039Y409082D01*
X532789Y409165D01*
X532539Y409082D01*
X532331Y408874D01*
X532206Y408499D01*
X532248Y408124D01*
X532414Y407749D01*
G01X534706Y411432D02*
X534664Y411724D01*
X534539Y412057D01*
X534331Y412265D01*
X534039Y412349D01*
X533748Y412265D01*
X533498Y412015D01*
X533373Y411640D01*
Y411224D01*
X533289Y410974D01*
X533081Y410765D01*
X532789Y410682D01*
X532498Y410807D01*
X532289Y411099D01*
X532206Y411432D01*
X532289Y411765D01*
X532498Y412057D01*
X532789Y412182D01*
X533081Y412099D01*
X533289Y411890D01*
X533373Y411640D01*
Y411224D01*
X533498Y410849D01*
X533748Y410599D01*
X534039Y410515D01*
X534331Y410599D01*
X534539Y410807D01*
X534664Y411140D01*
X534706Y411432D01*
G01X532623Y413740D02*
X532373Y413990D01*
X532248Y414282D01*
X532206Y414615D01*
X532289Y415032D01*
X532498Y415324D01*
X532748Y415407D01*
X532998Y415365D01*
X533206Y415199D01*
X533623Y414365D01*
X533914Y413990D01*
X534331Y413740D01*
X534706Y413657D01*
Y415407D01*
G01X549706Y406182D02*
Y411382D01*
G01X556706Y406182D02*
Y413982D01*
G01X549706Y406182D02*
X556706D01*
G01X549706Y419582D02*
Y410882D01*
G01X556706Y419582D02*
X549706D01*
G01X556706Y413182D02*
Y419582D01*
G01X539000Y404567D02*
X536500D01*
Y405608D01*
X536625Y405942D01*
X536792Y406150D01*
X537125Y406233D01*
X537458Y406150D01*
X537667Y405900D01*
X537792Y405608D01*
Y404567D01*
G01Y405608D02*
X539000Y406233D01*
G01X536917Y407708D02*
X536667Y407958D01*
X536542Y408250D01*
X536500Y408583D01*
X536583Y409000D01*
X536792Y409292D01*
X537042Y409375D01*
X537292Y409333D01*
X537500Y409167D01*
X537917Y408333D01*
X538208Y407958D01*
X538625Y407708D01*
X539000Y407625D01*
Y409375D01*
G01X537958Y410808D02*
X537667Y411100D01*
X537500Y411350D01*
X537417Y411683D01*
X537500Y411975D01*
X537667Y412183D01*
X537917Y412350D01*
X538208Y412392D01*
X538458Y412350D01*
X538708Y412183D01*
X538917Y411933D01*
X539000Y411642D01*
X538917Y411308D01*
X538667Y411017D01*
X538292Y410850D01*
X537875Y410808D01*
X537333Y410892D01*
X537042Y411017D01*
X536750Y411225D01*
X536542Y411517D01*
X536500Y411808D01*
X536583Y412100D01*
X536792Y412308D01*
G01X558206Y406182D02*
Y411382D01*
G01X565206Y406182D02*
Y413982D01*
G01X558206Y406182D02*
X565206D01*
G01X558206Y419582D02*
Y410882D01*
G01X565206Y419582D02*
X558206D01*
G01X565206Y413182D02*
Y419582D01*
G01X556000Y466017D02*
X553500D01*
Y467058D01*
X553625Y467392D01*
X553792Y467600D01*
X554125Y467683D01*
X554458Y467600D01*
X554667Y467350D01*
X554792Y467058D01*
Y466017D01*
G01Y467058D02*
X556000Y467683D01*
G01X555500Y469033D02*
X555792Y469283D01*
X555958Y469617D01*
X556000Y469992D01*
X555958Y470325D01*
X555750Y470658D01*
X555500Y470867D01*
X555250Y470908D01*
X554958Y470825D01*
X554750Y470533D01*
X554667Y470242D01*
Y469867D01*
G01Y470242D02*
X554542Y470492D01*
X554333Y470700D01*
X554083Y470783D01*
X553833Y470700D01*
X553625Y470492D01*
X553500Y470117D01*
X553542Y469742D01*
X553708Y469367D01*
G01X556000Y472967D02*
X555458Y473050D01*
X555000Y473175D01*
X554583Y473342D01*
X554125Y473550D01*
X553500Y473883D01*
Y472217D01*
G01X556000Y476150D02*
X555958Y476442D01*
X555833Y476775D01*
X555625Y476983D01*
X555333Y477067D01*
X555042Y476983D01*
X554792Y476733D01*
X554667Y476358D01*
Y475942D01*
X554583Y475692D01*
X554375Y475483D01*
X554083Y475400D01*
X553792Y475525D01*
X553583Y475817D01*
X553500Y476150D01*
X553583Y476483D01*
X553792Y476775D01*
X554083Y476900D01*
X554375Y476817D01*
X554583Y476608D01*
X554667Y476358D01*
Y475942D01*
X554792Y475567D01*
X555042Y475317D01*
X555333Y475233D01*
X555625Y475317D01*
X555833Y475525D01*
X555958Y475858D01*
X556000Y476150D01*
G01X571570Y458280D02*
X575570D01*
Y465680D01*
G01X572067Y471667D02*
Y474167D01*
X573108D01*
X573442Y474042D01*
X573650Y473875D01*
X573733Y473542D01*
X573650Y473209D01*
X573400Y473000D01*
X573108Y472875D01*
X572067D01*
G01X573108D02*
X573733Y471667D01*
G01X575208Y473750D02*
X575458Y474000D01*
X575750Y474125D01*
X576083Y474167D01*
X576500Y474084D01*
X576792Y473875D01*
X576875Y473625D01*
X576833Y473375D01*
X576667Y473167D01*
X575833Y472750D01*
X575458Y472459D01*
X575208Y472042D01*
X575125Y471667D01*
X576875D01*
G01X579017D02*
X579100Y472209D01*
X579225Y472667D01*
X579392Y473084D01*
X579600Y473542D01*
X579933Y474167D01*
X578267D01*
G01X549708Y467767D02*
X549583Y467517D01*
X549500Y467225D01*
Y466892D01*
X549625Y466517D01*
X549833Y466225D01*
X550083Y466017D01*
X550500Y465850D01*
X550875Y465808D01*
X551250Y465892D01*
X551500Y466017D01*
X551750Y466267D01*
X551917Y466558D01*
X552000Y466850D01*
Y467142D01*
X551917Y467433D01*
X551792Y467683D01*
X551625Y467892D01*
G01X550958Y469158D02*
X550667Y469450D01*
X550500Y469700D01*
X550417Y470033D01*
X550500Y470325D01*
X550667Y470533D01*
X550917Y470700D01*
X551208Y470742D01*
X551458Y470700D01*
X551708Y470533D01*
X551917Y470283D01*
X552000Y469992D01*
X551917Y469658D01*
X551667Y469367D01*
X551292Y469200D01*
X550875Y469158D01*
X550333Y469242D01*
X550042Y469367D01*
X549750Y469575D01*
X549542Y469867D01*
X549500Y470158D01*
X549583Y470450D01*
X549792Y470658D01*
G01X552000Y472967D02*
X551458Y473050D01*
X551000Y473175D01*
X550583Y473342D01*
X550125Y473550D01*
X549500Y473883D01*
Y472217D01*
G01X551625Y475233D02*
X551833Y475483D01*
X551958Y475775D01*
X552000Y476150D01*
X551917Y476525D01*
X551750Y476817D01*
X551458Y477025D01*
X551125Y477067D01*
X550792Y476983D01*
X550583Y476775D01*
X550417Y476483D01*
X550375Y476192D01*
X550417Y475900D01*
X550583Y475525D01*
X549500Y475650D01*
Y476775D01*
G01X549223Y463598D02*
Y461098D01*
X550889D01*
G01X552364Y463181D02*
X552614Y463431D01*
X552906Y463556D01*
X553239Y463598D01*
X553656Y463515D01*
X553948Y463306D01*
X554031Y463056D01*
X553989Y462806D01*
X553823Y462598D01*
X552989Y462181D01*
X552614Y461890D01*
X552364Y461473D01*
X552281Y461098D01*
X554031D01*
G01X555548Y461390D02*
X555839Y461181D01*
X556173Y461098D01*
X556506Y461181D01*
X556798Y461431D01*
X557006Y461806D01*
X557089Y462181D01*
Y462640D01*
X557006Y463015D01*
X556798Y463348D01*
X556548Y463515D01*
X556256Y463598D01*
X555923Y463515D01*
X555673Y463348D01*
X555506Y463098D01*
X555423Y462765D01*
X555506Y462473D01*
X555714Y462181D01*
X555964Y462015D01*
X556256Y461973D01*
X556589Y462056D01*
X556839Y462265D01*
X557089Y462640D01*
G01X553756Y455531D02*
X589156D01*
Y427531D01*
X553756D01*
Y455531D01*
G01X527400Y464167D02*
Y461667D01*
G01X526442Y464167D02*
X528358D01*
G01X531417Y463959D02*
X531167Y464084D01*
X530875Y464167D01*
X530542D01*
X530167Y464042D01*
X529875Y463834D01*
X529667Y463584D01*
X529500Y463167D01*
X529458Y462792D01*
X529542Y462417D01*
X529667Y462167D01*
X529917Y461917D01*
X530208Y461750D01*
X530500Y461667D01*
X530792D01*
X531083Y461750D01*
X531333Y461875D01*
X531542Y462042D01*
G01X532683D02*
X532933Y461834D01*
X533225Y461709D01*
X533600Y461667D01*
X533975Y461750D01*
X534267Y461917D01*
X534475Y462209D01*
X534517Y462542D01*
X534433Y462875D01*
X534225Y463084D01*
X533933Y463250D01*
X533642Y463292D01*
X533350Y463250D01*
X532975Y463084D01*
X533100Y464167D01*
X534225D01*
G01X552200Y454500D02*
X541000D01*
G01X552200Y436500D02*
Y454500D01*
G01X541000Y436500D02*
X552200D01*
G01X513800Y454500D02*
X525000D01*
G01X513800Y436500D02*
Y454500D01*
G01X525000Y436500D02*
X513800D01*
G01X548000Y465533D02*
X545500D01*
Y466367D01*
X545625Y466700D01*
X545792Y466950D01*
X546042Y467158D01*
X546333Y467325D01*
X546750Y467367D01*
X547167Y467325D01*
X547458Y467158D01*
X547708Y466950D01*
X547875Y466700D01*
X548000Y466367D01*
Y465533D01*
G01X547500Y468633D02*
X547792Y468883D01*
X547958Y469217D01*
X548000Y469592D01*
X547958Y469925D01*
X547750Y470258D01*
X547500Y470467D01*
X547250Y470508D01*
X546958Y470425D01*
X546750Y470133D01*
X546667Y469842D01*
Y469467D01*
G01Y469842D02*
X546542Y470092D01*
X546333Y470300D01*
X546083Y470383D01*
X545833Y470300D01*
X545625Y470092D01*
X545500Y469717D01*
X545542Y469342D01*
X545708Y468967D01*
G01X565960Y475070D02*
Y458970D01*
G01X558960Y475070D02*
X565960D01*
G01X558960Y458970D02*
Y475070D01*
G01X565960Y458970D02*
X558960D01*
G01X557333Y529933D02*
X558000Y530433D01*
X558500Y531266D01*
X558833Y532433D01*
X558500Y533433D01*
X557833Y534100D01*
X556667Y534600D01*
X552167D01*
Y524600D01*
X557667D01*
X558833Y525267D01*
X559500Y526267D01*
X559833Y527433D01*
X559500Y528600D01*
X558500Y529600D01*
X557333Y529933D01*
X552167D01*
G01X568600Y524600D02*
Y534600D01*
X562433Y527433D01*
X570767D01*
G01X577200Y524600D02*
X578367Y524767D01*
X579700Y525267D01*
X580533Y526100D01*
X580867Y527267D01*
X580533Y528433D01*
X579533Y529433D01*
X578033Y529933D01*
X576367D01*
X575367Y530267D01*
X574533Y531100D01*
X574200Y532267D01*
X574700Y533433D01*
X575866Y534267D01*
X577200Y534600D01*
X578533Y534267D01*
X579700Y533433D01*
X580200Y532267D01*
X579867Y531100D01*
X579033Y530267D01*
X578033Y529933D01*
X576367D01*
X574867Y529433D01*
X573867Y528433D01*
X573533Y527267D01*
X573867Y526100D01*
X574700Y525267D01*
X576033Y524767D01*
X577200Y524600D01*
G01X587800Y524267D02*
X587467Y524433D01*
Y524767D01*
X587800Y524933D01*
X588133Y524767D01*
Y524433D01*
X587800Y524267D01*
G01X598400Y534600D02*
X597066Y534267D01*
X596067Y533433D01*
X595400Y532433D01*
X594900Y531100D01*
X594733Y529600D01*
X594900Y528100D01*
X595400Y526767D01*
X596067Y525766D01*
X597066Y524933D01*
X598400Y524600D01*
X599733Y524933D01*
X600733Y525766D01*
X601400Y526767D01*
X601900Y528100D01*
X602067Y529600D01*
X601900Y531100D01*
X601400Y532433D01*
X600733Y533433D01*
X599733Y534267D01*
X598400Y534600D01*
G01X609000Y524600D02*
Y534600D01*
X607000Y532600D01*
G01Y524600D02*
X611000D01*
G01X619600D02*
Y534600D01*
X617600Y532600D01*
G01Y524600D02*
X621600D01*
G01X630200D02*
Y534600D01*
X628200Y532600D01*
G01Y524600D02*
X632200D01*
G01X637133Y526600D02*
X638133Y525433D01*
X639466Y524767D01*
X640967Y524600D01*
X642300Y524767D01*
X643633Y525600D01*
X644467Y526600D01*
X644633Y527600D01*
X644300Y528766D01*
X643133Y529600D01*
X641967Y529933D01*
X640467D01*
G01X641967D02*
X642967Y530433D01*
X643800Y531266D01*
X644133Y532267D01*
X643800Y533267D01*
X642967Y534100D01*
X641467Y534600D01*
X639967Y534433D01*
X638467Y533767D01*
G01X651400Y524267D02*
X651067Y524433D01*
Y524767D01*
X651400Y524933D01*
X651733Y524767D01*
Y524433D01*
X651400Y524267D01*
G01X662000Y534600D02*
X660666Y534267D01*
X659667Y533433D01*
X659000Y532433D01*
X658500Y531100D01*
X658333Y529600D01*
X658500Y528100D01*
X659000Y526767D01*
X659667Y525766D01*
X660666Y524933D01*
X662000Y524600D01*
X663333Y524933D01*
X664333Y525766D01*
X665000Y526767D01*
X665500Y528100D01*
X665667Y529600D01*
X665500Y531100D01*
X665000Y532433D01*
X664333Y533433D01*
X663333Y534267D01*
X662000Y534600D01*
G01X672600D02*
X671266Y534267D01*
X670267Y533433D01*
X669600Y532433D01*
X669100Y531100D01*
X668933Y529600D01*
X669100Y528100D01*
X669600Y526767D01*
X670267Y525766D01*
X671266Y524933D01*
X672600Y524600D01*
X673933Y524933D01*
X674933Y525766D01*
X675600Y526767D01*
X676100Y528100D01*
X676267Y529600D01*
X676100Y531100D01*
X675600Y532433D01*
X674933Y533433D01*
X673933Y534267D01*
X672600Y534600D01*
G01X683200Y524600D02*
Y534600D01*
X681200Y532600D01*
G01Y524600D02*
X685200D01*
G01X693800D02*
Y534600D01*
X691800Y532600D01*
G01Y524600D02*
X695800D01*
G01X549667Y511100D02*
Y521100D01*
X554000Y512767D01*
X558333Y521100D01*
Y511100D01*
G01X560433D02*
X564600Y521100D01*
X568767Y511100D01*
G01X567267Y514600D02*
X561933D01*
G01X571533Y511100D02*
Y521100D01*
X574867D01*
X576200Y520600D01*
X577200Y519933D01*
X578033Y518933D01*
X578700Y517766D01*
X578867Y516100D01*
X578700Y514433D01*
X578033Y513267D01*
X577200Y512266D01*
X576200Y511600D01*
X574867Y511100D01*
X571533D01*
G01X589133D02*
X582467D01*
Y521100D01*
X589133D01*
G01X586467Y516267D02*
X582467D01*
G01X605000Y521100D02*
X609000D01*
G01X607000D02*
Y511100D01*
G01X605000D02*
X609000D01*
G01X613767D02*
Y521100D01*
X621433Y511100D01*
Y521100D01*
G01X638800D02*
Y511100D01*
G01X634967Y521100D02*
X642633D01*
G01X645233Y511100D02*
X649400Y521100D01*
X653567Y511100D01*
G01X652067Y514600D02*
X646733D01*
G01X658000Y521100D02*
X662000D01*
G01X660000D02*
Y511100D01*
G01X658000D02*
X662000D01*
G01X665600Y521100D02*
X667933Y511100D01*
X670600Y521100D01*
X673267Y511100D01*
X675600Y521100D01*
G01X677033Y511100D02*
X681200Y521100D01*
X685367Y511100D01*
G01X683867Y514600D02*
X678533D01*
G01X687967Y511100D02*
Y521100D01*
X695633Y511100D01*
Y521100D01*
G01X570067Y494000D02*
Y496500D01*
X571108D01*
X571442Y496375D01*
X571650Y496208D01*
X571733Y495875D01*
X571650Y495542D01*
X571400Y495333D01*
X571108Y495208D01*
X570067D01*
G01X571108D02*
X571733Y494000D01*
G01X573208Y496083D02*
X573458Y496333D01*
X573750Y496458D01*
X574083Y496500D01*
X574500Y496417D01*
X574792Y496208D01*
X574875Y495958D01*
X574833Y495708D01*
X574667Y495500D01*
X573833Y495083D01*
X573458Y494792D01*
X573208Y494375D01*
X573125Y494000D01*
X574875D01*
G01X576392Y494292D02*
X576683Y494083D01*
X577017Y494000D01*
X577350Y494083D01*
X577642Y494333D01*
X577850Y494708D01*
X577933Y495083D01*
Y495542D01*
X577850Y495917D01*
X577642Y496250D01*
X577392Y496417D01*
X577100Y496500D01*
X576767Y496417D01*
X576517Y496250D01*
X576350Y496000D01*
X576267Y495667D01*
X576350Y495375D01*
X576558Y495083D01*
X576808Y494917D01*
X577100Y494875D01*
X577433Y494958D01*
X577683Y495167D01*
X577933Y495542D01*
G01X532433Y559333D02*
X533100Y559833D01*
X533600Y560666D01*
X533933Y561833D01*
X533600Y562833D01*
X532933Y563500D01*
X531767Y564000D01*
X527267D01*
Y554000D01*
X532767D01*
X533933Y554667D01*
X534600Y555667D01*
X534933Y556833D01*
X534600Y558000D01*
X533600Y559000D01*
X532433Y559333D01*
X527267D01*
G01X539367Y554000D02*
Y560666D01*
G01Y559333D02*
X540200Y560000D01*
X541033Y560500D01*
X542200Y560666D01*
X543033Y560500D01*
X544033Y560000D01*
G01X548800Y551000D02*
X549800Y550667D01*
X551133Y551000D01*
X551967Y551667D01*
X552633Y552500D01*
X553633Y555166D01*
X555800Y560666D01*
G01X550467D02*
X553633Y555166D01*
G01X565567Y559833D02*
X564400Y560500D01*
X563400Y560666D01*
X562067Y560333D01*
X561067Y559667D01*
X560400Y558500D01*
X560233Y557333D01*
X560400Y556167D01*
X561067Y555166D01*
X562067Y554333D01*
X563400Y554000D01*
X564567Y554333D01*
X565567Y555000D01*
G01X571000Y558500D02*
X576333D01*
X575833Y559667D01*
X575000Y560333D01*
X573833Y560666D01*
X572667Y560500D01*
X571667Y560000D01*
X571000Y558833D01*
X570667Y557833D01*
Y556833D01*
X571000Y555833D01*
X571833Y554833D01*
X572833Y554167D01*
X574000Y554000D01*
X575167Y554333D01*
X576333Y555333D01*
G01X598367Y563167D02*
X597367Y563667D01*
X596200Y564000D01*
X594867D01*
X593366Y563500D01*
X592200Y562667D01*
X591367Y561667D01*
X590700Y560000D01*
X590533Y558500D01*
X590867Y557000D01*
X591367Y556000D01*
X592367Y555000D01*
X593533Y554333D01*
X594700Y554000D01*
X595867D01*
X597033Y554333D01*
X598033Y554833D01*
X598867Y555500D01*
G01X608300Y554000D02*
Y560666D01*
G01Y559500D02*
X607633Y560167D01*
X606633Y560500D01*
X605467Y560666D01*
X604300Y560333D01*
X603300Y559667D01*
X602633Y558667D01*
X602300Y557333D01*
X602633Y556000D01*
X603300Y555000D01*
X604300Y554333D01*
X605467Y554000D01*
X606633Y554167D01*
X607633Y554667D01*
X608300Y555333D01*
G01X613067Y554000D02*
Y560666D01*
G01Y559000D02*
X613733Y559833D01*
X614733Y560500D01*
X616067Y560666D01*
X617233Y560500D01*
X618233Y559833D01*
X618733Y558667D01*
Y554000D01*
G01X623000Y551000D02*
X624000Y550667D01*
X625333Y551000D01*
X626167Y551667D01*
X626833Y552500D01*
X627833Y555166D01*
X630000Y560666D01*
G01X624667D02*
X627833Y555166D01*
G01X637100Y554000D02*
X636100Y554167D01*
X635100Y554833D01*
X634433Y556000D01*
X634100Y557333D01*
X634433Y558667D01*
X635100Y559833D01*
X636100Y560500D01*
X637100Y560666D01*
X638100Y560500D01*
X639100Y559833D01*
X639767Y558667D01*
X639933Y557333D01*
X639767Y556000D01*
X639100Y554833D01*
X638100Y554167D01*
X637100Y554000D01*
G01X644867D02*
Y560666D01*
G01Y559000D02*
X645533Y559833D01*
X646533Y560500D01*
X647867Y560666D01*
X649033Y560500D01*
X650033Y559833D01*
X650533Y558667D01*
Y554000D01*
G01X665400Y555333D02*
X666733Y554500D01*
X668233Y554000D01*
X669567D01*
X670900Y554500D01*
X671900Y555333D01*
X672400Y556500D01*
X672067Y557666D01*
X671233Y558667D01*
X669733Y559333D01*
X667733Y559667D01*
X666567Y560333D01*
X666067Y561500D01*
X666400Y562667D01*
X667233Y563500D01*
X668400Y564000D01*
X669567D01*
X670733Y563667D01*
X671733Y562833D01*
G01X683167Y563167D02*
X682167Y563667D01*
X681000Y564000D01*
X679667D01*
X678166Y563500D01*
X677000Y562667D01*
X676167Y561667D01*
X675500Y560000D01*
X675333Y558500D01*
X675667Y557000D01*
X676167Y556000D01*
X677167Y555000D01*
X678333Y554333D01*
X679500Y554000D01*
X680667D01*
X681833Y554333D01*
X682833Y554833D01*
X683667Y555500D01*
G01X693767Y563167D02*
X692767Y563667D01*
X691600Y564000D01*
X690267D01*
X688766Y563500D01*
X687600Y562667D01*
X686767Y561667D01*
X686100Y560000D01*
X685933Y558500D01*
X686267Y557000D01*
X686767Y556000D01*
X687767Y555000D01*
X688933Y554333D01*
X690100Y554000D01*
X691267D01*
X692433Y554333D01*
X693433Y554833D01*
X694267Y555500D01*
G01X633826Y30868D02*
X654426D01*
G01X633826Y41868D02*
Y30868D01*
G01X654426Y41868D02*
X633826D01*
G01X625517Y86167D02*
Y88667D01*
X626558D01*
X626892Y88542D01*
X627100Y88375D01*
X627183Y88042D01*
X627100Y87709D01*
X626850Y87500D01*
X626558Y87375D01*
X625517D01*
G01X626558D02*
X627183Y86167D01*
G01X629450D02*
Y88667D01*
X628950Y88167D01*
G01Y86167D02*
X629950D01*
G01X632467D02*
X632550Y86709D01*
X632675Y87167D01*
X632842Y87584D01*
X633050Y88042D01*
X633383Y88667D01*
X631717D01*
G01X634733Y86667D02*
X634983Y86375D01*
X635317Y86209D01*
X635692Y86167D01*
X636025Y86209D01*
X636358Y86417D01*
X636567Y86667D01*
X636608Y86917D01*
X636525Y87209D01*
X636233Y87417D01*
X635942Y87500D01*
X635567D01*
G01X635942D02*
X636192Y87625D01*
X636400Y87834D01*
X636483Y88084D01*
X636400Y88334D01*
X636192Y88542D01*
X635817Y88667D01*
X635442Y88625D01*
X635067Y88459D01*
G01X612517Y86167D02*
Y88667D01*
X613558D01*
X613892Y88542D01*
X614100Y88375D01*
X614183Y88042D01*
X614100Y87709D01*
X613850Y87500D01*
X613558Y87375D01*
X612517D01*
G01X613558D02*
X614183Y86167D01*
G01X616450D02*
Y88667D01*
X615950Y88167D01*
G01Y86167D02*
X616950D01*
G01X619467D02*
X619550Y86709D01*
X619675Y87167D01*
X619842Y87584D01*
X620050Y88042D01*
X620383Y88667D01*
X618717D01*
G01X622650D02*
X622317Y88584D01*
X622067Y88375D01*
X621900Y88125D01*
X621775Y87792D01*
X621733Y87417D01*
X621775Y87042D01*
X621900Y86709D01*
X622067Y86459D01*
X622317Y86250D01*
X622650Y86167D01*
X622983Y86250D01*
X623233Y86459D01*
X623400Y86709D01*
X623525Y87042D01*
X623567Y87417D01*
X623525Y87792D01*
X623400Y88125D01*
X623233Y88375D01*
X622983Y88584D01*
X622650Y88667D01*
G01X641392Y92236D02*
Y96236D01*
X633992D01*
G01X627342Y73553D02*
X624842D01*
Y74594D01*
X624967Y74928D01*
X625134Y75136D01*
X625467Y75219D01*
X625800Y75136D01*
X626009Y74886D01*
X626134Y74594D01*
Y73553D01*
G01Y74594D02*
X627342Y75219D01*
G01Y77486D02*
X624842D01*
X625342Y76986D01*
G01X627342D02*
Y77986D01*
G01Y80503D02*
X626800Y80586D01*
X626342Y80711D01*
X625925Y80878D01*
X625467Y81086D01*
X624842Y81419D01*
Y79753D01*
G01X627342Y84186D02*
X624842D01*
X626634Y82644D01*
Y84728D01*
G01X623242Y73553D02*
X620742D01*
Y74594D01*
X620867Y74928D01*
X621034Y75136D01*
X621367Y75219D01*
X621700Y75136D01*
X621909Y74886D01*
X622034Y74594D01*
Y73553D01*
G01Y74594D02*
X623242Y75219D01*
G01Y77486D02*
X620742D01*
X621242Y76986D01*
G01X623242D02*
Y77986D01*
G01X622200Y79794D02*
X621909Y80086D01*
X621742Y80336D01*
X621659Y80669D01*
X621742Y80961D01*
X621909Y81169D01*
X622159Y81336D01*
X622450Y81378D01*
X622700Y81336D01*
X622950Y81169D01*
X623159Y80919D01*
X623242Y80628D01*
X623159Y80294D01*
X622909Y80003D01*
X622534Y79836D01*
X622117Y79794D01*
X621575Y79878D01*
X621284Y80003D01*
X620992Y80211D01*
X620784Y80503D01*
X620742Y80794D01*
X620825Y81086D01*
X621034Y81294D01*
G01X622950Y82978D02*
X623159Y83269D01*
X623242Y83603D01*
X623159Y83936D01*
X622909Y84228D01*
X622534Y84436D01*
X622159Y84519D01*
X621700D01*
X621325Y84436D01*
X620992Y84228D01*
X620825Y83978D01*
X620742Y83686D01*
X620825Y83353D01*
X620992Y83103D01*
X621242Y82936D01*
X621575Y82853D01*
X621867Y82936D01*
X622159Y83144D01*
X622325Y83394D01*
X622367Y83686D01*
X622284Y84019D01*
X622075Y84269D01*
X621700Y84519D01*
G01X578267Y171792D02*
X578017Y171917D01*
X577725Y172000D01*
X577392D01*
X577017Y171875D01*
X576725Y171667D01*
X576517Y171417D01*
X576350Y171000D01*
X576308Y170625D01*
X576392Y170250D01*
X576517Y170000D01*
X576767Y169750D01*
X577058Y169583D01*
X577350Y169500D01*
X577642D01*
X577933Y169583D01*
X578183Y169708D01*
X578392Y169875D01*
G01X579533Y170000D02*
X579783Y169708D01*
X580117Y169542D01*
X580492Y169500D01*
X580825Y169542D01*
X581158Y169750D01*
X581367Y170000D01*
X581408Y170250D01*
X581325Y170542D01*
X581033Y170750D01*
X580742Y170833D01*
X580367D01*
G01X580742D02*
X580992Y170958D01*
X581200Y171167D01*
X581283Y171417D01*
X581200Y171667D01*
X580992Y171875D01*
X580617Y172000D01*
X580242Y171958D01*
X579867Y171792D01*
G01X582633Y170000D02*
X582883Y169708D01*
X583217Y169542D01*
X583592Y169500D01*
X583925Y169542D01*
X584258Y169750D01*
X584467Y170000D01*
X584508Y170250D01*
X584425Y170542D01*
X584133Y170750D01*
X583842Y170833D01*
X583467D01*
G01X583842D02*
X584092Y170958D01*
X584300Y171167D01*
X584383Y171417D01*
X584300Y171667D01*
X584092Y171875D01*
X583717Y172000D01*
X583342Y171958D01*
X582967Y171792D01*
G01X586650Y169500D02*
X586942Y169542D01*
X587275Y169667D01*
X587483Y169875D01*
X587567Y170167D01*
X587483Y170458D01*
X587233Y170708D01*
X586858Y170833D01*
X586442D01*
X586192Y170917D01*
X585983Y171125D01*
X585900Y171417D01*
X586025Y171708D01*
X586317Y171917D01*
X586650Y172000D01*
X586983Y171917D01*
X587275Y171708D01*
X587400Y171417D01*
X587317Y171125D01*
X587108Y170917D01*
X586858Y170833D01*
X586442D01*
X586067Y170708D01*
X585817Y170458D01*
X585733Y170167D01*
X585817Y169875D01*
X586025Y169667D01*
X586358Y169542D01*
X586650Y169500D01*
G01X594767Y139792D02*
X594517Y139917D01*
X594225Y140000D01*
X593892D01*
X593517Y139875D01*
X593225Y139667D01*
X593017Y139417D01*
X592850Y139000D01*
X592808Y138625D01*
X592892Y138250D01*
X593017Y138000D01*
X593267Y137750D01*
X593558Y137583D01*
X593850Y137500D01*
X594142D01*
X594433Y137583D01*
X594683Y137708D01*
X594892Y137875D01*
G01X596033Y138000D02*
X596283Y137708D01*
X596617Y137542D01*
X596992Y137500D01*
X597325Y137542D01*
X597658Y137750D01*
X597867Y138000D01*
X597908Y138250D01*
X597825Y138542D01*
X597533Y138750D01*
X597242Y138833D01*
X596867D01*
G01X597242D02*
X597492Y138958D01*
X597700Y139167D01*
X597783Y139417D01*
X597700Y139667D01*
X597492Y139875D01*
X597117Y140000D01*
X596742Y139958D01*
X596367Y139792D01*
G01X599133Y138000D02*
X599383Y137708D01*
X599717Y137542D01*
X600092Y137500D01*
X600425Y137542D01*
X600758Y137750D01*
X600967Y138000D01*
X601008Y138250D01*
X600925Y138542D01*
X600633Y138750D01*
X600342Y138833D01*
X599967D01*
G01X600342D02*
X600592Y138958D01*
X600800Y139167D01*
X600883Y139417D01*
X600800Y139667D01*
X600592Y139875D01*
X600217Y140000D01*
X599842Y139958D01*
X599467Y139792D01*
G01X602358Y139583D02*
X602608Y139833D01*
X602900Y139958D01*
X603233Y140000D01*
X603650Y139917D01*
X603942Y139708D01*
X604025Y139458D01*
X603983Y139208D01*
X603817Y139000D01*
X602983Y138583D01*
X602608Y138292D01*
X602358Y137875D01*
X602275Y137500D01*
X604025D01*
G01X594767Y143292D02*
X594517Y143417D01*
X594225Y143500D01*
X593892D01*
X593517Y143375D01*
X593225Y143167D01*
X593017Y142917D01*
X592850Y142500D01*
X592808Y142125D01*
X592892Y141750D01*
X593017Y141500D01*
X593267Y141250D01*
X593558Y141083D01*
X593850Y141000D01*
X594142D01*
X594433Y141083D01*
X594683Y141208D01*
X594892Y141375D01*
G01X596033Y141500D02*
X596283Y141208D01*
X596617Y141042D01*
X596992Y141000D01*
X597325Y141042D01*
X597658Y141250D01*
X597867Y141500D01*
X597908Y141750D01*
X597825Y142042D01*
X597533Y142250D01*
X597242Y142333D01*
X596867D01*
G01X597242D02*
X597492Y142458D01*
X597700Y142667D01*
X597783Y142917D01*
X597700Y143167D01*
X597492Y143375D01*
X597117Y143500D01*
X596742Y143458D01*
X596367Y143292D01*
G01X599133Y141500D02*
X599383Y141208D01*
X599717Y141042D01*
X600092Y141000D01*
X600425Y141042D01*
X600758Y141250D01*
X600967Y141500D01*
X601008Y141750D01*
X600925Y142042D01*
X600633Y142250D01*
X600342Y142333D01*
X599967D01*
G01X600342D02*
X600592Y142458D01*
X600800Y142667D01*
X600883Y142917D01*
X600800Y143167D01*
X600592Y143375D01*
X600217Y143500D01*
X599842Y143458D01*
X599467Y143292D01*
G01X603150Y141000D02*
Y143500D01*
X602650Y143000D01*
G01Y141000D02*
X603650D01*
G01X593615Y132232D02*
X593365Y132357D01*
X593073Y132440D01*
X592740D01*
X592365Y132315D01*
X592073Y132107D01*
X591865Y131857D01*
X591698Y131440D01*
X591656Y131065D01*
X591740Y130690D01*
X591865Y130440D01*
X592115Y130190D01*
X592406Y130023D01*
X592698Y129940D01*
X592990D01*
X593281Y130023D01*
X593531Y130148D01*
X593740Y130315D01*
G01X594881Y130440D02*
X595131Y130148D01*
X595465Y129982D01*
X595840Y129940D01*
X596173Y129982D01*
X596506Y130190D01*
X596715Y130440D01*
X596756Y130690D01*
X596673Y130982D01*
X596381Y131190D01*
X596090Y131273D01*
X595715D01*
G01X596090D02*
X596340Y131398D01*
X596548Y131607D01*
X596631Y131857D01*
X596548Y132107D01*
X596340Y132315D01*
X595965Y132440D01*
X595590Y132398D01*
X595215Y132232D01*
G01X597981Y130440D02*
X598231Y130148D01*
X598565Y129982D01*
X598940Y129940D01*
X599273Y129982D01*
X599606Y130190D01*
X599815Y130440D01*
X599856Y130690D01*
X599773Y130982D01*
X599481Y131190D01*
X599190Y131273D01*
X598815D01*
G01X599190D02*
X599440Y131398D01*
X599648Y131607D01*
X599731Y131857D01*
X599648Y132107D01*
X599440Y132315D01*
X599065Y132440D01*
X598690Y132398D01*
X598315Y132232D01*
G01X601998Y132440D02*
X601665Y132357D01*
X601415Y132148D01*
X601248Y131898D01*
X601123Y131565D01*
X601081Y131190D01*
X601123Y130815D01*
X601248Y130482D01*
X601415Y130232D01*
X601665Y130023D01*
X601998Y129940D01*
X602331Y130023D01*
X602581Y130232D01*
X602748Y130482D01*
X602873Y130815D01*
X602915Y131190D01*
X602873Y131565D01*
X602748Y131898D01*
X602581Y132148D01*
X602331Y132357D01*
X601998Y132440D01*
G01X593515Y135932D02*
X593265Y136057D01*
X592973Y136140D01*
X592640D01*
X592265Y136015D01*
X591973Y135807D01*
X591765Y135557D01*
X591598Y135140D01*
X591556Y134765D01*
X591640Y134390D01*
X591765Y134140D01*
X592015Y133890D01*
X592306Y133723D01*
X592598Y133640D01*
X592890D01*
X593181Y133723D01*
X593431Y133848D01*
X593640Y134015D01*
G01X594781Y134140D02*
X595031Y133848D01*
X595365Y133682D01*
X595740Y133640D01*
X596073Y133682D01*
X596406Y133890D01*
X596615Y134140D01*
X596656Y134390D01*
X596573Y134682D01*
X596281Y134890D01*
X595990Y134973D01*
X595615D01*
G01X595990D02*
X596240Y135098D01*
X596448Y135307D01*
X596531Y135557D01*
X596448Y135807D01*
X596240Y136015D01*
X595865Y136140D01*
X595490Y136098D01*
X595115Y135932D01*
G01X598006Y135723D02*
X598256Y135973D01*
X598548Y136098D01*
X598881Y136140D01*
X599298Y136057D01*
X599590Y135848D01*
X599673Y135598D01*
X599631Y135348D01*
X599465Y135140D01*
X598631Y134723D01*
X598256Y134432D01*
X598006Y134015D01*
X597923Y133640D01*
X599673D01*
G01X601190Y133932D02*
X601481Y133723D01*
X601815Y133640D01*
X602148Y133723D01*
X602440Y133973D01*
X602648Y134348D01*
X602731Y134723D01*
Y135182D01*
X602648Y135557D01*
X602440Y135890D01*
X602190Y136057D01*
X601898Y136140D01*
X601565Y136057D01*
X601315Y135890D01*
X601148Y135640D01*
X601065Y135307D01*
X601148Y135015D01*
X601356Y134723D01*
X601606Y134557D01*
X601898Y134515D01*
X602231Y134598D01*
X602481Y134807D01*
X602731Y135182D01*
G01X626017Y156500D02*
Y159000D01*
X627058D01*
X627392Y158875D01*
X627600Y158708D01*
X627683Y158375D01*
X627600Y158042D01*
X627350Y157833D01*
X627058Y157708D01*
X626017D01*
G01X627058D02*
X627683Y156500D01*
G01X629950D02*
Y159000D01*
X629450Y158500D01*
G01Y156500D02*
X630450D01*
G01X632967D02*
X633050Y157042D01*
X633175Y157500D01*
X633342Y157917D01*
X633550Y158375D01*
X633883Y159000D01*
X632217D01*
G01X636067Y156500D02*
X636150Y157042D01*
X636275Y157500D01*
X636442Y157917D01*
X636650Y158375D01*
X636983Y159000D01*
X635317D01*
G01X620300Y164500D02*
Y160500D01*
X627700D01*
G01X632208Y170267D02*
X632083Y170017D01*
X632000Y169725D01*
Y169392D01*
X632125Y169017D01*
X632333Y168725D01*
X632583Y168517D01*
X633000Y168350D01*
X633375Y168308D01*
X633750Y168392D01*
X634000Y168517D01*
X634250Y168767D01*
X634417Y169058D01*
X634500Y169350D01*
Y169642D01*
X634417Y169933D01*
X634292Y170183D01*
X634125Y170392D01*
G01X634000Y171533D02*
X634292Y171783D01*
X634458Y172117D01*
X634500Y172492D01*
X634458Y172825D01*
X634250Y173158D01*
X634000Y173367D01*
X633750Y173408D01*
X633458Y173325D01*
X633250Y173033D01*
X633167Y172742D01*
Y172367D01*
G01Y172742D02*
X633042Y172992D01*
X632833Y173200D01*
X632583Y173283D01*
X632333Y173200D01*
X632125Y172992D01*
X632000Y172617D01*
X632042Y172242D01*
X632208Y171867D01*
G01X634000Y174633D02*
X634292Y174883D01*
X634458Y175217D01*
X634500Y175592D01*
X634458Y175925D01*
X634250Y176258D01*
X634000Y176467D01*
X633750Y176508D01*
X633458Y176425D01*
X633250Y176133D01*
X633167Y175842D01*
Y175467D01*
G01Y175842D02*
X633042Y176092D01*
X632833Y176300D01*
X632583Y176383D01*
X632333Y176300D01*
X632125Y176092D01*
X632000Y175717D01*
X632042Y175342D01*
X632208Y174967D01*
G01X634500Y179150D02*
X632000D01*
X633792Y177608D01*
Y179692D01*
G01X616208Y171767D02*
X616083Y171517D01*
X616000Y171225D01*
Y170892D01*
X616125Y170517D01*
X616333Y170225D01*
X616583Y170017D01*
X617000Y169850D01*
X617375Y169808D01*
X617750Y169892D01*
X618000Y170017D01*
X618250Y170267D01*
X618417Y170558D01*
X618500Y170850D01*
Y171142D01*
X618417Y171433D01*
X618292Y171683D01*
X618125Y171892D01*
G01X618000Y173033D02*
X618292Y173283D01*
X618458Y173617D01*
X618500Y173992D01*
X618458Y174325D01*
X618250Y174658D01*
X618000Y174867D01*
X617750Y174908D01*
X617458Y174825D01*
X617250Y174533D01*
X617167Y174242D01*
Y173867D01*
G01Y174242D02*
X617042Y174492D01*
X616833Y174700D01*
X616583Y174783D01*
X616333Y174700D01*
X616125Y174492D01*
X616000Y174117D01*
X616042Y173742D01*
X616208Y173367D01*
G01X618000Y176133D02*
X618292Y176383D01*
X618458Y176717D01*
X618500Y177092D01*
X618458Y177425D01*
X618250Y177758D01*
X618000Y177967D01*
X617750Y178008D01*
X617458Y177925D01*
X617250Y177633D01*
X617167Y177342D01*
Y176967D01*
G01Y177342D02*
X617042Y177592D01*
X616833Y177800D01*
X616583Y177883D01*
X616333Y177800D01*
X616125Y177592D01*
X616000Y177217D01*
X616042Y176842D01*
X616208Y176467D01*
G01X618125Y179233D02*
X618333Y179483D01*
X618458Y179775D01*
X618500Y180150D01*
X618417Y180525D01*
X618250Y180817D01*
X617958Y181025D01*
X617625Y181067D01*
X617292Y180983D01*
X617083Y180775D01*
X616917Y180483D01*
X616875Y180192D01*
X616917Y179900D01*
X617083Y179525D01*
X616000Y179650D01*
Y180775D01*
G01X621115Y182671D02*
X629915D01*
Y170271D01*
X621115D01*
Y182671D01*
G01X610500Y229800D02*
X613000D01*
G01X610500Y228842D02*
Y230758D01*
G01X613000Y232067D02*
X610500D01*
Y233067D01*
X610625Y233400D01*
X610917Y233650D01*
X611250Y233733D01*
X611583Y233650D01*
X611833Y233442D01*
X611958Y233067D01*
Y232067D01*
G01X613000Y236000D02*
X610500D01*
X611000Y235500D01*
G01X613000D02*
Y236500D01*
G01X610917Y238308D02*
X610667Y238558D01*
X610542Y238850D01*
X610500Y239183D01*
X610583Y239600D01*
X610792Y239892D01*
X611042Y239975D01*
X611292Y239933D01*
X611500Y239767D01*
X611917Y238933D01*
X612208Y238558D01*
X612625Y238308D01*
X613000Y238225D01*
Y239975D01*
G01Y242200D02*
X612958Y242492D01*
X612833Y242825D01*
X612625Y243033D01*
X612333Y243117D01*
X612042Y243033D01*
X611792Y242783D01*
X611667Y242408D01*
Y241992D01*
X611583Y241742D01*
X611375Y241533D01*
X611083Y241450D01*
X610792Y241575D01*
X610583Y241867D01*
X610500Y242200D01*
X610583Y242533D01*
X610792Y242825D01*
X611083Y242950D01*
X611375Y242867D01*
X611583Y242658D01*
X611667Y242408D01*
Y241992D01*
X611792Y241617D01*
X612042Y241367D01*
X612333Y241283D01*
X612625Y241367D01*
X612833Y241575D01*
X612958Y241908D01*
X613000Y242200D01*
G01X614500Y235800D02*
X617000D01*
G01X614500Y234842D02*
Y236758D01*
G01X617000Y238067D02*
X614500D01*
Y239067D01*
X614625Y239400D01*
X614917Y239650D01*
X615250Y239733D01*
X615583Y239650D01*
X615833Y239442D01*
X615958Y239067D01*
Y238067D01*
G01X617000Y242000D02*
X614500D01*
X615000Y241500D01*
G01X617000D02*
Y242500D01*
G01X614917Y244308D02*
X614667Y244558D01*
X614542Y244850D01*
X614500Y245183D01*
X614583Y245600D01*
X614792Y245892D01*
X615042Y245975D01*
X615292Y245933D01*
X615500Y245767D01*
X615917Y244933D01*
X616208Y244558D01*
X616625Y244308D01*
X617000Y244225D01*
Y245975D01*
G01X616625Y247283D02*
X616833Y247533D01*
X616958Y247825D01*
X617000Y248200D01*
X616917Y248575D01*
X616750Y248867D01*
X616458Y249075D01*
X616125Y249117D01*
X615792Y249033D01*
X615583Y248825D01*
X615417Y248533D01*
X615375Y248242D01*
X615417Y247950D01*
X615583Y247575D01*
X614500Y247700D01*
Y248825D01*
G01X618500Y229800D02*
X621000D01*
G01X618500Y228842D02*
Y230758D01*
G01X621000Y232067D02*
X618500D01*
Y233067D01*
X618625Y233400D01*
X618917Y233650D01*
X619250Y233733D01*
X619583Y233650D01*
X619833Y233442D01*
X619958Y233067D01*
Y232067D01*
G01X621000Y236000D02*
X618500D01*
X619000Y235500D01*
G01X621000D02*
Y236500D01*
G01X618917Y238308D02*
X618667Y238558D01*
X618542Y238850D01*
X618500Y239183D01*
X618583Y239600D01*
X618792Y239892D01*
X619042Y239975D01*
X619292Y239933D01*
X619500Y239767D01*
X619917Y238933D01*
X620208Y238558D01*
X620625Y238308D01*
X621000Y238225D01*
Y239975D01*
G01Y242700D02*
X618500D01*
X620292Y241158D01*
Y243242D01*
G01X626500Y229800D02*
X629000D01*
G01X626500Y228842D02*
Y230758D01*
G01X629000Y232067D02*
X626500D01*
Y233067D01*
X626625Y233400D01*
X626917Y233650D01*
X627250Y233733D01*
X627583Y233650D01*
X627833Y233442D01*
X627958Y233067D01*
Y232067D01*
G01X629000Y236000D02*
X626500D01*
X627000Y235500D01*
G01X629000D02*
Y236500D01*
G01X626917Y238308D02*
X626667Y238558D01*
X626542Y238850D01*
X626500Y239183D01*
X626583Y239600D01*
X626792Y239892D01*
X627042Y239975D01*
X627292Y239933D01*
X627500Y239767D01*
X627917Y238933D01*
X628208Y238558D01*
X628625Y238308D01*
X629000Y238225D01*
Y239975D01*
G01X628500Y241283D02*
X628792Y241533D01*
X628958Y241867D01*
X629000Y242242D01*
X628958Y242575D01*
X628750Y242908D01*
X628500Y243117D01*
X628250Y243158D01*
X627958Y243075D01*
X627750Y242783D01*
X627667Y242492D01*
Y242117D01*
G01Y242492D02*
X627542Y242742D01*
X627333Y242950D01*
X627083Y243033D01*
X626833Y242950D01*
X626625Y242742D01*
X626500Y242367D01*
X626542Y241992D01*
X626708Y241617D01*
G01X630500Y235800D02*
X633000D01*
G01X630500Y234842D02*
Y236758D01*
G01X633000Y238067D02*
X630500D01*
Y239067D01*
X630625Y239400D01*
X630917Y239650D01*
X631250Y239733D01*
X631583Y239650D01*
X631833Y239442D01*
X631958Y239067D01*
Y238067D01*
G01X633000Y242000D02*
X630500D01*
X631000Y241500D01*
G01X633000D02*
Y242500D01*
G01X630917Y244308D02*
X630667Y244558D01*
X630542Y244850D01*
X630500Y245183D01*
X630583Y245600D01*
X630792Y245892D01*
X631042Y245975D01*
X631292Y245933D01*
X631500Y245767D01*
X631917Y244933D01*
X632208Y244558D01*
X632625Y244308D01*
X633000Y244225D01*
Y245975D01*
G01X630917Y247408D02*
X630667Y247658D01*
X630542Y247950D01*
X630500Y248283D01*
X630583Y248700D01*
X630792Y248992D01*
X631042Y249075D01*
X631292Y249033D01*
X631500Y248867D01*
X631917Y248033D01*
X632208Y247658D01*
X632625Y247408D01*
X633000Y247325D01*
Y249075D01*
G01X622500Y235800D02*
X625000D01*
G01X622500Y234842D02*
Y236758D01*
G01X625000Y238067D02*
X622500D01*
Y239067D01*
X622625Y239400D01*
X622917Y239650D01*
X623250Y239733D01*
X623583Y239650D01*
X623833Y239442D01*
X623958Y239067D01*
Y238067D01*
G01X625000Y242000D02*
X622500D01*
X623000Y241500D01*
G01X625000D02*
Y242500D01*
G01X622917Y244308D02*
X622667Y244558D01*
X622542Y244850D01*
X622500Y245183D01*
X622583Y245600D01*
X622792Y245892D01*
X623042Y245975D01*
X623292Y245933D01*
X623500Y245767D01*
X623917Y244933D01*
X624208Y244558D01*
X624625Y244308D01*
X625000Y244225D01*
Y245975D01*
G01Y248200D02*
X622500D01*
X623000Y247700D01*
G01X625000D02*
Y248700D01*
G01X606500Y235800D02*
X609000D01*
G01X606500Y234842D02*
Y236758D01*
G01X609000Y238067D02*
X606500D01*
Y239067D01*
X606625Y239400D01*
X606917Y239650D01*
X607250Y239733D01*
X607583Y239650D01*
X607833Y239442D01*
X607958Y239067D01*
Y238067D01*
G01X609000Y242000D02*
X606500D01*
X607000Y241500D01*
G01X609000D02*
Y242500D01*
G01X606917Y244308D02*
X606667Y244558D01*
X606542Y244850D01*
X606500Y245183D01*
X606583Y245600D01*
X606792Y245892D01*
X607042Y245975D01*
X607292Y245933D01*
X607500Y245767D01*
X607917Y244933D01*
X608208Y244558D01*
X608625Y244308D01*
X609000Y244225D01*
Y245975D01*
G01X606500Y248200D02*
X606583Y247867D01*
X606792Y247617D01*
X607042Y247450D01*
X607375Y247325D01*
X607750Y247283D01*
X608125Y247325D01*
X608458Y247450D01*
X608708Y247617D01*
X608917Y247867D01*
X609000Y248200D01*
X608917Y248533D01*
X608708Y248783D01*
X608458Y248950D01*
X608125Y249075D01*
X607750Y249117D01*
X607375Y249075D01*
X607042Y248950D01*
X606792Y248783D01*
X606583Y248533D01*
X606500Y248200D01*
G01X634000Y229300D02*
X636500D01*
G01X634000Y228342D02*
Y230258D01*
G01X636500Y231567D02*
X634000D01*
Y232567D01*
X634125Y232900D01*
X634417Y233150D01*
X634750Y233233D01*
X635083Y233150D01*
X635333Y232942D01*
X635458Y232567D01*
Y231567D01*
G01X636500Y235500D02*
X634000D01*
X634500Y235000D01*
G01X636500D02*
Y236000D01*
G01Y238600D02*
X634000D01*
X634500Y238100D01*
G01X636500D02*
Y239100D01*
G01X636208Y240992D02*
X636417Y241283D01*
X636500Y241617D01*
X636417Y241950D01*
X636167Y242242D01*
X635792Y242450D01*
X635417Y242533D01*
X634958D01*
X634583Y242450D01*
X634250Y242242D01*
X634083Y241992D01*
X634000Y241700D01*
X634083Y241367D01*
X634250Y241117D01*
X634500Y240950D01*
X634833Y240867D01*
X635125Y240950D01*
X635417Y241158D01*
X635583Y241408D01*
X635625Y241700D01*
X635542Y242033D01*
X635333Y242283D01*
X634958Y242533D01*
G01X622296Y189147D02*
X624046Y191647D01*
G01X622296D02*
X624046Y189147D01*
G01X625479Y191230D02*
X625729Y191480D01*
X626021Y191605D01*
X626354Y191647D01*
X626771Y191564D01*
X627063Y191355D01*
X627146Y191105D01*
X627104Y190855D01*
X626938Y190647D01*
X626104Y190230D01*
X625729Y189939D01*
X625479Y189522D01*
X625396Y189147D01*
X627146D01*
G01X597250Y256850D02*
X600750Y261850D01*
G01X597250D02*
X600750Y256850D01*
G01X603017Y261017D02*
X603517Y261517D01*
X604100Y261767D01*
X604767Y261850D01*
X605600Y261683D01*
X606183Y261267D01*
X606350Y260767D01*
X606267Y260267D01*
X605933Y259850D01*
X604267Y259017D01*
X603517Y258433D01*
X603017Y257600D01*
X602850Y256850D01*
X606350D01*
G01X610200Y256683D02*
X610033Y256767D01*
Y256933D01*
X610200Y257017D01*
X610367Y256933D01*
Y256767D01*
X610200Y256683D01*
G01Y258933D02*
X610033Y259017D01*
Y259183D01*
X610200Y259267D01*
X610367Y259183D01*
Y259017D01*
X610200Y258933D01*
G01X614217Y261017D02*
X614717Y261517D01*
X615300Y261767D01*
X615967Y261850D01*
X616800Y261683D01*
X617383Y261267D01*
X617550Y260767D01*
X617467Y260267D01*
X617133Y259850D01*
X615467Y259017D01*
X614717Y258433D01*
X614217Y257600D01*
X614050Y256850D01*
X617550D01*
G01X619567Y257600D02*
X620067Y257183D01*
X620650Y256933D01*
X621400Y256850D01*
X622150Y257017D01*
X622733Y257350D01*
X623150Y257933D01*
X623233Y258600D01*
X623067Y259267D01*
X622650Y259683D01*
X622067Y260017D01*
X621483Y260100D01*
X620900Y260017D01*
X620150Y259683D01*
X620400Y261850D01*
X622650D01*
G01X624833Y256850D02*
Y261850D01*
X627000Y257683D01*
X629167Y261850D01*
Y256850D01*
G01X630850D02*
Y261850D01*
G01X634350D02*
Y256850D01*
G01Y259350D02*
X630850D01*
G01X636617Y261850D02*
X639783D01*
X636617Y256850D01*
X639783D01*
G01X614211Y265422D02*
X611711D01*
Y266463D01*
X611836Y266797D01*
X612003Y267005D01*
X612336Y267088D01*
X612669Y267005D01*
X612878Y266755D01*
X613003Y266463D01*
Y265422D01*
G01Y266463D02*
X614211Y267088D01*
G01X613711Y268438D02*
X614003Y268688D01*
X614169Y269022D01*
X614211Y269397D01*
X614169Y269730D01*
X613961Y270063D01*
X613711Y270272D01*
X613461Y270313D01*
X613169Y270230D01*
X612961Y269938D01*
X612878Y269647D01*
Y269272D01*
G01Y269647D02*
X612753Y269897D01*
X612544Y270105D01*
X612294Y270188D01*
X612044Y270105D01*
X611836Y269897D01*
X611711Y269522D01*
X611753Y269147D01*
X611919Y268772D01*
G01X612128Y271663D02*
X611878Y271913D01*
X611753Y272205D01*
X611711Y272538D01*
X611794Y272955D01*
X612003Y273247D01*
X612253Y273330D01*
X612503Y273288D01*
X612711Y273122D01*
X613128Y272288D01*
X613419Y271913D01*
X613836Y271663D01*
X614211Y271580D01*
Y273330D01*
G01X613836Y274638D02*
X614044Y274888D01*
X614169Y275180D01*
X614211Y275555D01*
X614128Y275930D01*
X613961Y276222D01*
X613669Y276430D01*
X613336Y276472D01*
X613003Y276388D01*
X612794Y276180D01*
X612628Y275888D01*
X612586Y275597D01*
X612628Y275305D01*
X612794Y274930D01*
X611711Y275055D01*
Y276180D01*
G01X615211Y285605D02*
X611211D01*
Y278205D01*
G01X609711Y265422D02*
X607211D01*
Y266463D01*
X607336Y266797D01*
X607503Y267005D01*
X607836Y267088D01*
X608169Y267005D01*
X608378Y266755D01*
X608503Y266463D01*
Y265422D01*
G01Y266463D02*
X609711Y267088D01*
G01X609211Y268438D02*
X609503Y268688D01*
X609669Y269022D01*
X609711Y269397D01*
X609669Y269730D01*
X609461Y270063D01*
X609211Y270272D01*
X608961Y270313D01*
X608669Y270230D01*
X608461Y269938D01*
X608378Y269647D01*
Y269272D01*
G01Y269647D02*
X608253Y269897D01*
X608044Y270105D01*
X607794Y270188D01*
X607544Y270105D01*
X607336Y269897D01*
X607211Y269522D01*
X607253Y269147D01*
X607419Y268772D01*
G01X607628Y271663D02*
X607378Y271913D01*
X607253Y272205D01*
X607211Y272538D01*
X607294Y272955D01*
X607503Y273247D01*
X607753Y273330D01*
X608003Y273288D01*
X608211Y273122D01*
X608628Y272288D01*
X608919Y271913D01*
X609336Y271663D01*
X609711Y271580D01*
Y273330D01*
G01Y275555D02*
X609669Y275847D01*
X609544Y276180D01*
X609336Y276388D01*
X609044Y276472D01*
X608753Y276388D01*
X608503Y276138D01*
X608378Y275763D01*
Y275347D01*
X608294Y275097D01*
X608086Y274888D01*
X607794Y274805D01*
X607503Y274930D01*
X607294Y275222D01*
X607211Y275555D01*
X607294Y275888D01*
X607503Y276180D01*
X607794Y276305D01*
X608086Y276222D01*
X608294Y276013D01*
X608378Y275763D01*
Y275347D01*
X608503Y274972D01*
X608753Y274722D01*
X609044Y274638D01*
X609336Y274722D01*
X609544Y274930D01*
X609669Y275263D01*
X609711Y275555D01*
G01X610711Y285605D02*
X606711D01*
Y278205D01*
G01X581054Y278017D02*
Y280517D01*
X582095D01*
X582429Y280392D01*
X582637Y280225D01*
X582720Y279892D01*
X582637Y279559D01*
X582387Y279350D01*
X582095Y279225D01*
X581054D01*
G01X582095D02*
X582720Y278017D01*
G01X584070Y278517D02*
X584320Y278225D01*
X584654Y278059D01*
X585029Y278017D01*
X585362Y278059D01*
X585695Y278267D01*
X585904Y278517D01*
X585945Y278767D01*
X585862Y279059D01*
X585570Y279267D01*
X585279Y279350D01*
X584904D01*
G01X585279D02*
X585529Y279475D01*
X585737Y279684D01*
X585820Y279934D01*
X585737Y280184D01*
X585529Y280392D01*
X585154Y280517D01*
X584779Y280475D01*
X584404Y280309D01*
G01X587170Y278392D02*
X587420Y278184D01*
X587712Y278059D01*
X588087Y278017D01*
X588462Y278100D01*
X588754Y278267D01*
X588962Y278559D01*
X589004Y278892D01*
X588920Y279225D01*
X588712Y279434D01*
X588420Y279600D01*
X588129Y279642D01*
X587837Y279600D01*
X587462Y279434D01*
X587587Y280517D01*
X588712D01*
G01X590395Y280100D02*
X590645Y280350D01*
X590937Y280475D01*
X591270Y280517D01*
X591687Y280434D01*
X591979Y280225D01*
X592062Y279975D01*
X592020Y279725D01*
X591854Y279517D01*
X591020Y279100D01*
X590645Y278809D01*
X590395Y278392D01*
X590312Y278017D01*
X592062D01*
G01X595337Y282017D02*
Y278017D01*
X602737D01*
G01X617017Y271000D02*
Y273500D01*
X618058D01*
X618392Y273375D01*
X618600Y273208D01*
X618683Y272875D01*
X618600Y272542D01*
X618350Y272333D01*
X618058Y272208D01*
X617017D01*
G01X618058D02*
X618683Y271000D01*
G01X620033Y271500D02*
X620283Y271208D01*
X620617Y271042D01*
X620992Y271000D01*
X621325Y271042D01*
X621658Y271250D01*
X621867Y271500D01*
X621908Y271750D01*
X621825Y272042D01*
X621533Y272250D01*
X621242Y272333D01*
X620867D01*
G01X621242D02*
X621492Y272458D01*
X621700Y272667D01*
X621783Y272917D01*
X621700Y273167D01*
X621492Y273375D01*
X621117Y273500D01*
X620742Y273458D01*
X620367Y273292D01*
G01X623133Y271375D02*
X623383Y271167D01*
X623675Y271042D01*
X624050Y271000D01*
X624425Y271083D01*
X624717Y271250D01*
X624925Y271542D01*
X624967Y271875D01*
X624883Y272208D01*
X624675Y272417D01*
X624383Y272583D01*
X624092Y272625D01*
X623800Y272583D01*
X623425Y272417D01*
X623550Y273500D01*
X624675D01*
G01X626233Y271500D02*
X626483Y271208D01*
X626817Y271042D01*
X627192Y271000D01*
X627525Y271042D01*
X627858Y271250D01*
X628067Y271500D01*
X628108Y271750D01*
X628025Y272042D01*
X627733Y272250D01*
X627442Y272333D01*
X627067D01*
G01X627442D02*
X627692Y272458D01*
X627900Y272667D01*
X627983Y272917D01*
X627900Y273167D01*
X627692Y273375D01*
X627317Y273500D01*
X626942Y273458D01*
X626567Y273292D01*
G01X619800Y280745D02*
Y276745D01*
X627200D01*
G01X630017Y271000D02*
Y273500D01*
X631058D01*
X631392Y273375D01*
X631600Y273208D01*
X631683Y272875D01*
X631600Y272542D01*
X631350Y272333D01*
X631058Y272208D01*
X630017D01*
G01X631058D02*
X631683Y271000D01*
G01X633033Y271500D02*
X633283Y271208D01*
X633617Y271042D01*
X633992Y271000D01*
X634325Y271042D01*
X634658Y271250D01*
X634867Y271500D01*
X634908Y271750D01*
X634825Y272042D01*
X634533Y272250D01*
X634242Y272333D01*
X633867D01*
G01X634242D02*
X634492Y272458D01*
X634700Y272667D01*
X634783Y272917D01*
X634700Y273167D01*
X634492Y273375D01*
X634117Y273500D01*
X633742Y273458D01*
X633367Y273292D01*
G01X636133Y271375D02*
X636383Y271167D01*
X636675Y271042D01*
X637050Y271000D01*
X637425Y271083D01*
X637717Y271250D01*
X637925Y271542D01*
X637967Y271875D01*
X637883Y272208D01*
X637675Y272417D01*
X637383Y272583D01*
X637092Y272625D01*
X636800Y272583D01*
X636425Y272417D01*
X636550Y273500D01*
X637675D01*
G01X639442Y271292D02*
X639733Y271083D01*
X640067Y271000D01*
X640400Y271083D01*
X640692Y271333D01*
X640900Y271708D01*
X640983Y272083D01*
Y272542D01*
X640900Y272917D01*
X640692Y273250D01*
X640442Y273417D01*
X640150Y273500D01*
X639817Y273417D01*
X639567Y273250D01*
X639400Y273000D01*
X639317Y272667D01*
X639400Y272375D01*
X639608Y272083D01*
X639858Y271917D01*
X640150Y271875D01*
X640483Y271958D01*
X640733Y272167D01*
X640983Y272542D01*
G01X634700Y276745D02*
Y280745D01*
X627300D01*
G01X637267Y296459D02*
X637017Y296584D01*
X636725Y296667D01*
X636392D01*
X636017Y296542D01*
X635725Y296334D01*
X635517Y296084D01*
X635350Y295667D01*
X635308Y295292D01*
X635392Y294917D01*
X635517Y294667D01*
X635767Y294417D01*
X636058Y294250D01*
X636350Y294167D01*
X636642D01*
X636933Y294250D01*
X637183Y294375D01*
X637392Y294542D01*
G01X638533D02*
X638783Y294334D01*
X639075Y294209D01*
X639450Y294167D01*
X639825Y294250D01*
X640117Y294417D01*
X640325Y294709D01*
X640367Y295042D01*
X640283Y295375D01*
X640075Y295584D01*
X639783Y295750D01*
X639492Y295792D01*
X639200Y295750D01*
X638825Y295584D01*
X638950Y296667D01*
X640075D01*
G01X641758Y296250D02*
X642008Y296500D01*
X642300Y296625D01*
X642633Y296667D01*
X643050Y296584D01*
X643342Y296375D01*
X643425Y296125D01*
X643383Y295875D01*
X643217Y295667D01*
X642383Y295250D01*
X642008Y294959D01*
X641758Y294542D01*
X641675Y294167D01*
X643425D01*
G01X645650D02*
Y296667D01*
X645150Y296167D01*
G01Y294167D02*
X646150D01*
G01X582804Y284309D02*
X582554Y284434D01*
X582262Y284517D01*
X581929D01*
X581554Y284392D01*
X581262Y284184D01*
X581054Y283934D01*
X580887Y283517D01*
X580845Y283142D01*
X580929Y282767D01*
X581054Y282517D01*
X581304Y282267D01*
X581595Y282100D01*
X581887Y282017D01*
X582179D01*
X582470Y282100D01*
X582720Y282225D01*
X582929Y282392D01*
G01X584070D02*
X584320Y282184D01*
X584612Y282059D01*
X584987Y282017D01*
X585362Y282100D01*
X585654Y282267D01*
X585862Y282559D01*
X585904Y282892D01*
X585820Y283225D01*
X585612Y283434D01*
X585320Y283600D01*
X585029Y283642D01*
X584737Y283600D01*
X584362Y283434D01*
X584487Y284517D01*
X585612D01*
G01X587170Y282517D02*
X587420Y282225D01*
X587754Y282059D01*
X588129Y282017D01*
X588462Y282059D01*
X588795Y282267D01*
X589004Y282517D01*
X589045Y282767D01*
X588962Y283059D01*
X588670Y283267D01*
X588379Y283350D01*
X588004D01*
G01X588379D02*
X588629Y283475D01*
X588837Y283684D01*
X588920Y283934D01*
X588837Y284184D01*
X588629Y284392D01*
X588254Y284517D01*
X587879Y284475D01*
X587504Y284309D01*
G01X590395Y284100D02*
X590645Y284350D01*
X590937Y284475D01*
X591270Y284517D01*
X591687Y284434D01*
X591979Y284225D01*
X592062Y283975D01*
X592020Y283725D01*
X591854Y283517D01*
X591020Y283100D01*
X590645Y282809D01*
X590395Y282392D01*
X590312Y282017D01*
X592062D01*
G01X634867Y285292D02*
X634617Y285417D01*
X634325Y285500D01*
X633992D01*
X633617Y285375D01*
X633325Y285167D01*
X633117Y284917D01*
X632950Y284500D01*
X632908Y284125D01*
X632992Y283750D01*
X633117Y283500D01*
X633367Y283250D01*
X633658Y283083D01*
X633950Y283000D01*
X634242D01*
X634533Y283083D01*
X634783Y283208D01*
X634992Y283375D01*
G01X636133D02*
X636383Y283167D01*
X636675Y283042D01*
X637050Y283000D01*
X637425Y283083D01*
X637717Y283250D01*
X637925Y283542D01*
X637967Y283875D01*
X637883Y284208D01*
X637675Y284417D01*
X637383Y284583D01*
X637092Y284625D01*
X636800Y284583D01*
X636425Y284417D01*
X636550Y285500D01*
X637675D01*
G01X639233Y283500D02*
X639483Y283208D01*
X639817Y283042D01*
X640192Y283000D01*
X640525Y283042D01*
X640858Y283250D01*
X641067Y283500D01*
X641108Y283750D01*
X641025Y284042D01*
X640733Y284250D01*
X640442Y284333D01*
X640067D01*
G01X640442D02*
X640692Y284458D01*
X640900Y284667D01*
X640983Y284917D01*
X640900Y285167D01*
X640692Y285375D01*
X640317Y285500D01*
X639942Y285458D01*
X639567Y285292D01*
G01X643750Y283000D02*
Y285500D01*
X642208Y283708D01*
X644292D01*
G01X596500Y291483D02*
X598292D01*
X598667Y291650D01*
X598917Y291983D01*
X599000Y292400D01*
X598917Y292817D01*
X598667Y293150D01*
X598292Y293317D01*
X596500D01*
G01X596917Y294708D02*
X596667Y294958D01*
X596542Y295250D01*
X596500Y295583D01*
X596583Y296000D01*
X596792Y296292D01*
X597042Y296375D01*
X597292Y296333D01*
X597500Y296167D01*
X597917Y295333D01*
X598208Y294958D01*
X598625Y294708D01*
X599000Y294625D01*
Y296375D01*
G01X597958Y297808D02*
X597667Y298100D01*
X597500Y298350D01*
X597417Y298683D01*
X597500Y298975D01*
X597667Y299183D01*
X597917Y299350D01*
X598208Y299392D01*
X598458Y299350D01*
X598708Y299183D01*
X598917Y298933D01*
X599000Y298642D01*
X598917Y298308D01*
X598667Y298017D01*
X598292Y297850D01*
X597875Y297808D01*
X597333Y297892D01*
X597042Y298017D01*
X596750Y298225D01*
X596542Y298517D01*
X596500Y298808D01*
X596583Y299100D01*
X596792Y299308D01*
G01X609170Y307189D02*
X617170D01*
Y294789D01*
X609170D01*
Y307189D01*
G01X578517Y345500D02*
Y348000D01*
X579558D01*
X579892Y347875D01*
X580100Y347708D01*
X580183Y347375D01*
X580100Y347042D01*
X579850Y346833D01*
X579558Y346708D01*
X578517D01*
G01X579558D02*
X580183Y345500D01*
G01X582950D02*
Y348000D01*
X581408Y346208D01*
X583492D01*
G01X586050Y345500D02*
Y348000D01*
X584508Y346208D01*
X586592D01*
G01X587733Y345875D02*
X587983Y345667D01*
X588275Y345542D01*
X588650Y345500D01*
X589025Y345583D01*
X589317Y345750D01*
X589525Y346042D01*
X589567Y346375D01*
X589483Y346708D01*
X589275Y346917D01*
X588983Y347083D01*
X588692Y347125D01*
X588400Y347083D01*
X588025Y346917D01*
X588150Y348000D01*
X589275D01*
G01X599200Y344950D02*
Y348950D01*
X591800D01*
G01X626517Y355500D02*
Y358000D01*
X627558D01*
X627892Y357875D01*
X628100Y357708D01*
X628183Y357375D01*
X628100Y357042D01*
X627850Y356833D01*
X627558Y356708D01*
X626517D01*
G01X627558D02*
X628183Y355500D01*
G01X629658Y357583D02*
X629908Y357833D01*
X630200Y357958D01*
X630533Y358000D01*
X630950Y357917D01*
X631242Y357708D01*
X631325Y357458D01*
X631283Y357208D01*
X631117Y357000D01*
X630283Y356583D01*
X629908Y356292D01*
X629658Y355875D01*
X629575Y355500D01*
X631325D01*
G01X633550D02*
X633842Y355542D01*
X634175Y355667D01*
X634383Y355875D01*
X634467Y356167D01*
X634383Y356458D01*
X634133Y356708D01*
X633758Y356833D01*
X633342D01*
X633092Y356917D01*
X632883Y357125D01*
X632800Y357417D01*
X632925Y357708D01*
X633217Y357917D01*
X633550Y358000D01*
X633883Y357917D01*
X634175Y357708D01*
X634300Y357417D01*
X634217Y357125D01*
X634008Y356917D01*
X633758Y356833D01*
X633342D01*
X632967Y356708D01*
X632717Y356458D01*
X632633Y356167D01*
X632717Y355875D01*
X632925Y355667D01*
X633258Y355542D01*
X633550Y355500D01*
G01X635858Y356542D02*
X636150Y356833D01*
X636400Y357000D01*
X636733Y357083D01*
X637025Y357000D01*
X637233Y356833D01*
X637400Y356583D01*
X637442Y356292D01*
X637400Y356042D01*
X637233Y355792D01*
X636983Y355583D01*
X636692Y355500D01*
X636358Y355583D01*
X636067Y355833D01*
X635900Y356208D01*
X635858Y356625D01*
X635942Y357167D01*
X636067Y357458D01*
X636275Y357750D01*
X636567Y357958D01*
X636858Y358000D01*
X637150Y357917D01*
X637358Y357708D01*
G01X603123Y350729D02*
Y354729D01*
X595723D01*
G01X603123D02*
Y358729D01*
X595723D01*
G01X584500Y321017D02*
X582000D01*
Y322058D01*
X582125Y322392D01*
X582292Y322600D01*
X582625Y322683D01*
X582958Y322600D01*
X583167Y322350D01*
X583292Y322058D01*
Y321017D01*
G01Y322058D02*
X584500Y322683D01*
G01X584000Y324033D02*
X584292Y324283D01*
X584458Y324617D01*
X584500Y324992D01*
X584458Y325325D01*
X584250Y325658D01*
X584000Y325867D01*
X583750Y325908D01*
X583458Y325825D01*
X583250Y325533D01*
X583167Y325242D01*
Y324867D01*
G01Y325242D02*
X583042Y325492D01*
X582833Y325700D01*
X582583Y325783D01*
X582333Y325700D01*
X582125Y325492D01*
X582000Y325117D01*
X582042Y324742D01*
X582208Y324367D01*
G01X582417Y327258D02*
X582167Y327508D01*
X582042Y327800D01*
X582000Y328133D01*
X582083Y328550D01*
X582292Y328842D01*
X582542Y328925D01*
X582792Y328883D01*
X583000Y328717D01*
X583417Y327883D01*
X583708Y327508D01*
X584125Y327258D01*
X584500Y327175D01*
Y328925D01*
G01Y331150D02*
X582000D01*
X582500Y330650D01*
G01X584500D02*
Y331650D01*
G01X588350Y325050D02*
X592350D01*
Y332450D01*
G01X628700Y314517D02*
X626200D01*
Y315558D01*
X626325Y315892D01*
X626492Y316100D01*
X626825Y316183D01*
X627158Y316100D01*
X627367Y315850D01*
X627492Y315558D01*
Y314517D01*
G01Y315558D02*
X628700Y316183D01*
G01X628200Y317533D02*
X628492Y317783D01*
X628658Y318117D01*
X628700Y318492D01*
X628658Y318825D01*
X628450Y319158D01*
X628200Y319367D01*
X627950Y319408D01*
X627658Y319325D01*
X627450Y319033D01*
X627367Y318742D01*
Y318367D01*
G01Y318742D02*
X627242Y318992D01*
X627033Y319200D01*
X626783Y319283D01*
X626533Y319200D01*
X626325Y318992D01*
X626200Y318617D01*
X626242Y318242D01*
X626408Y317867D01*
G01X626617Y320758D02*
X626367Y321008D01*
X626242Y321300D01*
X626200Y321633D01*
X626283Y322050D01*
X626492Y322342D01*
X626742Y322425D01*
X626992Y322383D01*
X627200Y322217D01*
X627617Y321383D01*
X627908Y321008D01*
X628325Y320758D01*
X628700Y320675D01*
Y322425D01*
G01X626617Y323858D02*
X626367Y324108D01*
X626242Y324400D01*
X626200Y324733D01*
X626283Y325150D01*
X626492Y325442D01*
X626742Y325525D01*
X626992Y325483D01*
X627200Y325317D01*
X627617Y324483D01*
X627908Y324108D01*
X628325Y323858D01*
X628700Y323775D01*
Y325525D01*
G01X616900Y317400D02*
X620900D01*
Y324800D01*
G01X637500Y314517D02*
X635000D01*
Y315558D01*
X635125Y315892D01*
X635292Y316100D01*
X635625Y316183D01*
X635958Y316100D01*
X636167Y315850D01*
X636292Y315558D01*
Y314517D01*
G01Y315558D02*
X637500Y316183D01*
G01X637000Y317533D02*
X637292Y317783D01*
X637458Y318117D01*
X637500Y318492D01*
X637458Y318825D01*
X637250Y319158D01*
X637000Y319367D01*
X636750Y319408D01*
X636458Y319325D01*
X636250Y319033D01*
X636167Y318742D01*
Y318367D01*
G01Y318742D02*
X636042Y318992D01*
X635833Y319200D01*
X635583Y319283D01*
X635333Y319200D01*
X635125Y318992D01*
X635000Y318617D01*
X635042Y318242D01*
X635208Y317867D01*
G01X635417Y320758D02*
X635167Y321008D01*
X635042Y321300D01*
X635000Y321633D01*
X635083Y322050D01*
X635292Y322342D01*
X635542Y322425D01*
X635792Y322383D01*
X636000Y322217D01*
X636417Y321383D01*
X636708Y321008D01*
X637125Y320758D01*
X637500Y320675D01*
Y322425D01*
G01X637000Y323733D02*
X637292Y323983D01*
X637458Y324317D01*
X637500Y324692D01*
X637458Y325025D01*
X637250Y325358D01*
X637000Y325567D01*
X636750Y325608D01*
X636458Y325525D01*
X636250Y325233D01*
X636167Y324942D01*
Y324567D01*
G01Y324942D02*
X636042Y325192D01*
X635833Y325400D01*
X635583Y325483D01*
X635333Y325400D01*
X635125Y325192D01*
X635000Y324817D01*
X635042Y324442D01*
X635208Y324067D01*
G01X629800Y317300D02*
X633800D01*
Y324700D01*
G01X585804Y316456D02*
Y318956D01*
X586845D01*
X587179Y318831D01*
X587387Y318664D01*
X587470Y318331D01*
X587387Y317998D01*
X587137Y317789D01*
X586845Y317664D01*
X585804D01*
G01X586845D02*
X587470Y316456D01*
G01X588820Y316956D02*
X589070Y316664D01*
X589404Y316498D01*
X589779Y316456D01*
X590112Y316498D01*
X590445Y316706D01*
X590654Y316956D01*
X590695Y317206D01*
X590612Y317498D01*
X590320Y317706D01*
X590029Y317789D01*
X589654D01*
G01X590029D02*
X590279Y317914D01*
X590487Y318123D01*
X590570Y318373D01*
X590487Y318623D01*
X590279Y318831D01*
X589904Y318956D01*
X589529Y318914D01*
X589154Y318748D01*
G01X592045Y318539D02*
X592295Y318789D01*
X592587Y318914D01*
X592920Y318956D01*
X593337Y318873D01*
X593629Y318664D01*
X593712Y318414D01*
X593670Y318164D01*
X593504Y317956D01*
X592670Y317539D01*
X592295Y317248D01*
X592045Y316831D01*
X591962Y316456D01*
X593712D01*
G01X595145Y317498D02*
X595437Y317789D01*
X595687Y317956D01*
X596020Y318039D01*
X596312Y317956D01*
X596520Y317789D01*
X596687Y317539D01*
X596729Y317248D01*
X596687Y316998D01*
X596520Y316748D01*
X596270Y316539D01*
X595979Y316456D01*
X595645Y316539D01*
X595354Y316789D01*
X595187Y317164D01*
X595145Y317581D01*
X595229Y318123D01*
X595354Y318414D01*
X595562Y318706D01*
X595854Y318914D01*
X596145Y318956D01*
X596437Y318873D01*
X596645Y318664D01*
G01X605987Y320456D02*
Y324456D01*
X598587D01*
G01X585804Y320656D02*
Y323156D01*
X586845D01*
X587179Y323031D01*
X587387Y322864D01*
X587470Y322531D01*
X587387Y322198D01*
X587137Y321989D01*
X586845Y321864D01*
X585804D01*
G01X586845D02*
X587470Y320656D01*
G01X588820Y321156D02*
X589070Y320864D01*
X589404Y320698D01*
X589779Y320656D01*
X590112Y320698D01*
X590445Y320906D01*
X590654Y321156D01*
X590695Y321406D01*
X590612Y321698D01*
X590320Y321906D01*
X590029Y321989D01*
X589654D01*
G01X590029D02*
X590279Y322114D01*
X590487Y322323D01*
X590570Y322573D01*
X590487Y322823D01*
X590279Y323031D01*
X589904Y323156D01*
X589529Y323114D01*
X589154Y322948D01*
G01X592045Y322739D02*
X592295Y322989D01*
X592587Y323114D01*
X592920Y323156D01*
X593337Y323073D01*
X593629Y322864D01*
X593712Y322614D01*
X593670Y322364D01*
X593504Y322156D01*
X592670Y321739D01*
X592295Y321448D01*
X592045Y321031D01*
X591962Y320656D01*
X593712D01*
G01X595854D02*
X595937Y321198D01*
X596062Y321656D01*
X596229Y322073D01*
X596437Y322531D01*
X596770Y323156D01*
X595104D01*
G01X605987Y324656D02*
Y328656D01*
X598587D01*
G01X583517Y350500D02*
Y353000D01*
X584558D01*
X584892Y352875D01*
X585100Y352708D01*
X585183Y352375D01*
X585100Y352042D01*
X584850Y351833D01*
X584558Y351708D01*
X583517D01*
G01X584558D02*
X585183Y350500D01*
G01X586533Y351000D02*
X586783Y350708D01*
X587117Y350542D01*
X587492Y350500D01*
X587825Y350542D01*
X588158Y350750D01*
X588367Y351000D01*
X588408Y351250D01*
X588325Y351542D01*
X588033Y351750D01*
X587742Y351833D01*
X587367D01*
G01X587742D02*
X587992Y351958D01*
X588200Y352167D01*
X588283Y352417D01*
X588200Y352667D01*
X587992Y352875D01*
X587617Y353000D01*
X587242Y352958D01*
X586867Y352792D01*
G01X589758Y352583D02*
X590008Y352833D01*
X590300Y352958D01*
X590633Y353000D01*
X591050Y352917D01*
X591342Y352708D01*
X591425Y352458D01*
X591383Y352208D01*
X591217Y352000D01*
X590383Y351583D01*
X590008Y351292D01*
X589758Y350875D01*
X589675Y350500D01*
X591425D01*
G01X592942Y350792D02*
X593233Y350583D01*
X593567Y350500D01*
X593900Y350583D01*
X594192Y350833D01*
X594400Y351208D01*
X594483Y351583D01*
Y352042D01*
X594400Y352417D01*
X594192Y352750D01*
X593942Y352917D01*
X593650Y353000D01*
X593317Y352917D01*
X593067Y352750D01*
X592900Y352500D01*
X592817Y352167D01*
X592900Y351875D01*
X593108Y351583D01*
X593358Y351417D01*
X593650Y351375D01*
X593983Y351458D01*
X594233Y351667D01*
X594483Y352042D01*
G01X627750Y346900D02*
Y350900D01*
X620350D01*
G01X583517Y355000D02*
Y357500D01*
X584558D01*
X584892Y357375D01*
X585100Y357208D01*
X585183Y356875D01*
X585100Y356542D01*
X584850Y356333D01*
X584558Y356208D01*
X583517D01*
G01X584558D02*
X585183Y355000D01*
G01X586533Y355500D02*
X586783Y355208D01*
X587117Y355042D01*
X587492Y355000D01*
X587825Y355042D01*
X588158Y355250D01*
X588367Y355500D01*
X588408Y355750D01*
X588325Y356042D01*
X588033Y356250D01*
X587742Y356333D01*
X587367D01*
G01X587742D02*
X587992Y356458D01*
X588200Y356667D01*
X588283Y356917D01*
X588200Y357167D01*
X587992Y357375D01*
X587617Y357500D01*
X587242Y357458D01*
X586867Y357292D01*
G01X589633Y355500D02*
X589883Y355208D01*
X590217Y355042D01*
X590592Y355000D01*
X590925Y355042D01*
X591258Y355250D01*
X591467Y355500D01*
X591508Y355750D01*
X591425Y356042D01*
X591133Y356250D01*
X590842Y356333D01*
X590467D01*
G01X590842D02*
X591092Y356458D01*
X591300Y356667D01*
X591383Y356917D01*
X591300Y357167D01*
X591092Y357375D01*
X590717Y357500D01*
X590342Y357458D01*
X589967Y357292D01*
G01X593650Y357500D02*
X593317Y357417D01*
X593067Y357208D01*
X592900Y356958D01*
X592775Y356625D01*
X592733Y356250D01*
X592775Y355875D01*
X592900Y355542D01*
X593067Y355292D01*
X593317Y355083D01*
X593650Y355000D01*
X593983Y355083D01*
X594233Y355292D01*
X594400Y355542D01*
X594525Y355875D01*
X594567Y356250D01*
X594525Y356625D01*
X594400Y356958D01*
X594233Y357208D01*
X593983Y357417D01*
X593650Y357500D01*
G01X625250Y351400D02*
Y355400D01*
X617850D01*
G01X595017Y308500D02*
Y311000D01*
X596058D01*
X596392Y310875D01*
X596600Y310708D01*
X596683Y310375D01*
X596600Y310042D01*
X596350Y309833D01*
X596058Y309708D01*
X595017D01*
G01X596058D02*
X596683Y308500D01*
G01X598033Y309000D02*
X598283Y308708D01*
X598617Y308542D01*
X598992Y308500D01*
X599325Y308542D01*
X599658Y308750D01*
X599867Y309000D01*
X599908Y309250D01*
X599825Y309542D01*
X599533Y309750D01*
X599242Y309833D01*
X598867D01*
G01X599242D02*
X599492Y309958D01*
X599700Y310167D01*
X599783Y310417D01*
X599700Y310667D01*
X599492Y310875D01*
X599117Y311000D01*
X598742Y310958D01*
X598367Y310792D01*
G01X601133Y309000D02*
X601383Y308708D01*
X601717Y308542D01*
X602092Y308500D01*
X602425Y308542D01*
X602758Y308750D01*
X602967Y309000D01*
X603008Y309250D01*
X602925Y309542D01*
X602633Y309750D01*
X602342Y309833D01*
X601967D01*
G01X602342D02*
X602592Y309958D01*
X602800Y310167D01*
X602883Y310417D01*
X602800Y310667D01*
X602592Y310875D01*
X602217Y311000D01*
X601842Y310958D01*
X601467Y310792D01*
G01X605150Y308500D02*
Y311000D01*
X604650Y310500D01*
G01Y308500D02*
X605650D01*
G01X627750Y308491D02*
Y312491D01*
X620350D01*
G01X593517Y312500D02*
Y315000D01*
X594558D01*
X594892Y314875D01*
X595100Y314708D01*
X595183Y314375D01*
X595100Y314042D01*
X594850Y313833D01*
X594558Y313708D01*
X593517D01*
G01X594558D02*
X595183Y312500D01*
G01X596533Y313000D02*
X596783Y312708D01*
X597117Y312542D01*
X597492Y312500D01*
X597825Y312542D01*
X598158Y312750D01*
X598367Y313000D01*
X598408Y313250D01*
X598325Y313542D01*
X598033Y313750D01*
X597742Y313833D01*
X597367D01*
G01X597742D02*
X597992Y313958D01*
X598200Y314167D01*
X598283Y314417D01*
X598200Y314667D01*
X597992Y314875D01*
X597617Y315000D01*
X597242Y314958D01*
X596867Y314792D01*
G01X599633Y313000D02*
X599883Y312708D01*
X600217Y312542D01*
X600592Y312500D01*
X600925Y312542D01*
X601258Y312750D01*
X601467Y313000D01*
X601508Y313250D01*
X601425Y313542D01*
X601133Y313750D01*
X600842Y313833D01*
X600467D01*
G01X600842D02*
X601092Y313958D01*
X601300Y314167D01*
X601383Y314417D01*
X601300Y314667D01*
X601092Y314875D01*
X600717Y315000D01*
X600342Y314958D01*
X599967Y314792D01*
G01X602858Y314583D02*
X603108Y314833D01*
X603400Y314958D01*
X603733Y315000D01*
X604150Y314917D01*
X604442Y314708D01*
X604525Y314458D01*
X604483Y314208D01*
X604317Y314000D01*
X603483Y313583D01*
X603108Y313292D01*
X602858Y312875D01*
X602775Y312500D01*
X604525D01*
G01X625250Y312991D02*
Y316991D01*
X617850D01*
G01X580517Y312500D02*
Y315000D01*
X581558D01*
X581892Y314875D01*
X582100Y314708D01*
X582183Y314375D01*
X582100Y314042D01*
X581850Y313833D01*
X581558Y313708D01*
X580517D01*
G01X581558D02*
X582183Y312500D01*
G01X583533Y313000D02*
X583783Y312708D01*
X584117Y312542D01*
X584492Y312500D01*
X584825Y312542D01*
X585158Y312750D01*
X585367Y313000D01*
X585408Y313250D01*
X585325Y313542D01*
X585033Y313750D01*
X584742Y313833D01*
X584367D01*
G01X584742D02*
X584992Y313958D01*
X585200Y314167D01*
X585283Y314417D01*
X585200Y314667D01*
X584992Y314875D01*
X584617Y315000D01*
X584242Y314958D01*
X583867Y314792D01*
G01X586633Y313000D02*
X586883Y312708D01*
X587217Y312542D01*
X587592Y312500D01*
X587925Y312542D01*
X588258Y312750D01*
X588467Y313000D01*
X588508Y313250D01*
X588425Y313542D01*
X588133Y313750D01*
X587842Y313833D01*
X587467D01*
G01X587842D02*
X588092Y313958D01*
X588300Y314167D01*
X588383Y314417D01*
X588300Y314667D01*
X588092Y314875D01*
X587717Y315000D01*
X587342Y314958D01*
X586967Y314792D01*
G01X591150Y312500D02*
Y315000D01*
X589608Y313208D01*
X591692D01*
G01X617250Y312991D02*
Y316991D01*
X609850D01*
G01X617750Y351400D02*
Y355400D01*
X610350D01*
G01X621767Y361292D02*
X621517Y361417D01*
X621225Y361500D01*
X620892D01*
X620517Y361375D01*
X620225Y361167D01*
X620017Y360917D01*
X619850Y360500D01*
X619808Y360125D01*
X619892Y359750D01*
X620017Y359500D01*
X620267Y359250D01*
X620558Y359083D01*
X620850Y359000D01*
X621142D01*
X621433Y359083D01*
X621683Y359208D01*
X621892Y359375D01*
G01X623033D02*
X623283Y359167D01*
X623575Y359042D01*
X623950Y359000D01*
X624325Y359083D01*
X624617Y359250D01*
X624825Y359542D01*
X624867Y359875D01*
X624783Y360208D01*
X624575Y360417D01*
X624283Y360583D01*
X623992Y360625D01*
X623700Y360583D01*
X623325Y360417D01*
X623450Y361500D01*
X624575D01*
G01X627050D02*
X626717Y361417D01*
X626467Y361208D01*
X626300Y360958D01*
X626175Y360625D01*
X626133Y360250D01*
X626175Y359875D01*
X626300Y359542D01*
X626467Y359292D01*
X626717Y359083D01*
X627050Y359000D01*
X627383Y359083D01*
X627633Y359292D01*
X627800Y359542D01*
X627925Y359875D01*
X627967Y360250D01*
X627925Y360625D01*
X627800Y360958D01*
X627633Y361208D01*
X627383Y361417D01*
X627050Y361500D01*
G01X630650Y359000D02*
Y361500D01*
X629108Y359708D01*
X631192D01*
G01X632767Y346792D02*
X632517Y346917D01*
X632225Y347000D01*
X631892D01*
X631517Y346875D01*
X631225Y346667D01*
X631017Y346417D01*
X630850Y346000D01*
X630808Y345625D01*
X630892Y345250D01*
X631017Y345000D01*
X631267Y344750D01*
X631558Y344583D01*
X631850Y344500D01*
X632142D01*
X632433Y344583D01*
X632683Y344708D01*
X632892Y344875D01*
G01X634033D02*
X634283Y344667D01*
X634575Y344542D01*
X634950Y344500D01*
X635325Y344583D01*
X635617Y344750D01*
X635825Y345042D01*
X635867Y345375D01*
X635783Y345708D01*
X635575Y345917D01*
X635283Y346083D01*
X634992Y346125D01*
X634700Y346083D01*
X634325Y345917D01*
X634450Y347000D01*
X635575D01*
G01X638050Y344500D02*
Y347000D01*
X637550Y346500D01*
G01Y344500D02*
X638550D01*
G01X640442Y344792D02*
X640733Y344583D01*
X641067Y344500D01*
X641400Y344583D01*
X641692Y344833D01*
X641900Y345208D01*
X641983Y345583D01*
Y346042D01*
X641900Y346417D01*
X641692Y346750D01*
X641442Y346917D01*
X641150Y347000D01*
X640817Y346917D01*
X640567Y346750D01*
X640400Y346500D01*
X640317Y346167D01*
X640400Y345875D01*
X640608Y345583D01*
X640858Y345417D01*
X641150Y345375D01*
X641483Y345458D01*
X641733Y345667D01*
X641983Y346042D01*
G01X578267Y336292D02*
X578017Y336417D01*
X577725Y336500D01*
X577392D01*
X577017Y336375D01*
X576725Y336167D01*
X576517Y335917D01*
X576350Y335500D01*
X576308Y335125D01*
X576392Y334750D01*
X576517Y334500D01*
X576767Y334250D01*
X577058Y334083D01*
X577350Y334000D01*
X577642D01*
X577933Y334083D01*
X578183Y334208D01*
X578392Y334375D01*
G01X579533D02*
X579783Y334167D01*
X580075Y334042D01*
X580450Y334000D01*
X580825Y334083D01*
X581117Y334250D01*
X581325Y334542D01*
X581367Y334875D01*
X581283Y335208D01*
X581075Y335417D01*
X580783Y335583D01*
X580492Y335625D01*
X580200Y335583D01*
X579825Y335417D01*
X579950Y336500D01*
X581075D01*
G01X582758Y336083D02*
X583008Y336333D01*
X583300Y336458D01*
X583633Y336500D01*
X584050Y336417D01*
X584342Y336208D01*
X584425Y335958D01*
X584383Y335708D01*
X584217Y335500D01*
X583383Y335083D01*
X583008Y334792D01*
X582758Y334375D01*
X582675Y334000D01*
X584425D01*
G01X587150D02*
Y336500D01*
X585608Y334708D01*
X587692D01*
G01X578267Y340292D02*
X578017Y340417D01*
X577725Y340500D01*
X577392D01*
X577017Y340375D01*
X576725Y340167D01*
X576517Y339917D01*
X576350Y339500D01*
X576308Y339125D01*
X576392Y338750D01*
X576517Y338500D01*
X576767Y338250D01*
X577058Y338083D01*
X577350Y338000D01*
X577642D01*
X577933Y338083D01*
X578183Y338208D01*
X578392Y338375D01*
G01X579533D02*
X579783Y338167D01*
X580075Y338042D01*
X580450Y338000D01*
X580825Y338083D01*
X581117Y338250D01*
X581325Y338542D01*
X581367Y338875D01*
X581283Y339208D01*
X581075Y339417D01*
X580783Y339583D01*
X580492Y339625D01*
X580200Y339583D01*
X579825Y339417D01*
X579950Y340500D01*
X581075D01*
G01X583467Y338000D02*
X583550Y338542D01*
X583675Y339000D01*
X583842Y339417D01*
X584050Y339875D01*
X584383Y340500D01*
X582717D01*
G01X585733Y338375D02*
X585983Y338167D01*
X586275Y338042D01*
X586650Y338000D01*
X587025Y338083D01*
X587317Y338250D01*
X587525Y338542D01*
X587567Y338875D01*
X587483Y339208D01*
X587275Y339417D01*
X586983Y339583D01*
X586692Y339625D01*
X586400Y339583D01*
X586025Y339417D01*
X586150Y340500D01*
X587275D01*
G01X632767Y350792D02*
X632517Y350917D01*
X632225Y351000D01*
X631892D01*
X631517Y350875D01*
X631225Y350667D01*
X631017Y350417D01*
X630850Y350000D01*
X630808Y349625D01*
X630892Y349250D01*
X631017Y349000D01*
X631267Y348750D01*
X631558Y348583D01*
X631850Y348500D01*
X632142D01*
X632433Y348583D01*
X632683Y348708D01*
X632892Y348875D01*
G01X634033D02*
X634283Y348667D01*
X634575Y348542D01*
X634950Y348500D01*
X635325Y348583D01*
X635617Y348750D01*
X635825Y349042D01*
X635867Y349375D01*
X635783Y349708D01*
X635575Y349917D01*
X635283Y350083D01*
X634992Y350125D01*
X634700Y350083D01*
X634325Y349917D01*
X634450Y351000D01*
X635575D01*
G01X638050Y348500D02*
Y351000D01*
X637550Y350500D01*
G01Y348500D02*
X638550D01*
G01X641150D02*
X641442Y348542D01*
X641775Y348667D01*
X641983Y348875D01*
X642067Y349167D01*
X641983Y349458D01*
X641733Y349708D01*
X641358Y349833D01*
X640942D01*
X640692Y349917D01*
X640483Y350125D01*
X640400Y350417D01*
X640525Y350708D01*
X640817Y350917D01*
X641150Y351000D01*
X641483Y350917D01*
X641775Y350708D01*
X641900Y350417D01*
X641817Y350125D01*
X641608Y349917D01*
X641358Y349833D01*
X640942D01*
X640567Y349708D01*
X640317Y349458D01*
X640233Y349167D01*
X640317Y348875D01*
X640525Y348667D01*
X640858Y348542D01*
X641150Y348500D01*
G01X631267Y308792D02*
X631017Y308917D01*
X630725Y309000D01*
X630392D01*
X630017Y308875D01*
X629725Y308667D01*
X629517Y308417D01*
X629350Y308000D01*
X629308Y307625D01*
X629392Y307250D01*
X629517Y307000D01*
X629767Y306750D01*
X630058Y306583D01*
X630350Y306500D01*
X630642D01*
X630933Y306583D01*
X631183Y306708D01*
X631392Y306875D01*
G01X632533D02*
X632783Y306667D01*
X633075Y306542D01*
X633450Y306500D01*
X633825Y306583D01*
X634117Y306750D01*
X634325Y307042D01*
X634367Y307375D01*
X634283Y307708D01*
X634075Y307917D01*
X633783Y308083D01*
X633492Y308125D01*
X633200Y308083D01*
X632825Y307917D01*
X632950Y309000D01*
X634075D01*
G01X635758Y308583D02*
X636008Y308833D01*
X636300Y308958D01*
X636633Y309000D01*
X637050Y308917D01*
X637342Y308708D01*
X637425Y308458D01*
X637383Y308208D01*
X637217Y308000D01*
X636383Y307583D01*
X636008Y307292D01*
X635758Y306875D01*
X635675Y306500D01*
X637425D01*
G01X639650Y309000D02*
X639317Y308917D01*
X639067Y308708D01*
X638900Y308458D01*
X638775Y308125D01*
X638733Y307750D01*
X638775Y307375D01*
X638900Y307042D01*
X639067Y306792D01*
X639317Y306583D01*
X639650Y306500D01*
X639983Y306583D01*
X640233Y306792D01*
X640400Y307042D01*
X640525Y307375D01*
X640567Y307750D01*
X640525Y308125D01*
X640400Y308458D01*
X640233Y308708D01*
X639983Y308917D01*
X639650Y309000D01*
G01X601020Y369720D02*
X618220D01*
Y359820D01*
X601020D01*
Y369720D01*
G01X610983Y328500D02*
Y326708D01*
X611150Y326333D01*
X611483Y326083D01*
X611900Y326000D01*
X612317Y326083D01*
X612650Y326333D01*
X612817Y326708D01*
Y328500D01*
G01X614208Y328083D02*
X614458Y328333D01*
X614750Y328458D01*
X615083Y328500D01*
X615500Y328417D01*
X615792Y328208D01*
X615875Y327958D01*
X615833Y327708D01*
X615667Y327500D01*
X614833Y327083D01*
X614458Y326792D01*
X614208Y326375D01*
X614125Y326000D01*
X615875D01*
G01X617183Y326375D02*
X617433Y326167D01*
X617725Y326042D01*
X618100Y326000D01*
X618475Y326083D01*
X618767Y326250D01*
X618975Y326542D01*
X619017Y326875D01*
X618933Y327208D01*
X618725Y327417D01*
X618433Y327583D01*
X618142Y327625D01*
X617850Y327583D01*
X617475Y327417D01*
X617600Y328500D01*
X618725D01*
G01X609170Y345598D02*
X617170D01*
Y333198D01*
X609170D01*
Y345598D01*
G01X613170Y343898D02*
X614670Y345398D01*
G01X613170Y343898D02*
X611670Y345398D01*
G01X613170Y305489D02*
X614670Y306989D01*
G01X613170Y305489D02*
X611670Y306989D01*
G01X625128Y366424D02*
Y362424D01*
X632528D01*
G01X629917Y391200D02*
Y393700D01*
X630958D01*
X631292Y393575D01*
X631500Y393408D01*
X631583Y393075D01*
X631500Y392742D01*
X631250Y392533D01*
X630958Y392408D01*
X629917D01*
G01X630958D02*
X631583Y391200D01*
G01X633058Y393283D02*
X633308Y393533D01*
X633600Y393658D01*
X633933Y393700D01*
X634350Y393617D01*
X634642Y393408D01*
X634725Y393158D01*
X634683Y392908D01*
X634517Y392700D01*
X633683Y392283D01*
X633308Y391992D01*
X633058Y391575D01*
X632975Y391200D01*
X634725D01*
G01X636242Y391492D02*
X636533Y391283D01*
X636867Y391200D01*
X637200Y391283D01*
X637492Y391533D01*
X637700Y391908D01*
X637783Y392283D01*
Y392742D01*
X637700Y393117D01*
X637492Y393450D01*
X637242Y393617D01*
X636950Y393700D01*
X636617Y393617D01*
X636367Y393450D01*
X636200Y393200D01*
X636117Y392867D01*
X636200Y392575D01*
X636408Y392283D01*
X636658Y392117D01*
X636950Y392075D01*
X637283Y392158D01*
X637533Y392367D01*
X637783Y392742D01*
G01X640050Y391200D02*
Y393700D01*
X639550Y393200D01*
G01Y391200D02*
X640550D01*
G01X625128Y387304D02*
Y383304D01*
X632528D01*
G01X588000Y394017D02*
X585500D01*
Y395058D01*
X585625Y395392D01*
X585792Y395600D01*
X586125Y395683D01*
X586458Y395600D01*
X586667Y395350D01*
X586792Y395058D01*
Y394017D01*
G01Y395058D02*
X588000Y395683D01*
G01X585917Y397158D02*
X585667Y397408D01*
X585542Y397700D01*
X585500Y398033D01*
X585583Y398450D01*
X585792Y398742D01*
X586042Y398825D01*
X586292Y398783D01*
X586500Y398617D01*
X586917Y397783D01*
X587208Y397408D01*
X587625Y397158D01*
X588000Y397075D01*
Y398825D01*
G01X587708Y400342D02*
X587917Y400633D01*
X588000Y400967D01*
X587917Y401300D01*
X587667Y401592D01*
X587292Y401800D01*
X586917Y401883D01*
X586458D01*
X586083Y401800D01*
X585750Y401592D01*
X585583Y401342D01*
X585500Y401050D01*
X585583Y400717D01*
X585750Y400467D01*
X586000Y400300D01*
X586333Y400217D01*
X586625Y400300D01*
X586917Y400508D01*
X587083Y400758D01*
X587125Y401050D01*
X587042Y401383D01*
X586833Y401633D01*
X586458Y401883D01*
G01X585917Y403358D02*
X585667Y403608D01*
X585542Y403900D01*
X585500Y404233D01*
X585583Y404650D01*
X585792Y404942D01*
X586042Y405025D01*
X586292Y404983D01*
X586500Y404817D01*
X586917Y403983D01*
X587208Y403608D01*
X587625Y403358D01*
X588000Y403275D01*
Y405025D01*
G01X595640Y397220D02*
Y393220D01*
X603040D01*
G01X592000Y394017D02*
X589500D01*
Y395058D01*
X589625Y395392D01*
X589792Y395600D01*
X590125Y395683D01*
X590458Y395600D01*
X590667Y395350D01*
X590792Y395058D01*
Y394017D01*
G01Y395058D02*
X592000Y395683D01*
G01X589917Y397158D02*
X589667Y397408D01*
X589542Y397700D01*
X589500Y398033D01*
X589583Y398450D01*
X589792Y398742D01*
X590042Y398825D01*
X590292Y398783D01*
X590500Y398617D01*
X590917Y397783D01*
X591208Y397408D01*
X591625Y397158D01*
X592000Y397075D01*
Y398825D01*
G01X591708Y400342D02*
X591917Y400633D01*
X592000Y400967D01*
X591917Y401300D01*
X591667Y401592D01*
X591292Y401800D01*
X590917Y401883D01*
X590458D01*
X590083Y401800D01*
X589750Y401592D01*
X589583Y401342D01*
X589500Y401050D01*
X589583Y400717D01*
X589750Y400467D01*
X590000Y400300D01*
X590333Y400217D01*
X590625Y400300D01*
X590917Y400508D01*
X591083Y400758D01*
X591125Y401050D01*
X591042Y401383D01*
X590833Y401633D01*
X590458Y401883D01*
G01X591500Y403233D02*
X591792Y403483D01*
X591958Y403817D01*
X592000Y404192D01*
X591958Y404525D01*
X591750Y404858D01*
X591500Y405067D01*
X591250Y405108D01*
X590958Y405025D01*
X590750Y404733D01*
X590667Y404442D01*
Y404067D01*
G01Y404442D02*
X590542Y404692D01*
X590333Y404900D01*
X590083Y404983D01*
X589833Y404900D01*
X589625Y404692D01*
X589500Y404317D01*
X589542Y403942D01*
X589708Y403567D01*
G01X606950Y397220D02*
Y393220D01*
X614350D01*
G01X602773Y376955D02*
Y380955D01*
X595373D01*
G01X602773Y372955D02*
Y376955D01*
X595373D01*
G01X575517Y374000D02*
Y376500D01*
X576558D01*
X576892Y376375D01*
X577100Y376208D01*
X577183Y375875D01*
X577100Y375542D01*
X576850Y375333D01*
X576558Y375208D01*
X575517D01*
G01X576558D02*
X577183Y374000D01*
G01X578533Y374500D02*
X578783Y374208D01*
X579117Y374042D01*
X579492Y374000D01*
X579825Y374042D01*
X580158Y374250D01*
X580367Y374500D01*
X580408Y374750D01*
X580325Y375042D01*
X580033Y375250D01*
X579742Y375333D01*
X579367D01*
G01X579742D02*
X579992Y375458D01*
X580200Y375667D01*
X580283Y375917D01*
X580200Y376167D01*
X579992Y376375D01*
X579617Y376500D01*
X579242Y376458D01*
X578867Y376292D01*
G01X582550Y374000D02*
Y376500D01*
X582050Y376000D01*
G01Y374000D02*
X583050D01*
G01X584733Y374375D02*
X584983Y374167D01*
X585275Y374042D01*
X585650Y374000D01*
X586025Y374083D01*
X586317Y374250D01*
X586525Y374542D01*
X586567Y374875D01*
X586483Y375208D01*
X586275Y375417D01*
X585983Y375583D01*
X585692Y375625D01*
X585400Y375583D01*
X585025Y375417D01*
X585150Y376500D01*
X586275D01*
G01X622467Y376894D02*
Y380894D01*
X615067D01*
G01X575517Y370000D02*
Y372500D01*
X576558D01*
X576892Y372375D01*
X577100Y372208D01*
X577183Y371875D01*
X577100Y371542D01*
X576850Y371333D01*
X576558Y371208D01*
X575517D01*
G01X576558D02*
X577183Y370000D01*
G01X578533Y370500D02*
X578783Y370208D01*
X579117Y370042D01*
X579492Y370000D01*
X579825Y370042D01*
X580158Y370250D01*
X580367Y370500D01*
X580408Y370750D01*
X580325Y371042D01*
X580033Y371250D01*
X579742Y371333D01*
X579367D01*
G01X579742D02*
X579992Y371458D01*
X580200Y371667D01*
X580283Y371917D01*
X580200Y372167D01*
X579992Y372375D01*
X579617Y372500D01*
X579242Y372458D01*
X578867Y372292D01*
G01X582550Y370000D02*
Y372500D01*
X582050Y372000D01*
G01Y370000D02*
X583050D01*
G01X586150D02*
Y372500D01*
X584608Y370708D01*
X586692D01*
G01X622467Y372894D02*
Y376894D01*
X615067D01*
G01X574517Y420200D02*
Y422700D01*
X575558D01*
X575892Y422575D01*
X576100Y422408D01*
X576183Y422075D01*
X576100Y421742D01*
X575850Y421533D01*
X575558Y421408D01*
X574517D01*
G01X575558D02*
X576183Y420200D01*
G01X577533Y420700D02*
X577783Y420408D01*
X578117Y420242D01*
X578492Y420200D01*
X578825Y420242D01*
X579158Y420450D01*
X579367Y420700D01*
X579408Y420950D01*
X579325Y421242D01*
X579033Y421450D01*
X578742Y421533D01*
X578367D01*
G01X578742D02*
X578992Y421658D01*
X579200Y421867D01*
X579283Y422117D01*
X579200Y422367D01*
X578992Y422575D01*
X578617Y422700D01*
X578242Y422658D01*
X577867Y422492D01*
G01X581550Y420200D02*
X581842Y420242D01*
X582175Y420367D01*
X582383Y420575D01*
X582467Y420867D01*
X582383Y421158D01*
X582133Y421408D01*
X581758Y421533D01*
X581342D01*
X581092Y421617D01*
X580883Y421825D01*
X580800Y422117D01*
X580925Y422408D01*
X581217Y422617D01*
X581550Y422700D01*
X581883Y422617D01*
X582175Y422408D01*
X582300Y422117D01*
X582217Y421825D01*
X582008Y421617D01*
X581758Y421533D01*
X581342D01*
X580967Y421408D01*
X580717Y421158D01*
X580633Y420867D01*
X580717Y420575D01*
X580925Y420367D01*
X581258Y420242D01*
X581550Y420200D01*
G01X584567D02*
X584650Y420742D01*
X584775Y421200D01*
X584942Y421617D01*
X585150Y422075D01*
X585483Y422700D01*
X583817D01*
G01X589208Y365267D02*
X589083Y365017D01*
X589000Y364725D01*
Y364392D01*
X589125Y364017D01*
X589333Y363725D01*
X589583Y363517D01*
X590000Y363350D01*
X590375Y363308D01*
X590750Y363392D01*
X591000Y363517D01*
X591250Y363767D01*
X591417Y364058D01*
X591500Y364350D01*
Y364642D01*
X591417Y364933D01*
X591292Y365183D01*
X591125Y365392D01*
G01Y366533D02*
X591333Y366783D01*
X591458Y367075D01*
X591500Y367450D01*
X591417Y367825D01*
X591250Y368117D01*
X590958Y368325D01*
X590625Y368367D01*
X590292Y368283D01*
X590083Y368075D01*
X589917Y367783D01*
X589875Y367492D01*
X589917Y367200D01*
X590083Y366825D01*
X589000Y366950D01*
Y368075D01*
G01Y370550D02*
X589083Y370217D01*
X589292Y369967D01*
X589542Y369800D01*
X589875Y369675D01*
X590250Y369633D01*
X590625Y369675D01*
X590958Y369800D01*
X591208Y369967D01*
X591417Y370217D01*
X591500Y370550D01*
X591417Y370883D01*
X591208Y371133D01*
X590958Y371300D01*
X590625Y371425D01*
X590250Y371467D01*
X589875Y371425D01*
X589542Y371300D01*
X589292Y371133D01*
X589083Y370883D01*
X589000Y370550D01*
G01X591000Y372733D02*
X591292Y372983D01*
X591458Y373317D01*
X591500Y373692D01*
X591458Y374025D01*
X591250Y374358D01*
X591000Y374567D01*
X590750Y374608D01*
X590458Y374525D01*
X590250Y374233D01*
X590167Y373942D01*
Y373567D01*
G01Y373942D02*
X590042Y374192D01*
X589833Y374400D01*
X589583Y374483D01*
X589333Y374400D01*
X589125Y374192D01*
X589000Y373817D01*
X589042Y373442D01*
X589208Y373067D01*
G01X585708Y383267D02*
X585583Y383017D01*
X585500Y382725D01*
Y382392D01*
X585625Y382017D01*
X585833Y381725D01*
X586083Y381517D01*
X586500Y381350D01*
X586875Y381308D01*
X587250Y381392D01*
X587500Y381517D01*
X587750Y381767D01*
X587917Y382058D01*
X588000Y382350D01*
Y382642D01*
X587917Y382933D01*
X587792Y383183D01*
X587625Y383392D01*
G01Y384533D02*
X587833Y384783D01*
X587958Y385075D01*
X588000Y385450D01*
X587917Y385825D01*
X587750Y386117D01*
X587458Y386325D01*
X587125Y386367D01*
X586792Y386283D01*
X586583Y386075D01*
X586417Y385783D01*
X586375Y385492D01*
X586417Y385200D01*
X586583Y384825D01*
X585500Y384950D01*
Y386075D01*
G01Y388550D02*
X585583Y388217D01*
X585792Y387967D01*
X586042Y387800D01*
X586375Y387675D01*
X586750Y387633D01*
X587125Y387675D01*
X587458Y387800D01*
X587708Y387967D01*
X587917Y388217D01*
X588000Y388550D01*
X587917Y388883D01*
X587708Y389133D01*
X587458Y389300D01*
X587125Y389425D01*
X586750Y389467D01*
X586375Y389425D01*
X586042Y389300D01*
X585792Y389133D01*
X585583Y388883D01*
X585500Y388550D01*
G01X586958Y390858D02*
X586667Y391150D01*
X586500Y391400D01*
X586417Y391733D01*
X586500Y392025D01*
X586667Y392233D01*
X586917Y392400D01*
X587208Y392442D01*
X587458Y392400D01*
X587708Y392233D01*
X587917Y391983D01*
X588000Y391692D01*
X587917Y391358D01*
X587667Y391067D01*
X587292Y390900D01*
X586875Y390858D01*
X586333Y390942D01*
X586042Y391067D01*
X585750Y391275D01*
X585542Y391567D01*
X585500Y391858D01*
X585583Y392150D01*
X585792Y392358D01*
G01X621367Y396692D02*
X621117Y396817D01*
X620825Y396900D01*
X620492D01*
X620117Y396775D01*
X619825Y396567D01*
X619617Y396317D01*
X619450Y395900D01*
X619408Y395525D01*
X619492Y395150D01*
X619617Y394900D01*
X619867Y394650D01*
X620158Y394483D01*
X620450Y394400D01*
X620742D01*
X621033Y394483D01*
X621283Y394608D01*
X621492Y394775D01*
G01X622633D02*
X622883Y394567D01*
X623175Y394442D01*
X623550Y394400D01*
X623925Y394483D01*
X624217Y394650D01*
X624425Y394942D01*
X624467Y395275D01*
X624383Y395608D01*
X624175Y395817D01*
X623883Y395983D01*
X623592Y396025D01*
X623300Y395983D01*
X622925Y395817D01*
X623050Y396900D01*
X624175D01*
G01X626650D02*
X626317Y396817D01*
X626067Y396608D01*
X625900Y396358D01*
X625775Y396025D01*
X625733Y395650D01*
X625775Y395275D01*
X625900Y394942D01*
X626067Y394692D01*
X626317Y394483D01*
X626650Y394400D01*
X626983Y394483D01*
X627233Y394692D01*
X627400Y394942D01*
X627525Y395275D01*
X627567Y395650D01*
X627525Y396025D01*
X627400Y396358D01*
X627233Y396608D01*
X626983Y396817D01*
X626650Y396900D01*
G01X629667Y394400D02*
X629750Y394942D01*
X629875Y395400D01*
X630042Y395817D01*
X630250Y396275D01*
X630583Y396900D01*
X628917D01*
G01X580267Y426292D02*
X580017Y426417D01*
X579725Y426500D01*
X579392D01*
X579017Y426375D01*
X578725Y426167D01*
X578517Y425917D01*
X578350Y425500D01*
X578308Y425125D01*
X578392Y424750D01*
X578517Y424500D01*
X578767Y424250D01*
X579058Y424083D01*
X579350Y424000D01*
X579642D01*
X579933Y424083D01*
X580183Y424208D01*
X580392Y424375D01*
G01X582367Y424000D02*
X582450Y424542D01*
X582575Y425000D01*
X582742Y425417D01*
X582950Y425875D01*
X583283Y426500D01*
X581617D01*
G01X585550Y424000D02*
Y426500D01*
X585050Y426000D01*
G01Y424000D02*
X586050D01*
G01X588650Y426500D02*
X588317Y426417D01*
X588067Y426208D01*
X587900Y425958D01*
X587775Y425625D01*
X587733Y425250D01*
X587775Y424875D01*
X587900Y424542D01*
X588067Y424292D01*
X588317Y424083D01*
X588650Y424000D01*
X588983Y424083D01*
X589233Y424292D01*
X589400Y424542D01*
X589525Y424875D01*
X589567Y425250D01*
X589525Y425625D01*
X589400Y425958D01*
X589233Y426208D01*
X588983Y426417D01*
X588650Y426500D01*
G01X576267Y418892D02*
X576017Y419017D01*
X575725Y419100D01*
X575392D01*
X575017Y418975D01*
X574725Y418767D01*
X574517Y418517D01*
X574350Y418100D01*
X574308Y417725D01*
X574392Y417350D01*
X574517Y417100D01*
X574767Y416850D01*
X575058Y416683D01*
X575350Y416600D01*
X575642D01*
X575933Y416683D01*
X576183Y416808D01*
X576392Y416975D01*
G01X577533D02*
X577783Y416767D01*
X578075Y416642D01*
X578450Y416600D01*
X578825Y416683D01*
X579117Y416850D01*
X579325Y417142D01*
X579367Y417475D01*
X579283Y417808D01*
X579075Y418017D01*
X578783Y418183D01*
X578492Y418225D01*
X578200Y418183D01*
X577825Y418017D01*
X577950Y419100D01*
X579075D01*
G01X581467Y416600D02*
X581550Y417142D01*
X581675Y417600D01*
X581842Y418017D01*
X582050Y418475D01*
X582383Y419100D01*
X580717D01*
G01X583858Y417642D02*
X584150Y417933D01*
X584400Y418100D01*
X584733Y418183D01*
X585025Y418100D01*
X585233Y417933D01*
X585400Y417683D01*
X585442Y417392D01*
X585400Y417142D01*
X585233Y416892D01*
X584983Y416683D01*
X584692Y416600D01*
X584358Y416683D01*
X584067Y416933D01*
X583900Y417308D01*
X583858Y417725D01*
X583942Y418267D01*
X584067Y418558D01*
X584275Y418850D01*
X584567Y419058D01*
X584858Y419100D01*
X585150Y419017D01*
X585358Y418808D01*
G01X577500Y392700D02*
Y387200D01*
G01Y404800D02*
Y399300D01*
G01X593000Y363983D02*
X594792D01*
X595167Y364150D01*
X595417Y364483D01*
X595500Y364900D01*
X595417Y365317D01*
X595167Y365650D01*
X594792Y365817D01*
X593000D01*
G01X593417Y367208D02*
X593167Y367458D01*
X593042Y367750D01*
X593000Y368083D01*
X593083Y368500D01*
X593292Y368792D01*
X593542Y368875D01*
X593792Y368833D01*
X594000Y368667D01*
X594417Y367833D01*
X594708Y367458D01*
X595125Y367208D01*
X595500Y367125D01*
Y368875D01*
G01X593000Y371100D02*
X593083Y370767D01*
X593292Y370517D01*
X593542Y370350D01*
X593875Y370225D01*
X594250Y370183D01*
X594625Y370225D01*
X594958Y370350D01*
X595208Y370517D01*
X595417Y370767D01*
X595500Y371100D01*
X595417Y371433D01*
X595208Y371683D01*
X594958Y371850D01*
X594625Y371975D01*
X594250Y372017D01*
X593875Y371975D01*
X593542Y371850D01*
X593292Y371683D01*
X593083Y371433D01*
X593000Y371100D01*
G01X611020Y369720D02*
Y369570D01*
X609770Y368320D01*
X608570Y369520D01*
Y369770D01*
G01X589500Y384483D02*
X591292D01*
X591667Y384650D01*
X591917Y384983D01*
X592000Y385400D01*
X591917Y385817D01*
X591667Y386150D01*
X591292Y386317D01*
X589500D01*
G01X589917Y387708D02*
X589667Y387958D01*
X589542Y388250D01*
X589500Y388583D01*
X589583Y389000D01*
X589792Y389292D01*
X590042Y389375D01*
X590292Y389333D01*
X590500Y389167D01*
X590917Y388333D01*
X591208Y387958D01*
X591625Y387708D01*
X592000Y387625D01*
Y389375D01*
G01Y391600D02*
X589500D01*
X590000Y391100D01*
G01X592000D02*
Y392100D01*
G01X611020D02*
Y391950D01*
X609770Y390700D01*
X608570Y391900D01*
Y392150D01*
G01X601020Y392100D02*
X618220D01*
Y382200D01*
X601020D01*
Y392100D01*
G01X633708Y373767D02*
X633583Y373517D01*
X633500Y373225D01*
Y372892D01*
X633625Y372517D01*
X633833Y372225D01*
X634083Y372017D01*
X634500Y371850D01*
X634875Y371808D01*
X635250Y371892D01*
X635500Y372017D01*
X635750Y372267D01*
X635917Y372558D01*
X636000Y372850D01*
Y373142D01*
X635917Y373433D01*
X635792Y373683D01*
X635625Y373892D01*
G01X634958Y375158D02*
X634667Y375450D01*
X634500Y375700D01*
X634417Y376033D01*
X634500Y376325D01*
X634667Y376533D01*
X634917Y376700D01*
X635208Y376742D01*
X635458Y376700D01*
X635708Y376533D01*
X635917Y376283D01*
X636000Y375992D01*
X635917Y375658D01*
X635667Y375367D01*
X635292Y375200D01*
X634875Y375158D01*
X634333Y375242D01*
X634042Y375367D01*
X633750Y375575D01*
X633542Y375867D01*
X633500Y376158D01*
X633583Y376450D01*
X633792Y376658D01*
G01X636000Y379050D02*
X633500D01*
X634000Y378550D01*
G01X636000D02*
Y379550D01*
G01X635708Y381442D02*
X635917Y381733D01*
X636000Y382067D01*
X635917Y382400D01*
X635667Y382692D01*
X635292Y382900D01*
X634917Y382983D01*
X634458D01*
X634083Y382900D01*
X633750Y382692D01*
X633583Y382442D01*
X633500Y382150D01*
X633583Y381817D01*
X633750Y381567D01*
X634000Y381400D01*
X634333Y381317D01*
X634625Y381400D01*
X634917Y381608D01*
X635083Y381858D01*
X635125Y382150D01*
X635042Y382483D01*
X634833Y382733D01*
X634458Y382983D01*
G01X593400Y398340D02*
X635400D01*
Y423940D01*
X593400D01*
Y398340D01*
G01X631067Y471667D02*
Y474167D01*
X632108D01*
X632442Y474042D01*
X632650Y473875D01*
X632733Y473542D01*
X632650Y473209D01*
X632400Y473000D01*
X632108Y472875D01*
X631067D01*
G01X632108D02*
X632733Y471667D01*
G01X634083Y472167D02*
X634333Y471875D01*
X634667Y471709D01*
X635042Y471667D01*
X635375Y471709D01*
X635708Y471917D01*
X635917Y472167D01*
X635958Y472417D01*
X635875Y472709D01*
X635583Y472917D01*
X635292Y473000D01*
X634917D01*
G01X635292D02*
X635542Y473125D01*
X635750Y473334D01*
X635833Y473584D01*
X635750Y473834D01*
X635542Y474042D01*
X635167Y474167D01*
X634792Y474125D01*
X634417Y473959D01*
G01X638100Y471667D02*
Y474167D01*
X637600Y473667D01*
G01Y471667D02*
X638600D01*
G01X624370Y470430D02*
Y466430D01*
X631770D01*
G01X627370Y454630D02*
X631370D01*
Y462030D01*
G01X592000Y484650D02*
Y488650D01*
X584600D01*
G01X618834Y480017D02*
X616334D01*
Y481058D01*
X616459Y481392D01*
X616626Y481600D01*
X616959Y481683D01*
X617292Y481600D01*
X617501Y481350D01*
X617626Y481058D01*
Y480017D01*
G01Y481058D02*
X618834Y481683D01*
G01X618334Y483033D02*
X618626Y483283D01*
X618792Y483617D01*
X618834Y483992D01*
X618792Y484325D01*
X618584Y484658D01*
X618334Y484867D01*
X618084Y484908D01*
X617792Y484825D01*
X617584Y484533D01*
X617501Y484242D01*
Y483867D01*
G01Y484242D02*
X617376Y484492D01*
X617167Y484700D01*
X616917Y484783D01*
X616667Y484700D01*
X616459Y484492D01*
X616334Y484117D01*
X616376Y483742D01*
X616542Y483367D01*
G01X618834Y487050D02*
X616334D01*
X616834Y486550D01*
G01X618834D02*
Y487550D01*
G01Y490150D02*
X616334D01*
X616834Y489650D01*
G01X618834D02*
Y490650D01*
G01X619000Y478200D02*
X615000D01*
Y470800D01*
G01X622834Y480017D02*
X620334D01*
Y481058D01*
X620459Y481392D01*
X620626Y481600D01*
X620959Y481683D01*
X621292Y481600D01*
X621501Y481350D01*
X621626Y481058D01*
Y480017D01*
G01Y481058D02*
X622834Y481683D01*
G01X622334Y483033D02*
X622626Y483283D01*
X622792Y483617D01*
X622834Y483992D01*
X622792Y484325D01*
X622584Y484658D01*
X622334Y484867D01*
X622084Y484908D01*
X621792Y484825D01*
X621584Y484533D01*
X621501Y484242D01*
Y483867D01*
G01Y484242D02*
X621376Y484492D01*
X621167Y484700D01*
X620917Y484783D01*
X620667Y484700D01*
X620459Y484492D01*
X620334Y484117D01*
X620376Y483742D01*
X620542Y483367D01*
G01X620751Y486258D02*
X620501Y486508D01*
X620376Y486800D01*
X620334Y487133D01*
X620417Y487550D01*
X620626Y487842D01*
X620876Y487925D01*
X621126Y487883D01*
X621334Y487717D01*
X621751Y486883D01*
X622042Y486508D01*
X622459Y486258D01*
X622834Y486175D01*
Y487925D01*
G01X620334Y490150D02*
X620417Y489817D01*
X620626Y489567D01*
X620876Y489400D01*
X621209Y489275D01*
X621584Y489233D01*
X621959Y489275D01*
X622292Y489400D01*
X622542Y489567D01*
X622751Y489817D01*
X622834Y490150D01*
X622751Y490483D01*
X622542Y490733D01*
X622292Y490900D01*
X621959Y491025D01*
X621584Y491067D01*
X621209Y491025D01*
X620876Y490900D01*
X620626Y490733D01*
X620417Y490483D01*
X620334Y490150D01*
G01X623500Y478200D02*
X619500D01*
Y470800D01*
G01X625517Y481167D02*
Y483667D01*
X626558D01*
X626892Y483542D01*
X627100Y483375D01*
X627183Y483042D01*
X627100Y482709D01*
X626850Y482500D01*
X626558Y482375D01*
X625517D01*
G01X626558D02*
X627183Y481167D01*
G01X628533Y481667D02*
X628783Y481375D01*
X629117Y481209D01*
X629492Y481167D01*
X629825Y481209D01*
X630158Y481417D01*
X630367Y481667D01*
X630408Y481917D01*
X630325Y482209D01*
X630033Y482417D01*
X629742Y482500D01*
X629367D01*
G01X629742D02*
X629992Y482625D01*
X630200Y482834D01*
X630283Y483084D01*
X630200Y483334D01*
X629992Y483542D01*
X629617Y483667D01*
X629242Y483625D01*
X628867Y483459D01*
G01X631758Y483250D02*
X632008Y483500D01*
X632300Y483625D01*
X632633Y483667D01*
X633050Y483584D01*
X633342Y483375D01*
X633425Y483125D01*
X633383Y482875D01*
X633217Y482667D01*
X632383Y482250D01*
X632008Y481959D01*
X631758Y481542D01*
X631675Y481167D01*
X633425D01*
G01X636150D02*
Y483667D01*
X634608Y481875D01*
X636692D01*
G01X623923Y479831D02*
Y475831D01*
X631323D01*
G01X579017Y463167D02*
Y465667D01*
X580058D01*
X580392Y465542D01*
X580600Y465375D01*
X580683Y465042D01*
X580600Y464709D01*
X580350Y464500D01*
X580058Y464375D01*
X579017D01*
G01X580058D02*
X580683Y463167D01*
G01X582033Y463667D02*
X582283Y463375D01*
X582617Y463209D01*
X582992Y463167D01*
X583325Y463209D01*
X583658Y463417D01*
X583867Y463667D01*
X583908Y463917D01*
X583825Y464209D01*
X583533Y464417D01*
X583242Y464500D01*
X582867D01*
G01X583242D02*
X583492Y464625D01*
X583700Y464834D01*
X583783Y465084D01*
X583700Y465334D01*
X583492Y465542D01*
X583117Y465667D01*
X582742Y465625D01*
X582367Y465459D01*
G01X585967Y463167D02*
X586050Y463709D01*
X586175Y464167D01*
X586342Y464584D01*
X586550Y465042D01*
X586883Y465667D01*
X585217D01*
G01X588358Y465250D02*
X588608Y465500D01*
X588900Y465625D01*
X589233Y465667D01*
X589650Y465584D01*
X589942Y465375D01*
X590025Y465125D01*
X589983Y464875D01*
X589817Y464667D01*
X588983Y464250D01*
X588608Y463959D01*
X588358Y463542D01*
X588275Y463167D01*
X590025D01*
G01X586400Y458300D02*
Y462300D01*
X579000D01*
G01X579334Y475567D02*
X576834D01*
Y476608D01*
X576959Y476942D01*
X577126Y477150D01*
X577459Y477233D01*
X577792Y477150D01*
X578001Y476900D01*
X578126Y476608D01*
Y475567D01*
G01Y476608D02*
X579334Y477233D01*
G01X577251Y478708D02*
X577001Y478958D01*
X576876Y479250D01*
X576834Y479583D01*
X576917Y480000D01*
X577126Y480292D01*
X577376Y480375D01*
X577626Y480333D01*
X577834Y480167D01*
X578251Y479333D01*
X578542Y478958D01*
X578959Y478708D01*
X579334Y478625D01*
Y480375D01*
G01X578959Y481683D02*
X579167Y481933D01*
X579292Y482225D01*
X579334Y482600D01*
X579251Y482975D01*
X579084Y483267D01*
X578792Y483475D01*
X578459Y483517D01*
X578126Y483433D01*
X577917Y483225D01*
X577751Y482933D01*
X577709Y482642D01*
X577751Y482350D01*
X577917Y481975D01*
X576834Y482100D01*
Y483225D01*
G01X584720Y470980D02*
X588720D01*
Y478380D01*
G01X594017Y482000D02*
Y484500D01*
X595058D01*
X595392Y484375D01*
X595600Y484208D01*
X595683Y483875D01*
X595600Y483542D01*
X595350Y483333D01*
X595058Y483208D01*
X594017D01*
G01X595058D02*
X595683Y482000D01*
G01X597033Y482500D02*
X597283Y482208D01*
X597617Y482042D01*
X597992Y482000D01*
X598325Y482042D01*
X598658Y482250D01*
X598867Y482500D01*
X598908Y482750D01*
X598825Y483042D01*
X598533Y483250D01*
X598242Y483333D01*
X597867D01*
G01X598242D02*
X598492Y483458D01*
X598700Y483667D01*
X598783Y483917D01*
X598700Y484167D01*
X598492Y484375D01*
X598117Y484500D01*
X597742Y484458D01*
X597367Y484292D01*
G01X600967Y482000D02*
X601050Y482542D01*
X601175Y483000D01*
X601342Y483417D01*
X601550Y483875D01*
X601883Y484500D01*
X600217D01*
G01X603233Y482500D02*
X603483Y482208D01*
X603817Y482042D01*
X604192Y482000D01*
X604525Y482042D01*
X604858Y482250D01*
X605067Y482500D01*
X605108Y482750D01*
X605025Y483042D01*
X604733Y483250D01*
X604442Y483333D01*
X604067D01*
G01X604442D02*
X604692Y483458D01*
X604900Y483667D01*
X604983Y483917D01*
X604900Y484167D01*
X604692Y484375D01*
X604317Y484500D01*
X603942Y484458D01*
X603567Y484292D01*
G01X589000Y481100D02*
Y477100D01*
X596400D01*
G01X586470Y466530D02*
Y470530D01*
X579070D01*
G01X589990Y432440D02*
Y428440D01*
X597390D01*
G01X595767Y488792D02*
X595517Y488917D01*
X595225Y489000D01*
X594892D01*
X594517Y488875D01*
X594225Y488667D01*
X594017Y488417D01*
X593850Y488000D01*
X593808Y487625D01*
X593892Y487250D01*
X594017Y487000D01*
X594267Y486750D01*
X594558Y486583D01*
X594850Y486500D01*
X595142D01*
X595433Y486583D01*
X595683Y486708D01*
X595892Y486875D01*
G01X597158Y487542D02*
X597450Y487833D01*
X597700Y488000D01*
X598033Y488083D01*
X598325Y488000D01*
X598533Y487833D01*
X598700Y487583D01*
X598742Y487292D01*
X598700Y487042D01*
X598533Y486792D01*
X598283Y486583D01*
X597992Y486500D01*
X597658Y486583D01*
X597367Y486833D01*
X597200Y487208D01*
X597158Y487625D01*
X597242Y488167D01*
X597367Y488458D01*
X597575Y488750D01*
X597867Y488958D01*
X598158Y489000D01*
X598450Y488917D01*
X598658Y488708D01*
G01X601050Y486500D02*
Y489000D01*
X600550Y488500D01*
G01Y486500D02*
X601550D01*
G01X604150D02*
Y489000D01*
X603650Y488500D01*
G01Y486500D02*
X604650D01*
G01X621483Y452000D02*
Y450208D01*
X621650Y449833D01*
X621983Y449583D01*
X622400Y449500D01*
X622817Y449583D01*
X623150Y449833D01*
X623317Y450208D01*
Y452000D01*
G01X625500Y449500D02*
Y452000D01*
X625000Y451500D01*
G01Y449500D02*
X626000D01*
G01X628600D02*
Y452000D01*
X628100Y451500D01*
G01Y449500D02*
X629100D01*
G01X618250Y464900D02*
Y469900D01*
X613250D01*
G01Y442300D02*
X618250D01*
Y447300D01*
G01X590550D02*
Y442300D01*
X595550D01*
G01X617243Y462006D02*
X620243D01*
G01X617243Y452163D02*
X619243D01*
G01X591557Y448226D02*
X588557D01*
G01X591557Y458069D02*
X589557D01*
G01X602500Y428300D02*
Y433500D01*
G01X609500Y428300D02*
Y436100D01*
G01X602500Y428300D02*
X609500D01*
G01X602500Y441700D02*
Y433000D01*
G01X609500Y441700D02*
X602500D01*
G01X609500Y435300D02*
Y441700D01*
G01X631400Y444200D02*
Y430800D01*
G01X638600Y444200D02*
X631400D01*
G01Y430800D02*
X638600D01*
G01X611750Y473700D02*
Y474533D01*
X612500D01*
X612750Y474283D01*
X612917Y473992D01*
X613000Y473575D01*
X612917Y473158D01*
X612750Y472867D01*
X612500Y472617D01*
X612208Y472450D01*
X611875Y472367D01*
X611583D01*
X611333Y472450D01*
X611042Y472617D01*
X610792Y472867D01*
X610625Y473117D01*
X610500Y473450D01*
Y473742D01*
X610583Y474075D01*
X610750Y474325D01*
G01X612625Y475633D02*
X612833Y475883D01*
X612958Y476175D01*
X613000Y476550D01*
X612917Y476925D01*
X612750Y477217D01*
X612458Y477425D01*
X612125Y477467D01*
X611792Y477383D01*
X611583Y477175D01*
X611417Y476883D01*
X611375Y476592D01*
X611417Y476300D01*
X611583Y475925D01*
X610500Y476050D01*
Y477175D01*
G01X614141Y424875D02*
Y427375D01*
X614975D01*
X615308Y427250D01*
X615558Y427083D01*
X615766Y426833D01*
X615933Y426542D01*
X615975Y426125D01*
X615933Y425708D01*
X615766Y425417D01*
X615558Y425167D01*
X615308Y425000D01*
X614975Y424875D01*
X614141D01*
G01X618991D02*
X617325D01*
Y427375D01*
X618991D01*
G01X618325Y426167D02*
X617325D01*
G01X621591Y426208D02*
X621758Y426333D01*
X621883Y426542D01*
X621966Y426833D01*
X621883Y427083D01*
X621716Y427250D01*
X621425Y427375D01*
X620300D01*
Y424875D01*
X621675D01*
X621966Y425042D01*
X622133Y425292D01*
X622216Y425583D01*
X622133Y425875D01*
X621883Y426125D01*
X621591Y426208D01*
X620300D01*
G01X623441Y427375D02*
Y425583D01*
X623608Y425208D01*
X623941Y424958D01*
X624358Y424875D01*
X624775Y424958D01*
X625108Y425208D01*
X625275Y425583D01*
Y427375D01*
G01X627708Y426125D02*
X628541D01*
Y425375D01*
X628291Y425125D01*
X628000Y424958D01*
X627583Y424875D01*
X627166Y424958D01*
X626875Y425125D01*
X626625Y425375D01*
X626458Y425667D01*
X626375Y426000D01*
Y426292D01*
X626458Y426542D01*
X626625Y426833D01*
X626875Y427083D01*
X627125Y427250D01*
X627458Y427375D01*
X627750D01*
X628083Y427292D01*
X628333Y427125D01*
G01X630558Y424875D02*
Y427375D01*
X630058Y426875D01*
G01Y424875D02*
X631058D01*
G01X586500Y539000D02*
Y549000D01*
X584500Y547000D01*
G01Y539000D02*
X588500D01*
G01X593933Y543166D02*
X595100Y544333D01*
X596100Y545000D01*
X597433Y545333D01*
X598600Y545000D01*
X599433Y544333D01*
X600100Y543333D01*
X600267Y542167D01*
X600100Y541167D01*
X599433Y540166D01*
X598433Y539333D01*
X597267Y539000D01*
X595933Y539333D01*
X594767Y540333D01*
X594100Y541833D01*
X593933Y543500D01*
X594267Y545666D01*
X594767Y546833D01*
X595600Y548000D01*
X596767Y548833D01*
X597933Y549000D01*
X599100Y548667D01*
X599933Y547833D01*
G01X604033Y541000D02*
X605033Y539833D01*
X606366Y539167D01*
X607867Y539000D01*
X609200Y539167D01*
X610533Y540000D01*
X611367Y541000D01*
X611533Y542000D01*
X611200Y543166D01*
X610033Y544000D01*
X608867Y544333D01*
X607367D01*
G01X608867D02*
X609867Y544833D01*
X610700Y545666D01*
X611033Y546667D01*
X610700Y547667D01*
X609867Y548500D01*
X608367Y549000D01*
X606867Y548833D01*
X605367Y548167D01*
G01X618300Y539000D02*
Y549000D01*
X616300Y547000D01*
G01Y539000D02*
X620300D01*
G01X625733Y543166D02*
X626900Y544333D01*
X627900Y545000D01*
X629233Y545333D01*
X630400Y545000D01*
X631233Y544333D01*
X631900Y543333D01*
X632067Y542167D01*
X631900Y541167D01*
X631233Y540166D01*
X630233Y539333D01*
X629067Y539000D01*
X627733Y539333D01*
X626567Y540333D01*
X625900Y541833D01*
X625733Y543500D01*
X626067Y545666D01*
X626567Y546833D01*
X627400Y548000D01*
X628567Y548833D01*
X629733Y549000D01*
X630900Y548667D01*
X631733Y547833D01*
G01X637333Y542333D02*
X641667D01*
G01X650100Y539000D02*
Y549000D01*
X648100Y547000D01*
G01Y539000D02*
X652100D01*
G01X594017Y490500D02*
Y493000D01*
X595058D01*
X595392Y492875D01*
X595600Y492708D01*
X595683Y492375D01*
X595600Y492042D01*
X595350Y491833D01*
X595058Y491708D01*
X594017D01*
G01X595058D02*
X595683Y490500D01*
G01X597033Y491000D02*
X597283Y490708D01*
X597617Y490542D01*
X597992Y490500D01*
X598325Y490542D01*
X598658Y490750D01*
X598867Y491000D01*
X598908Y491250D01*
X598825Y491542D01*
X598533Y491750D01*
X598242Y491833D01*
X597867D01*
G01X598242D02*
X598492Y491958D01*
X598700Y492167D01*
X598783Y492417D01*
X598700Y492667D01*
X598492Y492875D01*
X598117Y493000D01*
X597742Y492958D01*
X597367Y492792D01*
G01X600967Y490500D02*
X601050Y491042D01*
X601175Y491500D01*
X601342Y491917D01*
X601550Y492375D01*
X601883Y493000D01*
X600217D01*
G01X604067Y490500D02*
X604150Y491042D01*
X604275Y491500D01*
X604442Y491917D01*
X604650Y492375D01*
X604983Y493000D01*
X603317D01*
G01X595767Y497292D02*
X595517Y497417D01*
X595225Y497500D01*
X594892D01*
X594517Y497375D01*
X594225Y497167D01*
X594017Y496917D01*
X593850Y496500D01*
X593808Y496125D01*
X593892Y495750D01*
X594017Y495500D01*
X594267Y495250D01*
X594558Y495083D01*
X594850Y495000D01*
X595142D01*
X595433Y495083D01*
X595683Y495208D01*
X595892Y495375D01*
G01X597158Y496042D02*
X597450Y496333D01*
X597700Y496500D01*
X598033Y496583D01*
X598325Y496500D01*
X598533Y496333D01*
X598700Y496083D01*
X598742Y495792D01*
X598700Y495542D01*
X598533Y495292D01*
X598283Y495083D01*
X597992Y495000D01*
X597658Y495083D01*
X597367Y495333D01*
X597200Y495708D01*
X597158Y496125D01*
X597242Y496667D01*
X597367Y496958D01*
X597575Y497250D01*
X597867Y497458D01*
X598158Y497500D01*
X598450Y497417D01*
X598658Y497208D01*
G01X600967Y495000D02*
X601050Y495542D01*
X601175Y496000D01*
X601342Y496417D01*
X601550Y496875D01*
X601883Y497500D01*
X600217D01*
G01X603358Y496042D02*
X603650Y496333D01*
X603900Y496500D01*
X604233Y496583D01*
X604525Y496500D01*
X604733Y496333D01*
X604900Y496083D01*
X604942Y495792D01*
X604900Y495542D01*
X604733Y495292D01*
X604483Y495083D01*
X604192Y495000D01*
X603858Y495083D01*
X603567Y495333D01*
X603400Y495708D01*
X603358Y496125D01*
X603442Y496667D01*
X603567Y496958D01*
X603775Y497250D01*
X604067Y497458D01*
X604358Y497500D01*
X604650Y497417D01*
X604858Y497208D01*
G01X671508Y29369D02*
X669008D01*
Y30410D01*
X669133Y30744D01*
X669300Y30952D01*
X669633Y31035D01*
X669966Y30952D01*
X670175Y30702D01*
X670300Y30410D01*
Y29369D01*
G01Y30410D02*
X671508Y31035D01*
G01Y33302D02*
X671466Y33594D01*
X671341Y33927D01*
X671133Y34135D01*
X670841Y34219D01*
X670550Y34135D01*
X670300Y33885D01*
X670175Y33510D01*
Y33094D01*
X670091Y32844D01*
X669883Y32635D01*
X669591Y32552D01*
X669300Y32677D01*
X669091Y32969D01*
X669008Y33302D01*
X669091Y33635D01*
X669300Y33927D01*
X669591Y34052D01*
X669883Y33969D01*
X670091Y33760D01*
X670175Y33510D01*
Y33094D01*
X670300Y32719D01*
X670550Y32469D01*
X670841Y32385D01*
X671133Y32469D01*
X671341Y32677D01*
X671466Y33010D01*
X671508Y33302D01*
G01X669008Y36402D02*
X669091Y36069D01*
X669300Y35819D01*
X669550Y35652D01*
X669883Y35527D01*
X670258Y35485D01*
X670633Y35527D01*
X670966Y35652D01*
X671216Y35819D01*
X671425Y36069D01*
X671508Y36402D01*
X671425Y36735D01*
X671216Y36985D01*
X670966Y37152D01*
X670633Y37277D01*
X670258Y37319D01*
X669883Y37277D01*
X669550Y37152D01*
X669300Y36985D01*
X669091Y36735D01*
X669008Y36402D01*
G01X662301Y29865D02*
X666301D01*
Y37265D01*
G01X661000Y48517D02*
X658500D01*
Y49558D01*
X658625Y49892D01*
X658792Y50100D01*
X659125Y50183D01*
X659458Y50100D01*
X659667Y49850D01*
X659792Y49558D01*
Y48517D01*
G01Y49558D02*
X661000Y50183D01*
G01X658917Y51658D02*
X658667Y51908D01*
X658542Y52200D01*
X658500Y52533D01*
X658583Y52950D01*
X658792Y53242D01*
X659042Y53325D01*
X659292Y53283D01*
X659500Y53117D01*
X659917Y52283D01*
X660208Y51908D01*
X660625Y51658D01*
X661000Y51575D01*
Y53325D01*
G01Y55550D02*
X658500D01*
X659000Y55050D01*
G01X661000D02*
Y56050D01*
G01Y58650D02*
X658500D01*
X659000Y58150D01*
G01X661000D02*
Y59150D01*
G01X652976Y36368D02*
X654426Y37818D01*
G01Y34918D02*
X652976Y36368D01*
G01X654426Y30868D02*
Y41868D01*
G01X662000Y51800D02*
X666000D01*
Y59200D01*
G01X648892Y92236D02*
Y96236D01*
X641492D01*
G01Y84736D02*
X645492D01*
Y92136D01*
G01X637392Y84736D02*
X641392D01*
Y92136D01*
G01X641400Y72000D02*
X641067Y72042D01*
X640775Y72208D01*
X640525Y72458D01*
X640358Y72750D01*
X640275Y73083D01*
Y73417D01*
X640358Y73750D01*
X640525Y74042D01*
X640775Y74292D01*
X641067Y74458D01*
X641400Y74500D01*
X641733Y74458D01*
X642025Y74292D01*
X642275Y74042D01*
X642442Y73750D01*
X642525Y73417D01*
Y73083D01*
X642442Y72750D01*
X642275Y72458D01*
X642025Y72208D01*
X641733Y72042D01*
X641400Y72000D01*
G01X641733Y72667D02*
X642233Y72000D01*
G01X643708Y74083D02*
X643958Y74333D01*
X644250Y74458D01*
X644583Y74500D01*
X645000Y74417D01*
X645292Y74208D01*
X645375Y73958D01*
X645333Y73708D01*
X645167Y73500D01*
X644333Y73083D01*
X643958Y72792D01*
X643708Y72375D01*
X643625Y72000D01*
X645375D01*
G01X647600Y74500D02*
X647267Y74417D01*
X647017Y74208D01*
X646850Y73958D01*
X646725Y73625D01*
X646683Y73250D01*
X646725Y72875D01*
X646850Y72542D01*
X647017Y72292D01*
X647267Y72083D01*
X647600Y72000D01*
X647933Y72083D01*
X648183Y72292D01*
X648350Y72542D01*
X648475Y72875D01*
X648517Y73250D01*
X648475Y73625D01*
X648350Y73958D01*
X648183Y74208D01*
X647933Y74417D01*
X647600Y74500D01*
G01X663000Y60000D02*
Y74000D01*
G01X650000Y60000D02*
X663000D01*
G01X650000Y74000D02*
Y60000D01*
G01X663000Y74000D02*
X650000D01*
G01X639763Y110117D02*
Y114685D01*
G01X641613Y108267D02*
X646181D01*
G01X728071D02*
X649881D01*
G01X641613D02*
G02I-1850J0D01*
G01X649881D02*
G02I-1850J0D01*
G01X644983Y57000D02*
Y55208D01*
X645150Y54833D01*
X645483Y54583D01*
X645900Y54500D01*
X646317Y54583D01*
X646650Y54833D01*
X646817Y55208D01*
Y57000D01*
G01X649000Y54500D02*
Y57000D01*
X648500Y56500D01*
G01Y54500D02*
X649500D01*
G01X651308Y56583D02*
X651558Y56833D01*
X651850Y56958D01*
X652183Y57000D01*
X652600Y56917D01*
X652892Y56708D01*
X652975Y56458D01*
X652933Y56208D01*
X652767Y56000D01*
X651933Y55583D01*
X651558Y55292D01*
X651308Y54875D01*
X651225Y54500D01*
X652975D01*
G01X639763Y196575D02*
Y118385D01*
G01X641613Y116535D02*
G02I-1850J0D01*
G01X680700Y231800D02*
X684700D01*
Y239200D01*
G01X668353Y235149D02*
X665853D01*
Y236190D01*
X665978Y236524D01*
X666145Y236732D01*
X666478Y236815D01*
X666811Y236732D01*
X667020Y236482D01*
X667145Y236190D01*
Y235149D01*
G01Y236190D02*
X668353Y236815D01*
G01X666270Y238290D02*
X666020Y238540D01*
X665895Y238832D01*
X665853Y239165D01*
X665936Y239582D01*
X666145Y239874D01*
X666395Y239957D01*
X666645Y239915D01*
X666853Y239749D01*
X667270Y238915D01*
X667561Y238540D01*
X667978Y238290D01*
X668353Y238207D01*
Y239957D01*
G01X667311Y241390D02*
X667020Y241682D01*
X666853Y241932D01*
X666770Y242265D01*
X666853Y242557D01*
X667020Y242765D01*
X667270Y242932D01*
X667561Y242974D01*
X667811Y242932D01*
X668061Y242765D01*
X668270Y242515D01*
X668353Y242224D01*
X668270Y241890D01*
X668020Y241599D01*
X667645Y241432D01*
X667228Y241390D01*
X666686Y241474D01*
X666395Y241599D01*
X666103Y241807D01*
X665895Y242099D01*
X665853Y242390D01*
X665936Y242682D01*
X666145Y242890D01*
G01X668353Y245199D02*
X667811Y245282D01*
X667353Y245407D01*
X666936Y245574D01*
X666478Y245782D01*
X665853Y246115D01*
Y244449D01*
G01X669353Y232332D02*
X665353D01*
Y224932D01*
G01X642579Y235407D02*
X640079D01*
Y236448D01*
X640204Y236782D01*
X640371Y236990D01*
X640704Y237073D01*
X641037Y236990D01*
X641246Y236740D01*
X641371Y236448D01*
Y235407D01*
G01Y236448D02*
X642579Y237073D01*
G01X640496Y238548D02*
X640246Y238798D01*
X640121Y239090D01*
X640079Y239423D01*
X640162Y239840D01*
X640371Y240132D01*
X640621Y240215D01*
X640871Y240173D01*
X641079Y240007D01*
X641496Y239173D01*
X641787Y238798D01*
X642204Y238548D01*
X642579Y238465D01*
Y240215D01*
G01X641537Y241648D02*
X641246Y241940D01*
X641079Y242190D01*
X640996Y242523D01*
X641079Y242815D01*
X641246Y243023D01*
X641496Y243190D01*
X641787Y243232D01*
X642037Y243190D01*
X642287Y243023D01*
X642496Y242773D01*
X642579Y242482D01*
X642496Y242148D01*
X642246Y241857D01*
X641871Y241690D01*
X641454Y241648D01*
X640912Y241732D01*
X640621Y241857D01*
X640329Y242065D01*
X640121Y242357D01*
X640079Y242648D01*
X640162Y242940D01*
X640371Y243148D01*
G01X641537Y244748D02*
X641246Y245040D01*
X641079Y245290D01*
X640996Y245623D01*
X641079Y245915D01*
X641246Y246123D01*
X641496Y246290D01*
X641787Y246332D01*
X642037Y246290D01*
X642287Y246123D01*
X642496Y245873D01*
X642579Y245582D01*
X642496Y245248D01*
X642246Y244957D01*
X641871Y244790D01*
X641454Y244748D01*
X640912Y244832D01*
X640621Y244957D01*
X640329Y245165D01*
X640121Y245457D01*
X640079Y245748D01*
X640162Y246040D01*
X640371Y246248D01*
G01X643579Y232590D02*
X639579D01*
Y225190D01*
G01X659610Y235192D02*
X657110D01*
Y236233D01*
X657235Y236567D01*
X657402Y236775D01*
X657735Y236858D01*
X658068Y236775D01*
X658277Y236525D01*
X658402Y236233D01*
Y235192D01*
G01Y236233D02*
X659610Y236858D01*
G01X657527Y238333D02*
X657277Y238583D01*
X657152Y238875D01*
X657110Y239208D01*
X657193Y239625D01*
X657402Y239917D01*
X657652Y240000D01*
X657902Y239958D01*
X658110Y239792D01*
X658527Y238958D01*
X658818Y238583D01*
X659235Y238333D01*
X659610Y238250D01*
Y240000D01*
G01X658568Y241433D02*
X658277Y241725D01*
X658110Y241975D01*
X658027Y242308D01*
X658110Y242600D01*
X658277Y242808D01*
X658527Y242975D01*
X658818Y243017D01*
X659068Y242975D01*
X659318Y242808D01*
X659527Y242558D01*
X659610Y242267D01*
X659527Y241933D01*
X659277Y241642D01*
X658902Y241475D01*
X658485Y241433D01*
X657943Y241517D01*
X657652Y241642D01*
X657360Y241850D01*
X657152Y242142D01*
X657110Y242433D01*
X657193Y242725D01*
X657402Y242933D01*
G01X659235Y244408D02*
X659443Y244658D01*
X659568Y244950D01*
X659610Y245325D01*
X659527Y245700D01*
X659360Y245992D01*
X659068Y246200D01*
X658735Y246242D01*
X658402Y246158D01*
X658193Y245950D01*
X658027Y245658D01*
X657985Y245367D01*
X658027Y245075D01*
X658193Y244700D01*
X657110Y244825D01*
Y245950D01*
G01X660610Y232375D02*
X656610D01*
Y224975D01*
G01X664110Y235192D02*
X661610D01*
Y236233D01*
X661735Y236567D01*
X661902Y236775D01*
X662235Y236858D01*
X662568Y236775D01*
X662777Y236525D01*
X662902Y236233D01*
Y235192D01*
G01Y236233D02*
X664110Y236858D01*
G01X662027Y238333D02*
X661777Y238583D01*
X661652Y238875D01*
X661610Y239208D01*
X661693Y239625D01*
X661902Y239917D01*
X662152Y240000D01*
X662402Y239958D01*
X662610Y239792D01*
X663027Y238958D01*
X663318Y238583D01*
X663735Y238333D01*
X664110Y238250D01*
Y240000D01*
G01X663068Y241433D02*
X662777Y241725D01*
X662610Y241975D01*
X662527Y242308D01*
X662610Y242600D01*
X662777Y242808D01*
X663027Y242975D01*
X663318Y243017D01*
X663568Y242975D01*
X663818Y242808D01*
X664027Y242558D01*
X664110Y242267D01*
X664027Y241933D01*
X663777Y241642D01*
X663402Y241475D01*
X662985Y241433D01*
X662443Y241517D01*
X662152Y241642D01*
X661860Y241850D01*
X661652Y242142D01*
X661610Y242433D01*
X661693Y242725D01*
X661902Y242933D01*
G01X664110Y245825D02*
X661610D01*
X663402Y244283D01*
Y246367D01*
G01X665110Y232375D02*
X661110D01*
Y224975D01*
G01X655464Y235332D02*
X652964D01*
Y236373D01*
X653089Y236707D01*
X653256Y236915D01*
X653589Y236998D01*
X653922Y236915D01*
X654131Y236665D01*
X654256Y236373D01*
Y235332D01*
G01Y236373D02*
X655464Y236998D01*
G01X653381Y238473D02*
X653131Y238723D01*
X653006Y239015D01*
X652964Y239348D01*
X653047Y239765D01*
X653256Y240057D01*
X653506Y240140D01*
X653756Y240098D01*
X653964Y239932D01*
X654381Y239098D01*
X654672Y238723D01*
X655089Y238473D01*
X655464Y238390D01*
Y240140D01*
G01X654422Y241573D02*
X654131Y241865D01*
X653964Y242115D01*
X653881Y242448D01*
X653964Y242740D01*
X654131Y242948D01*
X654381Y243115D01*
X654672Y243157D01*
X654922Y243115D01*
X655172Y242948D01*
X655381Y242698D01*
X655464Y242407D01*
X655381Y242073D01*
X655131Y241782D01*
X654756Y241615D01*
X654339Y241573D01*
X653797Y241657D01*
X653506Y241782D01*
X653214Y241990D01*
X653006Y242282D01*
X652964Y242573D01*
X653047Y242865D01*
X653256Y243073D01*
G01X654964Y244548D02*
X655256Y244798D01*
X655422Y245132D01*
X655464Y245507D01*
X655422Y245840D01*
X655214Y246173D01*
X654964Y246382D01*
X654714Y246423D01*
X654422Y246340D01*
X654214Y246048D01*
X654131Y245757D01*
Y245382D01*
G01Y245757D02*
X654006Y246007D01*
X653797Y246215D01*
X653547Y246298D01*
X653297Y246215D01*
X653089Y246007D01*
X652964Y245632D01*
X653006Y245257D01*
X653172Y244882D01*
G01X656464Y232515D02*
X652464D01*
Y225115D01*
G01X651287Y235291D02*
X648787D01*
Y236332D01*
X648912Y236666D01*
X649079Y236874D01*
X649412Y236957D01*
X649745Y236874D01*
X649954Y236624D01*
X650079Y236332D01*
Y235291D01*
G01Y236332D02*
X651287Y236957D01*
G01X649204Y238432D02*
X648954Y238682D01*
X648829Y238974D01*
X648787Y239307D01*
X648870Y239724D01*
X649079Y240016D01*
X649329Y240099D01*
X649579Y240057D01*
X649787Y239891D01*
X650204Y239057D01*
X650495Y238682D01*
X650912Y238432D01*
X651287Y238349D01*
Y240099D01*
G01X650245Y241532D02*
X649954Y241824D01*
X649787Y242074D01*
X649704Y242407D01*
X649787Y242699D01*
X649954Y242907D01*
X650204Y243074D01*
X650495Y243116D01*
X650745Y243074D01*
X650995Y242907D01*
X651204Y242657D01*
X651287Y242366D01*
X651204Y242032D01*
X650954Y241741D01*
X650579Y241574D01*
X650162Y241532D01*
X649620Y241616D01*
X649329Y241741D01*
X649037Y241949D01*
X648829Y242241D01*
X648787Y242532D01*
X648870Y242824D01*
X649079Y243032D01*
G01X649204Y244632D02*
X648954Y244882D01*
X648829Y245174D01*
X648787Y245507D01*
X648870Y245924D01*
X649079Y246216D01*
X649329Y246299D01*
X649579Y246257D01*
X649787Y246091D01*
X650204Y245257D01*
X650495Y244882D01*
X650912Y244632D01*
X651287Y244549D01*
Y246299D01*
G01X652287Y232474D02*
X648287D01*
Y225074D01*
G01X646968Y235314D02*
X644468D01*
Y236355D01*
X644593Y236689D01*
X644760Y236897D01*
X645093Y236980D01*
X645426Y236897D01*
X645635Y236647D01*
X645760Y236355D01*
Y235314D01*
G01Y236355D02*
X646968Y236980D01*
G01X644885Y238455D02*
X644635Y238705D01*
X644510Y238997D01*
X644468Y239330D01*
X644551Y239747D01*
X644760Y240039D01*
X645010Y240122D01*
X645260Y240080D01*
X645468Y239914D01*
X645885Y239080D01*
X646176Y238705D01*
X646593Y238455D01*
X646968Y238372D01*
Y240122D01*
G01X645926Y241555D02*
X645635Y241847D01*
X645468Y242097D01*
X645385Y242430D01*
X645468Y242722D01*
X645635Y242930D01*
X645885Y243097D01*
X646176Y243139D01*
X646426Y243097D01*
X646676Y242930D01*
X646885Y242680D01*
X646968Y242389D01*
X646885Y242055D01*
X646635Y241764D01*
X646260Y241597D01*
X645843Y241555D01*
X645301Y241639D01*
X645010Y241764D01*
X644718Y241972D01*
X644510Y242264D01*
X644468Y242555D01*
X644551Y242847D01*
X644760Y243055D01*
G01X644468Y245447D02*
X644551Y245114D01*
X644760Y244864D01*
X645010Y244697D01*
X645343Y244572D01*
X645718Y244530D01*
X646093Y244572D01*
X646426Y244697D01*
X646676Y244864D01*
X646885Y245114D01*
X646968Y245447D01*
X646885Y245780D01*
X646676Y246030D01*
X646426Y246197D01*
X646093Y246322D01*
X645718Y246364D01*
X645343Y246322D01*
X645010Y246197D01*
X644760Y246030D01*
X644551Y245780D01*
X644468Y245447D01*
G01X647968Y232497D02*
X643968D01*
Y225097D01*
G01X693100Y239200D02*
X689100D01*
Y231800D01*
G01X693600D02*
X697600D01*
Y239200D01*
G01X688900D02*
X684900D01*
Y231800D01*
G01X680500Y239200D02*
X676500D01*
Y231800D01*
G01X637033Y217500D02*
Y215708D01*
X637200Y215333D01*
X637533Y215083D01*
X637950Y215000D01*
X638367Y215083D01*
X638700Y215333D01*
X638867Y215708D01*
Y217500D01*
G01X640258Y217083D02*
X640508Y217333D01*
X640800Y217458D01*
X641133Y217500D01*
X641550Y217417D01*
X641842Y217208D01*
X641925Y216958D01*
X641883Y216708D01*
X641717Y216500D01*
X640883Y216083D01*
X640508Y215792D01*
X640258Y215375D01*
X640175Y215000D01*
X641925D01*
G01X639763Y204843D02*
Y200275D01*
G01X641613Y206693D02*
X646181D01*
G01X728071D02*
X649881D01*
G01X641613D02*
G02I-1850J0D01*
G01Y198425D02*
G02I-1850J0D01*
G01X649881Y206693D02*
G02I-1850J0D01*
G01X669896Y223643D02*
X672396D01*
G01X669896Y222685D02*
Y224601D01*
G01X672396Y225910D02*
X669896D01*
Y226910D01*
X670021Y227243D01*
X670313Y227493D01*
X670646Y227576D01*
X670979Y227493D01*
X671229Y227285D01*
X671354Y226910D01*
Y225910D01*
G01X672396Y229843D02*
X669896D01*
X670396Y229343D01*
G01X672396D02*
Y230343D01*
G01Y233443D02*
X669896D01*
X671688Y231901D01*
Y233985D01*
G01X670313Y235251D02*
X670063Y235501D01*
X669938Y235793D01*
X669896Y236126D01*
X669979Y236543D01*
X670188Y236835D01*
X670438Y236918D01*
X670688Y236876D01*
X670896Y236710D01*
X671313Y235876D01*
X671604Y235501D01*
X672021Y235251D01*
X672396Y235168D01*
Y236918D01*
G01X673196Y223643D02*
X675696D01*
G01X673196Y222685D02*
Y224601D01*
G01X675696Y225910D02*
X673196D01*
Y226910D01*
X673321Y227243D01*
X673613Y227493D01*
X673946Y227576D01*
X674279Y227493D01*
X674529Y227285D01*
X674654Y226910D01*
Y225910D01*
G01X675696Y229843D02*
X673196D01*
X673696Y229343D01*
G01X675696D02*
Y230343D01*
G01X675196Y232026D02*
X675488Y232276D01*
X675654Y232610D01*
X675696Y232985D01*
X675654Y233318D01*
X675446Y233651D01*
X675196Y233860D01*
X674946Y233901D01*
X674654Y233818D01*
X674446Y233526D01*
X674363Y233235D01*
Y232860D01*
G01Y233235D02*
X674238Y233485D01*
X674029Y233693D01*
X673779Y233776D01*
X673529Y233693D01*
X673321Y233485D01*
X673196Y233110D01*
X673238Y232735D01*
X673404Y232360D01*
G01X675404Y235335D02*
X675613Y235626D01*
X675696Y235960D01*
X675613Y236293D01*
X675363Y236585D01*
X674988Y236793D01*
X674613Y236876D01*
X674154D01*
X673779Y236793D01*
X673446Y236585D01*
X673279Y236335D01*
X673196Y236043D01*
X673279Y235710D01*
X673446Y235460D01*
X673696Y235293D01*
X674029Y235210D01*
X674321Y235293D01*
X674613Y235501D01*
X674779Y235751D01*
X674821Y236043D01*
X674738Y236376D01*
X674529Y236626D01*
X674154Y236876D01*
G01X677334Y210800D02*
X679834D01*
G01X677334Y209842D02*
Y211758D01*
G01X679834Y213067D02*
X677334D01*
Y214067D01*
X677459Y214400D01*
X677751Y214650D01*
X678084Y214733D01*
X678417Y214650D01*
X678667Y214442D01*
X678792Y214067D01*
Y213067D01*
G01X679834Y217000D02*
X677334D01*
X677834Y216500D01*
G01X679834D02*
Y217500D01*
G01X679334Y219183D02*
X679626Y219433D01*
X679792Y219767D01*
X679834Y220142D01*
X679792Y220475D01*
X679584Y220808D01*
X679334Y221017D01*
X679084Y221058D01*
X678792Y220975D01*
X678584Y220683D01*
X678501Y220392D01*
Y220017D01*
G01Y220392D02*
X678376Y220642D01*
X678167Y220850D01*
X677917Y220933D01*
X677667Y220850D01*
X677459Y220642D01*
X677334Y220267D01*
X677376Y219892D01*
X677542Y219517D01*
G01X679834Y223200D02*
X679792Y223492D01*
X679667Y223825D01*
X679459Y224033D01*
X679167Y224117D01*
X678876Y224033D01*
X678626Y223783D01*
X678501Y223408D01*
Y222992D01*
X678417Y222742D01*
X678209Y222533D01*
X677917Y222450D01*
X677626Y222575D01*
X677417Y222867D01*
X677334Y223200D01*
X677417Y223533D01*
X677626Y223825D01*
X677917Y223950D01*
X678209Y223867D01*
X678417Y223658D01*
X678501Y223408D01*
Y222992D01*
X678626Y222617D01*
X678876Y222367D01*
X679167Y222283D01*
X679459Y222367D01*
X679667Y222575D01*
X679792Y222908D01*
X679834Y223200D01*
G01X686500Y211300D02*
X689000D01*
G01X686500Y210342D02*
Y212258D01*
G01X689000Y213567D02*
X686500D01*
Y214567D01*
X686625Y214900D01*
X686917Y215150D01*
X687250Y215233D01*
X687583Y215150D01*
X687833Y214942D01*
X687958Y214567D01*
Y213567D01*
G01X689000Y217500D02*
X686500D01*
X687000Y217000D01*
G01X689000D02*
Y218000D01*
G01X688500Y219683D02*
X688792Y219933D01*
X688958Y220267D01*
X689000Y220642D01*
X688958Y220975D01*
X688750Y221308D01*
X688500Y221517D01*
X688250Y221558D01*
X687958Y221475D01*
X687750Y221183D01*
X687667Y220892D01*
Y220517D01*
G01Y220892D02*
X687542Y221142D01*
X687333Y221350D01*
X687083Y221433D01*
X686833Y221350D01*
X686625Y221142D01*
X686500Y220767D01*
X686542Y220392D01*
X686708Y220017D01*
G01X687958Y222908D02*
X687667Y223200D01*
X687500Y223450D01*
X687417Y223783D01*
X687500Y224075D01*
X687667Y224283D01*
X687917Y224450D01*
X688208Y224492D01*
X688458Y224450D01*
X688708Y224283D01*
X688917Y224033D01*
X689000Y223742D01*
X688917Y223408D01*
X688667Y223117D01*
X688292Y222950D01*
X687875Y222908D01*
X687333Y222992D01*
X687042Y223117D01*
X686750Y223325D01*
X686542Y223617D01*
X686500Y223908D01*
X686583Y224200D01*
X686792Y224408D01*
G01X692800Y214500D02*
Y212000D01*
G01X691842Y214500D02*
X693758D01*
G01X695067Y212000D02*
Y214500D01*
X696067D01*
X696400Y214375D01*
X696650Y214083D01*
X696733Y213750D01*
X696650Y213417D01*
X696442Y213167D01*
X696067Y213042D01*
X695067D01*
G01X699000Y212000D02*
Y214500D01*
X698500Y214000D01*
G01Y212000D02*
X699500D01*
G01X701183Y212500D02*
X701433Y212208D01*
X701767Y212042D01*
X702142Y212000D01*
X702475Y212042D01*
X702808Y212250D01*
X703017Y212500D01*
X703058Y212750D01*
X702975Y213042D01*
X702683Y213250D01*
X702392Y213333D01*
X702017D01*
G01X702392D02*
X702642Y213458D01*
X702850Y213667D01*
X702933Y213917D01*
X702850Y214167D01*
X702642Y214375D01*
X702267Y214500D01*
X701892Y214458D01*
X701517Y214292D01*
G01X704283Y212375D02*
X704533Y212167D01*
X704825Y212042D01*
X705200Y212000D01*
X705575Y212083D01*
X705867Y212250D01*
X706075Y212542D01*
X706117Y212875D01*
X706033Y213208D01*
X705825Y213417D01*
X705533Y213583D01*
X705242Y213625D01*
X704950Y213583D01*
X704575Y213417D01*
X704700Y214500D01*
X705825D01*
G01X645328Y213393D02*
Y210893D01*
G01X644370Y213393D02*
X646286D01*
G01X647595Y210893D02*
Y213393D01*
X648595D01*
X648928Y213268D01*
X649178Y212976D01*
X649261Y212643D01*
X649178Y212310D01*
X648970Y212060D01*
X648595Y211935D01*
X647595D01*
G01X651528Y210893D02*
Y213393D01*
X651028Y212893D01*
G01Y210893D02*
X652028D01*
G01X653836Y212976D02*
X654086Y213226D01*
X654378Y213351D01*
X654711Y213393D01*
X655128Y213310D01*
X655420Y213101D01*
X655503Y212851D01*
X655461Y212601D01*
X655295Y212393D01*
X654461Y211976D01*
X654086Y211685D01*
X653836Y211268D01*
X653753Y210893D01*
X655503D01*
G01X657645D02*
X657728Y211435D01*
X657853Y211893D01*
X658020Y212310D01*
X658228Y212768D01*
X658561Y213393D01*
X656895D01*
G01X662480Y213330D02*
Y210830D01*
G01X661522Y213330D02*
X663438D01*
G01X664747Y210830D02*
Y213330D01*
X665747D01*
X666080Y213205D01*
X666330Y212913D01*
X666413Y212580D01*
X666330Y212247D01*
X666122Y211997D01*
X665747Y211872D01*
X664747D01*
G01X668680Y210830D02*
Y213330D01*
X668180Y212830D01*
G01Y210830D02*
X669180D01*
G01X670863Y211205D02*
X671113Y210997D01*
X671405Y210872D01*
X671780Y210830D01*
X672155Y210913D01*
X672447Y211080D01*
X672655Y211372D01*
X672697Y211705D01*
X672613Y212038D01*
X672405Y212247D01*
X672113Y212413D01*
X671822Y212455D01*
X671530Y212413D01*
X671155Y212247D01*
X671280Y213330D01*
X672405D01*
G01X675380Y210830D02*
Y213330D01*
X673838Y211538D01*
X675922D01*
G01X683000Y242017D02*
X680500D01*
Y243058D01*
X680625Y243392D01*
X680792Y243600D01*
X681125Y243683D01*
X681458Y243600D01*
X681667Y243350D01*
X681792Y243058D01*
Y242017D01*
G01Y243058D02*
X683000Y243683D01*
G01X680917Y245158D02*
X680667Y245408D01*
X680542Y245700D01*
X680500Y246033D01*
X680583Y246450D01*
X680792Y246742D01*
X681042Y246825D01*
X681292Y246783D01*
X681500Y246617D01*
X681917Y245783D01*
X682208Y245408D01*
X682625Y245158D01*
X683000Y245075D01*
Y246825D01*
G01Y248967D02*
X682458Y249050D01*
X682000Y249175D01*
X681583Y249342D01*
X681125Y249550D01*
X680500Y249883D01*
Y248217D01*
G01X682625Y251233D02*
X682833Y251483D01*
X682958Y251775D01*
X683000Y252150D01*
X682917Y252525D01*
X682750Y252817D01*
X682458Y253025D01*
X682125Y253067D01*
X681792Y252983D01*
X681583Y252775D01*
X681417Y252483D01*
X681375Y252192D01*
X681417Y251900D01*
X681583Y251525D01*
X680500Y251650D01*
Y252775D01*
G01X691000Y242017D02*
X688500D01*
Y243058D01*
X688625Y243392D01*
X688792Y243600D01*
X689125Y243683D01*
X689458Y243600D01*
X689667Y243350D01*
X689792Y243058D01*
Y242017D01*
G01Y243058D02*
X691000Y243683D01*
G01X688917Y245158D02*
X688667Y245408D01*
X688542Y245700D01*
X688500Y246033D01*
X688583Y246450D01*
X688792Y246742D01*
X689042Y246825D01*
X689292Y246783D01*
X689500Y246617D01*
X689917Y245783D01*
X690208Y245408D01*
X690625Y245158D01*
X691000Y245075D01*
Y246825D01*
G01Y249550D02*
X688500D01*
X690292Y248008D01*
Y250092D01*
G01X691000Y252067D02*
X690458Y252150D01*
X690000Y252275D01*
X689583Y252442D01*
X689125Y252650D01*
X688500Y252983D01*
Y251317D01*
G01X695000Y242017D02*
X692500D01*
Y243058D01*
X692625Y243392D01*
X692792Y243600D01*
X693125Y243683D01*
X693458Y243600D01*
X693667Y243350D01*
X693792Y243058D01*
Y242017D01*
G01Y243058D02*
X695000Y243683D01*
G01X692917Y245158D02*
X692667Y245408D01*
X692542Y245700D01*
X692500Y246033D01*
X692583Y246450D01*
X692792Y246742D01*
X693042Y246825D01*
X693292Y246783D01*
X693500Y246617D01*
X693917Y245783D01*
X694208Y245408D01*
X694625Y245158D01*
X695000Y245075D01*
Y246825D01*
G01X693958Y248258D02*
X693667Y248550D01*
X693500Y248800D01*
X693417Y249133D01*
X693500Y249425D01*
X693667Y249633D01*
X693917Y249800D01*
X694208Y249842D01*
X694458Y249800D01*
X694708Y249633D01*
X694917Y249383D01*
X695000Y249092D01*
X694917Y248758D01*
X694667Y248467D01*
X694292Y248300D01*
X693875Y248258D01*
X693333Y248342D01*
X693042Y248467D01*
X692750Y248675D01*
X692542Y248967D01*
X692500Y249258D01*
X692583Y249550D01*
X692792Y249758D01*
G01X694708Y251442D02*
X694917Y251733D01*
X695000Y252067D01*
X694917Y252400D01*
X694667Y252692D01*
X694292Y252900D01*
X693917Y252983D01*
X693458D01*
X693083Y252900D01*
X692750Y252692D01*
X692583Y252442D01*
X692500Y252150D01*
X692583Y251817D01*
X692750Y251567D01*
X693000Y251400D01*
X693333Y251317D01*
X693625Y251400D01*
X693917Y251608D01*
X694083Y251858D01*
X694125Y252150D01*
X694042Y252483D01*
X693833Y252733D01*
X693458Y252983D01*
G01X687000Y242017D02*
X684500D01*
Y243058D01*
X684625Y243392D01*
X684792Y243600D01*
X685125Y243683D01*
X685458Y243600D01*
X685667Y243350D01*
X685792Y243058D01*
Y242017D01*
G01Y243058D02*
X687000Y243683D01*
G01X684917Y245158D02*
X684667Y245408D01*
X684542Y245700D01*
X684500Y246033D01*
X684583Y246450D01*
X684792Y246742D01*
X685042Y246825D01*
X685292Y246783D01*
X685500Y246617D01*
X685917Y245783D01*
X686208Y245408D01*
X686625Y245158D01*
X687000Y245075D01*
Y246825D01*
G01X686625Y248133D02*
X686833Y248383D01*
X686958Y248675D01*
X687000Y249050D01*
X686917Y249425D01*
X686750Y249717D01*
X686458Y249925D01*
X686125Y249967D01*
X685792Y249883D01*
X685583Y249675D01*
X685417Y249383D01*
X685375Y249092D01*
X685417Y248800D01*
X685583Y248425D01*
X684500Y248550D01*
Y249675D01*
G01X686500Y251233D02*
X686792Y251483D01*
X686958Y251817D01*
X687000Y252192D01*
X686958Y252525D01*
X686750Y252858D01*
X686500Y253067D01*
X686250Y253108D01*
X685958Y253025D01*
X685750Y252733D01*
X685667Y252442D01*
Y252067D01*
G01Y252442D02*
X685542Y252692D01*
X685333Y252900D01*
X685083Y252983D01*
X684833Y252900D01*
X684625Y252692D01*
X684500Y252317D01*
X684542Y251942D01*
X684708Y251567D01*
G01X679000Y242017D02*
X676500D01*
Y243058D01*
X676625Y243392D01*
X676792Y243600D01*
X677125Y243683D01*
X677458Y243600D01*
X677667Y243350D01*
X677792Y243058D01*
Y242017D01*
G01Y243058D02*
X679000Y243683D01*
G01X676917Y245158D02*
X676667Y245408D01*
X676542Y245700D01*
X676500Y246033D01*
X676583Y246450D01*
X676792Y246742D01*
X677042Y246825D01*
X677292Y246783D01*
X677500Y246617D01*
X677917Y245783D01*
X678208Y245408D01*
X678625Y245158D01*
X679000Y245075D01*
Y246825D01*
G01X678625Y248133D02*
X678833Y248383D01*
X678958Y248675D01*
X679000Y249050D01*
X678917Y249425D01*
X678750Y249717D01*
X678458Y249925D01*
X678125Y249967D01*
X677792Y249883D01*
X677583Y249675D01*
X677417Y249383D01*
X677375Y249092D01*
X677417Y248800D01*
X677583Y248425D01*
X676500Y248550D01*
Y249675D01*
G01X676917Y251358D02*
X676667Y251608D01*
X676542Y251900D01*
X676500Y252233D01*
X676583Y252650D01*
X676792Y252942D01*
X677042Y253025D01*
X677292Y252983D01*
X677500Y252817D01*
X677917Y251983D01*
X678208Y251608D01*
X678625Y251358D01*
X679000Y251275D01*
Y253025D01*
G01X638667Y289959D02*
X638417Y290084D01*
X638125Y290167D01*
X637792D01*
X637417Y290042D01*
X637125Y289834D01*
X636917Y289584D01*
X636750Y289167D01*
X636708Y288792D01*
X636792Y288417D01*
X636917Y288167D01*
X637167Y287917D01*
X637458Y287750D01*
X637750Y287667D01*
X638042D01*
X638333Y287750D01*
X638583Y287875D01*
X638792Y288042D01*
G01X639933D02*
X640183Y287834D01*
X640475Y287709D01*
X640850Y287667D01*
X641225Y287750D01*
X641517Y287917D01*
X641725Y288209D01*
X641767Y288542D01*
X641683Y288875D01*
X641475Y289084D01*
X641183Y289250D01*
X640892Y289292D01*
X640600Y289250D01*
X640225Y289084D01*
X640350Y290167D01*
X641475D01*
G01X643033Y288167D02*
X643283Y287875D01*
X643617Y287709D01*
X643992Y287667D01*
X644325Y287709D01*
X644658Y287917D01*
X644867Y288167D01*
X644908Y288417D01*
X644825Y288709D01*
X644533Y288917D01*
X644242Y289000D01*
X643867D01*
G01X644242D02*
X644492Y289125D01*
X644700Y289334D01*
X644783Y289584D01*
X644700Y289834D01*
X644492Y290042D01*
X644117Y290167D01*
X643742Y290125D01*
X643367Y289959D01*
G01X646133Y288167D02*
X646383Y287875D01*
X646717Y287709D01*
X647092Y287667D01*
X647425Y287709D01*
X647758Y287917D01*
X647967Y288167D01*
X648008Y288417D01*
X647925Y288709D01*
X647633Y288917D01*
X647342Y289000D01*
X646967D01*
G01X647342D02*
X647592Y289125D01*
X647800Y289334D01*
X647883Y289584D01*
X647800Y289834D01*
X647592Y290042D01*
X647217Y290167D01*
X646842Y290125D01*
X646467Y289959D01*
G01X651767Y301292D02*
X651517Y301417D01*
X651225Y301500D01*
X650892D01*
X650517Y301375D01*
X650225Y301167D01*
X650017Y300917D01*
X649850Y300500D01*
X649808Y300125D01*
X649892Y299750D01*
X650017Y299500D01*
X650267Y299250D01*
X650558Y299083D01*
X650850Y299000D01*
X651142D01*
X651433Y299083D01*
X651683Y299208D01*
X651892Y299375D01*
G01X653158Y300042D02*
X653450Y300333D01*
X653700Y300500D01*
X654033Y300583D01*
X654325Y300500D01*
X654533Y300333D01*
X654700Y300083D01*
X654742Y299792D01*
X654700Y299542D01*
X654533Y299292D01*
X654283Y299083D01*
X653992Y299000D01*
X653658Y299083D01*
X653367Y299333D01*
X653200Y299708D01*
X653158Y300125D01*
X653242Y300667D01*
X653367Y300958D01*
X653575Y301250D01*
X653867Y301458D01*
X654158Y301500D01*
X654450Y301417D01*
X654658Y301208D01*
G01X656133Y299375D02*
X656383Y299167D01*
X656675Y299042D01*
X657050Y299000D01*
X657425Y299083D01*
X657717Y299250D01*
X657925Y299542D01*
X657967Y299875D01*
X657883Y300208D01*
X657675Y300417D01*
X657383Y300583D01*
X657092Y300625D01*
X656800Y300583D01*
X656425Y300417D01*
X656550Y301500D01*
X657675D01*
G01X660067Y299000D02*
X660150Y299542D01*
X660275Y300000D01*
X660442Y300417D01*
X660650Y300875D01*
X660983Y301500D01*
X659317D01*
G01X651767Y297292D02*
X651517Y297417D01*
X651225Y297500D01*
X650892D01*
X650517Y297375D01*
X650225Y297167D01*
X650017Y296917D01*
X649850Y296500D01*
X649808Y296125D01*
X649892Y295750D01*
X650017Y295500D01*
X650267Y295250D01*
X650558Y295083D01*
X650850Y295000D01*
X651142D01*
X651433Y295083D01*
X651683Y295208D01*
X651892Y295375D01*
G01X653158Y296042D02*
X653450Y296333D01*
X653700Y296500D01*
X654033Y296583D01*
X654325Y296500D01*
X654533Y296333D01*
X654700Y296083D01*
X654742Y295792D01*
X654700Y295542D01*
X654533Y295292D01*
X654283Y295083D01*
X653992Y295000D01*
X653658Y295083D01*
X653367Y295333D01*
X653200Y295708D01*
X653158Y296125D01*
X653242Y296667D01*
X653367Y296958D01*
X653575Y297250D01*
X653867Y297458D01*
X654158Y297500D01*
X654450Y297417D01*
X654658Y297208D01*
G01X657550Y295000D02*
Y297500D01*
X656008Y295708D01*
X658092D01*
G01X659233Y295500D02*
X659483Y295208D01*
X659817Y295042D01*
X660192Y295000D01*
X660525Y295042D01*
X660858Y295250D01*
X661067Y295500D01*
X661108Y295750D01*
X661025Y296042D01*
X660733Y296250D01*
X660442Y296333D01*
X660067D01*
G01X660442D02*
X660692Y296458D01*
X660900Y296667D01*
X660983Y296917D01*
X660900Y297167D01*
X660692Y297375D01*
X660317Y297500D01*
X659942Y297458D01*
X659567Y297292D01*
G01X651667Y292792D02*
X651417Y292917D01*
X651125Y293000D01*
X650792D01*
X650417Y292875D01*
X650125Y292667D01*
X649917Y292417D01*
X649750Y292000D01*
X649708Y291625D01*
X649792Y291250D01*
X649917Y291000D01*
X650167Y290750D01*
X650458Y290583D01*
X650750Y290500D01*
X651042D01*
X651333Y290583D01*
X651583Y290708D01*
X651792Y290875D01*
G01X653058Y291542D02*
X653350Y291833D01*
X653600Y292000D01*
X653933Y292083D01*
X654225Y292000D01*
X654433Y291833D01*
X654600Y291583D01*
X654642Y291292D01*
X654600Y291042D01*
X654433Y290792D01*
X654183Y290583D01*
X653892Y290500D01*
X653558Y290583D01*
X653267Y290833D01*
X653100Y291208D01*
X653058Y291625D01*
X653142Y292167D01*
X653267Y292458D01*
X653475Y292750D01*
X653767Y292958D01*
X654058Y293000D01*
X654350Y292917D01*
X654558Y292708D01*
G01X656033Y291000D02*
X656283Y290708D01*
X656617Y290542D01*
X656992Y290500D01*
X657325Y290542D01*
X657658Y290750D01*
X657867Y291000D01*
X657908Y291250D01*
X657825Y291542D01*
X657533Y291750D01*
X657242Y291833D01*
X656867D01*
G01X657242D02*
X657492Y291958D01*
X657700Y292167D01*
X657783Y292417D01*
X657700Y292667D01*
X657492Y292875D01*
X657117Y293000D01*
X656742Y292958D01*
X656367Y292792D01*
G01X659967Y290500D02*
X660050Y291042D01*
X660175Y291500D01*
X660342Y291917D01*
X660550Y292375D01*
X660883Y293000D01*
X659217D01*
G01X651667Y288492D02*
X651417Y288617D01*
X651125Y288700D01*
X650792D01*
X650417Y288575D01*
X650125Y288367D01*
X649917Y288117D01*
X649750Y287700D01*
X649708Y287325D01*
X649792Y286950D01*
X649917Y286700D01*
X650167Y286450D01*
X650458Y286283D01*
X650750Y286200D01*
X651042D01*
X651333Y286283D01*
X651583Y286408D01*
X651792Y286575D01*
G01X653058Y287242D02*
X653350Y287533D01*
X653600Y287700D01*
X653933Y287783D01*
X654225Y287700D01*
X654433Y287533D01*
X654600Y287283D01*
X654642Y286992D01*
X654600Y286742D01*
X654433Y286492D01*
X654183Y286283D01*
X653892Y286200D01*
X653558Y286283D01*
X653267Y286533D01*
X653100Y286908D01*
X653058Y287325D01*
X653142Y287867D01*
X653267Y288158D01*
X653475Y288450D01*
X653767Y288658D01*
X654058Y288700D01*
X654350Y288617D01*
X654558Y288408D01*
G01X656033Y286700D02*
X656283Y286408D01*
X656617Y286242D01*
X656992Y286200D01*
X657325Y286242D01*
X657658Y286450D01*
X657867Y286700D01*
X657908Y286950D01*
X657825Y287242D01*
X657533Y287450D01*
X657242Y287533D01*
X656867D01*
G01X657242D02*
X657492Y287658D01*
X657700Y287867D01*
X657783Y288117D01*
X657700Y288367D01*
X657492Y288575D01*
X657117Y288700D01*
X656742Y288658D01*
X656367Y288492D01*
G01X659258Y287242D02*
X659550Y287533D01*
X659800Y287700D01*
X660133Y287783D01*
X660425Y287700D01*
X660633Y287533D01*
X660800Y287283D01*
X660842Y286992D01*
X660800Y286742D01*
X660633Y286492D01*
X660383Y286283D01*
X660092Y286200D01*
X659758Y286283D01*
X659467Y286533D01*
X659300Y286908D01*
X659258Y287325D01*
X659342Y287867D01*
X659467Y288158D01*
X659675Y288450D01*
X659967Y288658D01*
X660258Y288700D01*
X660550Y288617D01*
X660758Y288408D01*
G01X651667Y284092D02*
X651417Y284217D01*
X651125Y284300D01*
X650792D01*
X650417Y284175D01*
X650125Y283967D01*
X649917Y283717D01*
X649750Y283300D01*
X649708Y282925D01*
X649792Y282550D01*
X649917Y282300D01*
X650167Y282050D01*
X650458Y281883D01*
X650750Y281800D01*
X651042D01*
X651333Y281883D01*
X651583Y282008D01*
X651792Y282175D01*
G01X653058Y282842D02*
X653350Y283133D01*
X653600Y283300D01*
X653933Y283383D01*
X654225Y283300D01*
X654433Y283133D01*
X654600Y282883D01*
X654642Y282592D01*
X654600Y282342D01*
X654433Y282092D01*
X654183Y281883D01*
X653892Y281800D01*
X653558Y281883D01*
X653267Y282133D01*
X653100Y282508D01*
X653058Y282925D01*
X653142Y283467D01*
X653267Y283758D01*
X653475Y284050D01*
X653767Y284258D01*
X654058Y284300D01*
X654350Y284217D01*
X654558Y284008D01*
G01X656033Y282300D02*
X656283Y282008D01*
X656617Y281842D01*
X656992Y281800D01*
X657325Y281842D01*
X657658Y282050D01*
X657867Y282300D01*
X657908Y282550D01*
X657825Y282842D01*
X657533Y283050D01*
X657242Y283133D01*
X656867D01*
G01X657242D02*
X657492Y283258D01*
X657700Y283467D01*
X657783Y283717D01*
X657700Y283967D01*
X657492Y284175D01*
X657117Y284300D01*
X656742Y284258D01*
X656367Y284092D01*
G01X659133Y282175D02*
X659383Y281967D01*
X659675Y281842D01*
X660050Y281800D01*
X660425Y281883D01*
X660717Y282050D01*
X660925Y282342D01*
X660967Y282675D01*
X660883Y283008D01*
X660675Y283217D01*
X660383Y283383D01*
X660092Y283425D01*
X659800Y283383D01*
X659425Y283217D01*
X659550Y284300D01*
X660675D01*
G01X652567Y280000D02*
Y277500D01*
X654233D01*
G01X655583Y278000D02*
X655833Y277708D01*
X656167Y277542D01*
X656542Y277500D01*
X656875Y277542D01*
X657208Y277750D01*
X657417Y278000D01*
X657458Y278250D01*
X657375Y278542D01*
X657083Y278750D01*
X656792Y278833D01*
X656417D01*
G01X656792D02*
X657042Y278958D01*
X657250Y279167D01*
X657333Y279417D01*
X657250Y279667D01*
X657042Y279875D01*
X656667Y280000D01*
X656292Y279958D01*
X655917Y279792D01*
G01X658808Y279583D02*
X659058Y279833D01*
X659350Y279958D01*
X659683Y280000D01*
X660100Y279917D01*
X660392Y279708D01*
X660475Y279458D01*
X660433Y279208D01*
X660267Y279000D01*
X659433Y278583D01*
X659058Y278292D01*
X658808Y277875D01*
X658725Y277500D01*
X660475D01*
G01X635708Y328767D02*
X635583Y328517D01*
X635500Y328225D01*
Y327892D01*
X635625Y327517D01*
X635833Y327225D01*
X636083Y327017D01*
X636500Y326850D01*
X636875Y326808D01*
X637250Y326892D01*
X637500Y327017D01*
X637750Y327267D01*
X637917Y327558D01*
X638000Y327850D01*
Y328142D01*
X637917Y328433D01*
X637792Y328683D01*
X637625Y328892D01*
G01Y330033D02*
X637833Y330283D01*
X637958Y330575D01*
X638000Y330950D01*
X637917Y331325D01*
X637750Y331617D01*
X637458Y331825D01*
X637125Y331867D01*
X636792Y331783D01*
X636583Y331575D01*
X636417Y331283D01*
X636375Y330992D01*
X636417Y330700D01*
X636583Y330325D01*
X635500Y330450D01*
Y331575D01*
G01X635917Y333258D02*
X635667Y333508D01*
X635542Y333800D01*
X635500Y334133D01*
X635583Y334550D01*
X635792Y334842D01*
X636042Y334925D01*
X636292Y334883D01*
X636500Y334717D01*
X636917Y333883D01*
X637208Y333508D01*
X637625Y333258D01*
X638000Y333175D01*
Y334925D01*
G01X637625Y336233D02*
X637833Y336483D01*
X637958Y336775D01*
X638000Y337150D01*
X637917Y337525D01*
X637750Y337817D01*
X637458Y338025D01*
X637125Y338067D01*
X636792Y337983D01*
X636583Y337775D01*
X636417Y337483D01*
X636375Y337192D01*
X636417Y336900D01*
X636583Y336525D01*
X635500Y336650D01*
Y337775D01*
G01X639708Y328767D02*
X639583Y328517D01*
X639500Y328225D01*
Y327892D01*
X639625Y327517D01*
X639833Y327225D01*
X640083Y327017D01*
X640500Y326850D01*
X640875Y326808D01*
X641250Y326892D01*
X641500Y327017D01*
X641750Y327267D01*
X641917Y327558D01*
X642000Y327850D01*
Y328142D01*
X641917Y328433D01*
X641792Y328683D01*
X641625Y328892D01*
G01Y330033D02*
X641833Y330283D01*
X641958Y330575D01*
X642000Y330950D01*
X641917Y331325D01*
X641750Y331617D01*
X641458Y331825D01*
X641125Y331867D01*
X640792Y331783D01*
X640583Y331575D01*
X640417Y331283D01*
X640375Y330992D01*
X640417Y330700D01*
X640583Y330325D01*
X639500Y330450D01*
Y331575D01*
G01X639917Y333258D02*
X639667Y333508D01*
X639542Y333800D01*
X639500Y334133D01*
X639583Y334550D01*
X639792Y334842D01*
X640042Y334925D01*
X640292Y334883D01*
X640500Y334717D01*
X640917Y333883D01*
X641208Y333508D01*
X641625Y333258D01*
X642000Y333175D01*
Y334925D01*
G01X640958Y336358D02*
X640667Y336650D01*
X640500Y336900D01*
X640417Y337233D01*
X640500Y337525D01*
X640667Y337733D01*
X640917Y337900D01*
X641208Y337942D01*
X641458Y337900D01*
X641708Y337733D01*
X641917Y337483D01*
X642000Y337192D01*
X641917Y336858D01*
X641667Y336567D01*
X641292Y336400D01*
X640875Y336358D01*
X640333Y336442D01*
X640042Y336567D01*
X639750Y336775D01*
X639542Y337067D01*
X639500Y337358D01*
X639583Y337650D01*
X639792Y337858D01*
G01X668699Y330525D02*
X668449Y330650D01*
X668157Y330733D01*
X667824D01*
X667449Y330608D01*
X667157Y330400D01*
X666949Y330150D01*
X666782Y329733D01*
X666740Y329358D01*
X666824Y328983D01*
X666949Y328733D01*
X667199Y328483D01*
X667490Y328316D01*
X667782Y328233D01*
X668074D01*
X668365Y328316D01*
X668615Y328441D01*
X668824Y328608D01*
G01X670799Y328233D02*
X670882Y328775D01*
X671007Y329233D01*
X671174Y329650D01*
X671382Y330108D01*
X671715Y330733D01*
X670049D01*
G01X674482Y328233D02*
Y330733D01*
X672940Y328941D01*
X675024D01*
G01X677582Y328233D02*
Y330733D01*
X676040Y328941D01*
X678124D01*
G01X684700Y332200D02*
X691700D01*
Y318800D01*
X684700D01*
Y332200D01*
G01X636008Y361367D02*
X635883Y361117D01*
X635800Y360825D01*
Y360492D01*
X635925Y360117D01*
X636133Y359825D01*
X636383Y359617D01*
X636800Y359450D01*
X637175Y359408D01*
X637550Y359492D01*
X637800Y359617D01*
X638050Y359867D01*
X638217Y360158D01*
X638300Y360450D01*
Y360742D01*
X638217Y361033D01*
X638092Y361283D01*
X637925Y361492D01*
G01X637258Y362758D02*
X636967Y363050D01*
X636800Y363300D01*
X636717Y363633D01*
X636800Y363925D01*
X636967Y364133D01*
X637217Y364300D01*
X637508Y364342D01*
X637758Y364300D01*
X638008Y364133D01*
X638217Y363883D01*
X638300Y363592D01*
X638217Y363258D01*
X637967Y362967D01*
X637592Y362800D01*
X637175Y362758D01*
X636633Y362842D01*
X636342Y362967D01*
X636050Y363175D01*
X635842Y363467D01*
X635800Y363758D01*
X635883Y364050D01*
X636092Y364258D01*
G01X638300Y367150D02*
X635800D01*
X637592Y365608D01*
Y367692D01*
G01X638300Y370250D02*
X635800D01*
X637592Y368708D01*
Y370792D01*
G01X699100Y309200D02*
X693600D01*
G01Y317200D02*
X699100D01*
G01X681500D02*
X687000D01*
G01X681500Y309200D02*
Y317200D01*
G01X687000Y309200D02*
X681500D01*
G01X670333Y332834D02*
X667833D01*
Y333875D01*
X667958Y334209D01*
X668125Y334417D01*
X668458Y334500D01*
X668791Y334417D01*
X669000Y334167D01*
X669125Y333875D01*
Y332834D01*
G01Y333875D02*
X670333Y334500D01*
G01X669291Y335975D02*
X669000Y336267D01*
X668833Y336517D01*
X668750Y336850D01*
X668833Y337142D01*
X669000Y337350D01*
X669250Y337517D01*
X669541Y337559D01*
X669791Y337517D01*
X670041Y337350D01*
X670250Y337100D01*
X670333Y336809D01*
X670250Y336475D01*
X670000Y336184D01*
X669625Y336017D01*
X669208Y335975D01*
X668666Y336059D01*
X668375Y336184D01*
X668083Y336392D01*
X667875Y336684D01*
X667833Y336975D01*
X667916Y337267D01*
X668125Y337475D01*
G01X670041Y339159D02*
X670250Y339450D01*
X670333Y339784D01*
X670250Y340117D01*
X670000Y340409D01*
X669625Y340617D01*
X669250Y340700D01*
X668791D01*
X668416Y340617D01*
X668083Y340409D01*
X667916Y340159D01*
X667833Y339867D01*
X667916Y339534D01*
X668083Y339284D01*
X668333Y339117D01*
X668666Y339034D01*
X668958Y339117D01*
X669250Y339325D01*
X669416Y339575D01*
X669458Y339867D01*
X669375Y340200D01*
X669166Y340450D01*
X668791Y340700D01*
G01X670333Y343467D02*
X667833D01*
X669625Y341925D01*
Y344009D01*
G01X671117Y362667D02*
Y357467D01*
G01X664117Y362667D02*
Y354867D01*
G01X671117Y349267D02*
Y357967D01*
G01X664117Y349267D02*
X671117D01*
G01X664117Y355667D02*
Y349267D01*
G01X663731Y319683D02*
X641131D01*
G01X663731Y309483D02*
Y319683D01*
G01X641131Y309483D02*
X663731D01*
G01X641131Y319683D02*
Y309483D01*
G01X663731Y319683D02*
X641131D01*
G01X663731Y309483D02*
Y319683D01*
G01X641131Y309483D02*
X663731D01*
G01X641131Y319683D02*
Y309483D01*
G01X639758Y361317D02*
X639633Y361067D01*
X639550Y360775D01*
Y360442D01*
X639675Y360067D01*
X639883Y359775D01*
X640133Y359567D01*
X640550Y359400D01*
X640925Y359358D01*
X641300Y359442D01*
X641550Y359567D01*
X641800Y359817D01*
X641967Y360108D01*
X642050Y360400D01*
Y360692D01*
X641967Y360983D01*
X641842Y361233D01*
X641675Y361442D01*
G01X641008Y362708D02*
X640717Y363000D01*
X640550Y363250D01*
X640467Y363583D01*
X640550Y363875D01*
X640717Y364083D01*
X640967Y364250D01*
X641258Y364292D01*
X641508Y364250D01*
X641758Y364083D01*
X641967Y363833D01*
X642050Y363542D01*
X641967Y363208D01*
X641717Y362917D01*
X641342Y362750D01*
X640925Y362708D01*
X640383Y362792D01*
X640092Y362917D01*
X639800Y363125D01*
X639592Y363417D01*
X639550Y363708D01*
X639633Y364000D01*
X639842Y364208D01*
G01X641675Y365683D02*
X641883Y365933D01*
X642008Y366225D01*
X642050Y366600D01*
X641967Y366975D01*
X641800Y367267D01*
X641508Y367475D01*
X641175Y367517D01*
X640842Y367433D01*
X640633Y367225D01*
X640467Y366933D01*
X640425Y366642D01*
X640467Y366350D01*
X640633Y365975D01*
X639550Y366100D01*
Y367225D01*
G01X642050Y369700D02*
X642008Y369992D01*
X641883Y370325D01*
X641675Y370533D01*
X641383Y370617D01*
X641092Y370533D01*
X640842Y370283D01*
X640717Y369908D01*
Y369492D01*
X640633Y369242D01*
X640425Y369033D01*
X640133Y368950D01*
X639842Y369075D01*
X639633Y369367D01*
X639550Y369700D01*
X639633Y370033D01*
X639842Y370325D01*
X640133Y370450D01*
X640425Y370367D01*
X640633Y370158D01*
X640717Y369908D01*
Y369492D01*
X640842Y369117D01*
X641092Y368867D01*
X641383Y368783D01*
X641675Y368867D01*
X641883Y369075D01*
X642008Y369408D01*
X642050Y369700D01*
G01X708376Y333571D02*
X672076D01*
Y361971D01*
X708376D01*
Y333571D01*
G01X668054Y422006D02*
Y435406D01*
G01X678054Y422006D02*
X668054D01*
G01X678054Y435406D02*
Y422006D01*
G01X642000Y406517D02*
X639500D01*
Y407558D01*
X639625Y407892D01*
X639792Y408100D01*
X640125Y408183D01*
X640458Y408100D01*
X640667Y407850D01*
X640792Y407558D01*
Y406517D01*
G01Y407558D02*
X642000Y408183D01*
G01X641500Y409533D02*
X641792Y409783D01*
X641958Y410117D01*
X642000Y410492D01*
X641958Y410825D01*
X641750Y411158D01*
X641500Y411367D01*
X641250Y411408D01*
X640958Y411325D01*
X640750Y411033D01*
X640667Y410742D01*
Y410367D01*
G01Y410742D02*
X640542Y410992D01*
X640333Y411200D01*
X640083Y411283D01*
X639833Y411200D01*
X639625Y410992D01*
X639500Y410617D01*
X639542Y410242D01*
X639708Y409867D01*
G01X642000Y413467D02*
X641458Y413550D01*
X641000Y413675D01*
X640583Y413842D01*
X640125Y414050D01*
X639500Y414383D01*
Y412717D01*
G01X642000Y417150D02*
X639500D01*
X641292Y415608D01*
Y417692D01*
G01X656770Y400060D02*
X652770D01*
Y392660D01*
G01X688390Y430270D02*
X684390D01*
Y422870D01*
G01X697380Y430250D02*
X693380D01*
Y422850D01*
G01X646000Y406517D02*
X643500D01*
Y407558D01*
X643625Y407892D01*
X643792Y408100D01*
X644125Y408183D01*
X644458Y408100D01*
X644667Y407850D01*
X644792Y407558D01*
Y406517D01*
G01Y407558D02*
X646000Y408183D01*
G01X645625Y409533D02*
X645833Y409783D01*
X645958Y410075D01*
X646000Y410450D01*
X645917Y410825D01*
X645750Y411117D01*
X645458Y411325D01*
X645125Y411367D01*
X644792Y411283D01*
X644583Y411075D01*
X644417Y410783D01*
X644375Y410492D01*
X644417Y410200D01*
X644583Y409825D01*
X643500Y409950D01*
Y411075D01*
G01X645500Y412633D02*
X645792Y412883D01*
X645958Y413217D01*
X646000Y413592D01*
X645958Y413925D01*
X645750Y414258D01*
X645500Y414467D01*
X645250Y414508D01*
X644958Y414425D01*
X644750Y414133D01*
X644667Y413842D01*
Y413467D01*
G01Y413842D02*
X644542Y414092D01*
X644333Y414300D01*
X644083Y414383D01*
X643833Y414300D01*
X643625Y414092D01*
X643500Y413717D01*
X643542Y413342D01*
X643708Y412967D01*
G01X645625Y415733D02*
X645833Y415983D01*
X645958Y416275D01*
X646000Y416650D01*
X645917Y417025D01*
X645750Y417317D01*
X645458Y417525D01*
X645125Y417567D01*
X644792Y417483D01*
X644583Y417275D01*
X644417Y416983D01*
X644375Y416692D01*
X644417Y416400D01*
X644583Y416025D01*
X643500Y416150D01*
Y417275D01*
G01X660840Y400060D02*
X656840D01*
Y392660D01*
G01X642485Y421963D02*
Y424463D01*
X643526D01*
X643860Y424338D01*
X644068Y424171D01*
X644151Y423838D01*
X644068Y423505D01*
X643818Y423296D01*
X643526Y423171D01*
X642485D01*
G01X643526D02*
X644151Y421963D01*
G01X646918D02*
Y424463D01*
X645376Y422671D01*
X647460D01*
G01X648810Y422255D02*
X649101Y422046D01*
X649435Y421963D01*
X649768Y422046D01*
X650060Y422296D01*
X650268Y422671D01*
X650351Y423046D01*
Y423505D01*
X650268Y423880D01*
X650060Y424213D01*
X649810Y424380D01*
X649518Y424463D01*
X649185Y424380D01*
X648935Y424213D01*
X648768Y423963D01*
X648685Y423630D01*
X648768Y423338D01*
X648976Y423046D01*
X649226Y422880D01*
X649518Y422838D01*
X649851Y422921D01*
X650101Y423130D01*
X650351Y423505D01*
G01X651701Y422463D02*
X651951Y422171D01*
X652285Y422005D01*
X652660Y421963D01*
X652993Y422005D01*
X653326Y422213D01*
X653535Y422463D01*
X653576Y422713D01*
X653493Y423005D01*
X653201Y423213D01*
X652910Y423296D01*
X652535D01*
G01X652910D02*
X653160Y423421D01*
X653368Y423630D01*
X653451Y423880D01*
X653368Y424130D01*
X653160Y424338D01*
X652785Y424463D01*
X652410Y424421D01*
X652035Y424255D01*
G01X662981Y402183D02*
Y398183D01*
X670381D01*
G01X648138Y411143D02*
Y413643D01*
X649179D01*
X649513Y413518D01*
X649721Y413351D01*
X649804Y413018D01*
X649721Y412685D01*
X649471Y412476D01*
X649179Y412351D01*
X648138D01*
G01X649179D02*
X649804Y411143D01*
G01X652571D02*
Y413643D01*
X651029Y411851D01*
X653113D01*
G01X654463Y411435D02*
X654754Y411226D01*
X655088Y411143D01*
X655421Y411226D01*
X655713Y411476D01*
X655921Y411851D01*
X656004Y412226D01*
Y412685D01*
X655921Y413060D01*
X655713Y413393D01*
X655463Y413560D01*
X655171Y413643D01*
X654838Y413560D01*
X654588Y413393D01*
X654421Y413143D01*
X654338Y412810D01*
X654421Y412518D01*
X654629Y412226D01*
X654879Y412060D01*
X655171Y412018D01*
X655504Y412101D01*
X655754Y412310D01*
X656004Y412685D01*
G01X658771Y411143D02*
Y413643D01*
X657229Y411851D01*
X659313D01*
G01X673631Y390433D02*
Y394433D01*
X666231D01*
G01X693100Y376300D02*
X697100D01*
Y383700D01*
G01X664517Y402667D02*
Y405167D01*
X665558D01*
X665892Y405042D01*
X666100Y404875D01*
X666183Y404542D01*
X666100Y404209D01*
X665850Y404000D01*
X665558Y403875D01*
X664517D01*
G01X665558D02*
X666183Y402667D01*
G01X668950D02*
Y405167D01*
X667408Y403375D01*
X669492D01*
G01X670842Y402959D02*
X671133Y402750D01*
X671467Y402667D01*
X671800Y402750D01*
X672092Y403000D01*
X672300Y403375D01*
X672383Y403750D01*
Y404209D01*
X672300Y404584D01*
X672092Y404917D01*
X671842Y405084D01*
X671550Y405167D01*
X671217Y405084D01*
X670967Y404917D01*
X670800Y404667D01*
X670717Y404334D01*
X670800Y404042D01*
X671008Y403750D01*
X671258Y403584D01*
X671550Y403542D01*
X671883Y403625D01*
X672133Y403834D01*
X672383Y404209D01*
G01X673858Y404750D02*
X674108Y405000D01*
X674400Y405125D01*
X674733Y405167D01*
X675150Y405084D01*
X675442Y404875D01*
X675525Y404625D01*
X675483Y404375D01*
X675317Y404167D01*
X674483Y403750D01*
X674108Y403459D01*
X673858Y403042D01*
X673775Y402667D01*
X675525D01*
G01X689581Y397833D02*
X685581D01*
Y390433D01*
G01X672517Y410167D02*
Y412667D01*
X673558D01*
X673892Y412542D01*
X674100Y412375D01*
X674183Y412042D01*
X674100Y411709D01*
X673850Y411500D01*
X673558Y411375D01*
X672517D01*
G01X673558D02*
X674183Y410167D01*
G01X675658Y411209D02*
X675950Y411500D01*
X676200Y411667D01*
X676533Y411750D01*
X676825Y411667D01*
X677033Y411500D01*
X677200Y411250D01*
X677242Y410959D01*
X677200Y410709D01*
X677033Y410459D01*
X676783Y410250D01*
X676492Y410167D01*
X676158Y410250D01*
X675867Y410500D01*
X675700Y410875D01*
X675658Y411292D01*
X675742Y411834D01*
X675867Y412125D01*
X676075Y412417D01*
X676367Y412625D01*
X676658Y412667D01*
X676950Y412584D01*
X677158Y412375D01*
G01X679550Y412667D02*
X679217Y412584D01*
X678967Y412375D01*
X678800Y412125D01*
X678675Y411792D01*
X678633Y411417D01*
X678675Y411042D01*
X678800Y410709D01*
X678967Y410459D01*
X679217Y410250D01*
X679550Y410167D01*
X679883Y410250D01*
X680133Y410459D01*
X680300Y410709D01*
X680425Y411042D01*
X680467Y411417D01*
X680425Y411792D01*
X680300Y412125D01*
X680133Y412375D01*
X679883Y412584D01*
X679550Y412667D01*
G01X681733Y410542D02*
X681983Y410334D01*
X682275Y410209D01*
X682650Y410167D01*
X683025Y410250D01*
X683317Y410417D01*
X683525Y410709D01*
X683567Y411042D01*
X683483Y411375D01*
X683275Y411584D01*
X682983Y411750D01*
X682692Y411792D01*
X682400Y411750D01*
X682025Y411584D01*
X682150Y412667D01*
X683275D01*
G01X678200Y405500D02*
Y409500D01*
X670800D01*
G01X663000Y409417D02*
X660500D01*
Y410458D01*
X660625Y410792D01*
X660792Y411000D01*
X661125Y411083D01*
X661458Y411000D01*
X661667Y410750D01*
X661792Y410458D01*
Y409417D01*
G01Y410458D02*
X663000Y411083D01*
G01Y413850D02*
X660500D01*
X662292Y412308D01*
Y414392D01*
G01X662708Y415742D02*
X662917Y416033D01*
X663000Y416367D01*
X662917Y416700D01*
X662667Y416992D01*
X662292Y417200D01*
X661917Y417283D01*
X661458D01*
X661083Y417200D01*
X660750Y416992D01*
X660583Y416742D01*
X660500Y416450D01*
X660583Y416117D01*
X660750Y415867D01*
X661000Y415700D01*
X661333Y415617D01*
X661625Y415700D01*
X661917Y415908D01*
X662083Y416158D01*
X662125Y416450D01*
X662042Y416783D01*
X661833Y417033D01*
X661458Y417283D01*
G01X662625Y418633D02*
X662833Y418883D01*
X662958Y419175D01*
X663000Y419550D01*
X662917Y419925D01*
X662750Y420217D01*
X662458Y420425D01*
X662125Y420467D01*
X661792Y420383D01*
X661583Y420175D01*
X661417Y419883D01*
X661375Y419592D01*
X661417Y419300D01*
X661583Y418925D01*
X660500Y419050D01*
Y420175D01*
G01X673831Y390633D02*
X677831D01*
Y398033D01*
G01X638017Y402500D02*
Y405000D01*
X639058D01*
X639392Y404875D01*
X639600Y404708D01*
X639683Y404375D01*
X639600Y404042D01*
X639350Y403833D01*
X639058Y403708D01*
X638017D01*
G01X639058D02*
X639683Y402500D01*
G01X642450D02*
Y405000D01*
X640908Y403208D01*
X642992D01*
G01X645050Y402500D02*
X645342Y402542D01*
X645675Y402667D01*
X645883Y402875D01*
X645967Y403167D01*
X645883Y403458D01*
X645633Y403708D01*
X645258Y403833D01*
X644842D01*
X644592Y403917D01*
X644383Y404125D01*
X644300Y404417D01*
X644425Y404708D01*
X644717Y404917D01*
X645050Y405000D01*
X645383Y404917D01*
X645675Y404708D01*
X645800Y404417D01*
X645717Y404125D01*
X645508Y403917D01*
X645258Y403833D01*
X644842D01*
X644467Y403708D01*
X644217Y403458D01*
X644133Y403167D01*
X644217Y402875D01*
X644425Y402667D01*
X644758Y402542D01*
X645050Y402500D01*
G01X647358Y403542D02*
X647650Y403833D01*
X647900Y404000D01*
X648233Y404083D01*
X648525Y404000D01*
X648733Y403833D01*
X648900Y403583D01*
X648942Y403292D01*
X648900Y403042D01*
X648733Y402792D01*
X648483Y402583D01*
X648192Y402500D01*
X647858Y402583D01*
X647567Y402833D01*
X647400Y403208D01*
X647358Y403625D01*
X647442Y404167D01*
X647567Y404458D01*
X647775Y404750D01*
X648067Y404958D01*
X648358Y405000D01*
X648650Y404917D01*
X648858Y404708D01*
G01X651420Y393300D02*
Y397300D01*
X644020D01*
G01X667834Y409517D02*
X665334D01*
Y410558D01*
X665459Y410892D01*
X665626Y411100D01*
X665959Y411183D01*
X666292Y411100D01*
X666501Y410850D01*
X666626Y410558D01*
Y409517D01*
G01Y410558D02*
X667834Y411183D01*
G01X667334Y412533D02*
X667626Y412783D01*
X667792Y413117D01*
X667834Y413492D01*
X667792Y413825D01*
X667584Y414158D01*
X667334Y414367D01*
X667084Y414408D01*
X666792Y414325D01*
X666584Y414033D01*
X666501Y413742D01*
Y413367D01*
G01Y413742D02*
X666376Y413992D01*
X666167Y414200D01*
X665917Y414283D01*
X665667Y414200D01*
X665459Y413992D01*
X665334Y413617D01*
X665376Y413242D01*
X665542Y412867D01*
G01X667834Y416467D02*
X667292Y416550D01*
X666834Y416675D01*
X666417Y416842D01*
X665959Y417050D01*
X665334Y417383D01*
Y415717D01*
G01X666792Y418858D02*
X666501Y419150D01*
X666334Y419400D01*
X666251Y419733D01*
X666334Y420025D01*
X666501Y420233D01*
X666751Y420400D01*
X667042Y420442D01*
X667292Y420400D01*
X667542Y420233D01*
X667751Y419983D01*
X667834Y419692D01*
X667751Y419358D01*
X667501Y419067D01*
X667126Y418900D01*
X666709Y418858D01*
X666167Y418942D01*
X665876Y419067D01*
X665584Y419275D01*
X665376Y419567D01*
X665334Y419858D01*
X665417Y420150D01*
X665626Y420358D01*
G01X668610Y413430D02*
X672610D01*
Y420830D01*
G01X692017Y399000D02*
Y401500D01*
X693058D01*
X693392Y401375D01*
X693600Y401208D01*
X693683Y400875D01*
X693600Y400542D01*
X693350Y400333D01*
X693058Y400208D01*
X692017D01*
G01X693058D02*
X693683Y399000D01*
G01X696450D02*
Y401500D01*
X694908Y399708D01*
X696992D01*
G01X698342Y399292D02*
X698633Y399083D01*
X698967Y399000D01*
X699300Y399083D01*
X699592Y399333D01*
X699800Y399708D01*
X699883Y400083D01*
Y400542D01*
X699800Y400917D01*
X699592Y401250D01*
X699342Y401417D01*
X699050Y401500D01*
X698717Y401417D01*
X698467Y401250D01*
X698300Y401000D01*
X698217Y400667D01*
X698300Y400375D01*
X698508Y400083D01*
X698758Y399917D01*
X699050Y399875D01*
X699383Y399958D01*
X699633Y400167D01*
X699883Y400542D01*
G01X702150Y399000D02*
Y401500D01*
X701650Y401000D01*
G01Y399000D02*
X702650D01*
G01X679208Y389267D02*
X679083Y389017D01*
X679000Y388725D01*
Y388392D01*
X679125Y388017D01*
X679333Y387725D01*
X679583Y387517D01*
X680000Y387350D01*
X680375Y387308D01*
X680750Y387392D01*
X681000Y387517D01*
X681250Y387767D01*
X681417Y388058D01*
X681500Y388350D01*
Y388642D01*
X681417Y388933D01*
X681292Y389183D01*
X681125Y389392D01*
G01X680458Y390658D02*
X680167Y390950D01*
X680000Y391200D01*
X679917Y391533D01*
X680000Y391825D01*
X680167Y392033D01*
X680417Y392200D01*
X680708Y392242D01*
X680958Y392200D01*
X681208Y392033D01*
X681417Y391783D01*
X681500Y391492D01*
X681417Y391158D01*
X681167Y390867D01*
X680792Y390700D01*
X680375Y390658D01*
X679833Y390742D01*
X679542Y390867D01*
X679250Y391075D01*
X679042Y391367D01*
X679000Y391658D01*
X679083Y391950D01*
X679292Y392158D01*
G01X679417Y393758D02*
X679167Y394008D01*
X679042Y394300D01*
X679000Y394633D01*
X679083Y395050D01*
X679292Y395342D01*
X679542Y395425D01*
X679792Y395383D01*
X680000Y395217D01*
X680417Y394383D01*
X680708Y394008D01*
X681125Y393758D01*
X681500Y393675D01*
Y395425D01*
G01Y398150D02*
X679000D01*
X680792Y396608D01*
Y398692D01*
G01X678767Y404459D02*
X678517Y404584D01*
X678225Y404667D01*
X677892D01*
X677517Y404542D01*
X677225Y404334D01*
X677017Y404084D01*
X676850Y403667D01*
X676808Y403292D01*
X676892Y402917D01*
X677017Y402667D01*
X677267Y402417D01*
X677558Y402250D01*
X677850Y402167D01*
X678142D01*
X678433Y402250D01*
X678683Y402375D01*
X678892Y402542D01*
G01X680158Y403209D02*
X680450Y403500D01*
X680700Y403667D01*
X681033Y403750D01*
X681325Y403667D01*
X681533Y403500D01*
X681700Y403250D01*
X681742Y402959D01*
X681700Y402709D01*
X681533Y402459D01*
X681283Y402250D01*
X680992Y402167D01*
X680658Y402250D01*
X680367Y402500D01*
X680200Y402875D01*
X680158Y403292D01*
X680242Y403834D01*
X680367Y404125D01*
X680575Y404417D01*
X680867Y404625D01*
X681158Y404667D01*
X681450Y404584D01*
X681658Y404375D01*
G01X683258Y403209D02*
X683550Y403500D01*
X683800Y403667D01*
X684133Y403750D01*
X684425Y403667D01*
X684633Y403500D01*
X684800Y403250D01*
X684842Y402959D01*
X684800Y402709D01*
X684633Y402459D01*
X684383Y402250D01*
X684092Y402167D01*
X683758Y402250D01*
X683467Y402500D01*
X683300Y402875D01*
X683258Y403292D01*
X683342Y403834D01*
X683467Y404125D01*
X683675Y404417D01*
X683967Y404625D01*
X684258Y404667D01*
X684550Y404584D01*
X684758Y404375D01*
G01X686358Y404250D02*
X686608Y404500D01*
X686900Y404625D01*
X687233Y404667D01*
X687650Y404584D01*
X687942Y404375D01*
X688025Y404125D01*
X687983Y403875D01*
X687817Y403667D01*
X686983Y403250D01*
X686608Y402959D01*
X686358Y402542D01*
X686275Y402167D01*
X688025D01*
G01X649924Y417183D02*
X649674Y417308D01*
X649382Y417391D01*
X649049D01*
X648674Y417266D01*
X648382Y417058D01*
X648174Y416808D01*
X648007Y416391D01*
X647965Y416016D01*
X648049Y415641D01*
X648174Y415391D01*
X648424Y415141D01*
X648715Y414974D01*
X649007Y414891D01*
X649299D01*
X649590Y414974D01*
X649840Y415099D01*
X650049Y415266D01*
G01X651315Y415933D02*
X651607Y416224D01*
X651857Y416391D01*
X652190Y416474D01*
X652482Y416391D01*
X652690Y416224D01*
X652857Y415974D01*
X652899Y415683D01*
X652857Y415433D01*
X652690Y415183D01*
X652440Y414974D01*
X652149Y414891D01*
X651815Y414974D01*
X651524Y415224D01*
X651357Y415599D01*
X651315Y416016D01*
X651399Y416558D01*
X651524Y416849D01*
X651732Y417141D01*
X652024Y417349D01*
X652315Y417391D01*
X652607Y417308D01*
X652815Y417099D01*
G01X654415Y416974D02*
X654665Y417224D01*
X654957Y417349D01*
X655290Y417391D01*
X655707Y417308D01*
X655999Y417099D01*
X656082Y416849D01*
X656040Y416599D01*
X655874Y416391D01*
X655040Y415974D01*
X654665Y415683D01*
X654415Y415266D01*
X654332Y414891D01*
X656082D01*
G01X657390Y415266D02*
X657640Y415058D01*
X657932Y414933D01*
X658307Y414891D01*
X658682Y414974D01*
X658974Y415141D01*
X659182Y415433D01*
X659224Y415766D01*
X659140Y416099D01*
X658932Y416308D01*
X658640Y416474D01*
X658349Y416516D01*
X658057Y416474D01*
X657682Y416308D01*
X657807Y417391D01*
X658932D01*
G01X684390Y422270D02*
Y408270D01*
G01X697390Y422270D02*
X684390D01*
G01Y408270D02*
X697390D01*
G01X691267Y404959D02*
X691017Y405084D01*
X690725Y405167D01*
X690392D01*
X690017Y405042D01*
X689725Y404834D01*
X689517Y404584D01*
X689350Y404167D01*
X689308Y403792D01*
X689392Y403417D01*
X689517Y403167D01*
X689767Y402917D01*
X690058Y402750D01*
X690350Y402667D01*
X690642D01*
X690933Y402750D01*
X691183Y402875D01*
X691392Y403042D01*
G01X692658Y403709D02*
X692950Y404000D01*
X693200Y404167D01*
X693533Y404250D01*
X693825Y404167D01*
X694033Y404000D01*
X694200Y403750D01*
X694242Y403459D01*
X694200Y403209D01*
X694033Y402959D01*
X693783Y402750D01*
X693492Y402667D01*
X693158Y402750D01*
X692867Y403000D01*
X692700Y403375D01*
X692658Y403792D01*
X692742Y404334D01*
X692867Y404625D01*
X693075Y404917D01*
X693367Y405125D01*
X693658Y405167D01*
X693950Y405084D01*
X694158Y404875D01*
G01X695758Y403709D02*
X696050Y404000D01*
X696300Y404167D01*
X696633Y404250D01*
X696925Y404167D01*
X697133Y404000D01*
X697300Y403750D01*
X697342Y403459D01*
X697300Y403209D01*
X697133Y402959D01*
X696883Y402750D01*
X696592Y402667D01*
X696258Y402750D01*
X695967Y403000D01*
X695800Y403375D01*
X695758Y403792D01*
X695842Y404334D01*
X695967Y404625D01*
X696175Y404917D01*
X696467Y405125D01*
X696758Y405167D01*
X697050Y405084D01*
X697258Y404875D01*
G01X698733Y403167D02*
X698983Y402875D01*
X699317Y402709D01*
X699692Y402667D01*
X700025Y402709D01*
X700358Y402917D01*
X700567Y403167D01*
X700608Y403417D01*
X700525Y403709D01*
X700233Y403917D01*
X699942Y404000D01*
X699567D01*
G01X699942D02*
X700192Y404125D01*
X700400Y404334D01*
X700483Y404584D01*
X700400Y404834D01*
X700192Y405042D01*
X699817Y405167D01*
X699442Y405125D01*
X699067Y404959D01*
G01X639767Y400582D02*
X639517Y400707D01*
X639225Y400790D01*
X638892D01*
X638517Y400665D01*
X638225Y400457D01*
X638017Y400207D01*
X637850Y399790D01*
X637808Y399415D01*
X637892Y399040D01*
X638017Y398790D01*
X638267Y398540D01*
X638558Y398373D01*
X638850Y398290D01*
X639142D01*
X639433Y398373D01*
X639683Y398498D01*
X639892Y398665D01*
G01X641158Y399332D02*
X641450Y399623D01*
X641700Y399790D01*
X642033Y399873D01*
X642325Y399790D01*
X642533Y399623D01*
X642700Y399373D01*
X642742Y399082D01*
X642700Y398832D01*
X642533Y398582D01*
X642283Y398373D01*
X641992Y398290D01*
X641658Y398373D01*
X641367Y398623D01*
X641200Y398998D01*
X641158Y399415D01*
X641242Y399957D01*
X641367Y400248D01*
X641575Y400540D01*
X641867Y400748D01*
X642158Y400790D01*
X642450Y400707D01*
X642658Y400498D01*
G01X644258Y400373D02*
X644508Y400623D01*
X644800Y400748D01*
X645133Y400790D01*
X645550Y400707D01*
X645842Y400498D01*
X645925Y400248D01*
X645883Y399998D01*
X645717Y399790D01*
X644883Y399373D01*
X644508Y399082D01*
X644258Y398665D01*
X644175Y398290D01*
X645925D01*
G01X648150D02*
Y400790D01*
X647650Y400290D01*
G01Y398290D02*
X648650D01*
G01X692767Y373559D02*
X692517Y373684D01*
X692225Y373767D01*
X691892D01*
X691517Y373642D01*
X691225Y373434D01*
X691017Y373184D01*
X690850Y372767D01*
X690808Y372392D01*
X690892Y372017D01*
X691017Y371767D01*
X691267Y371517D01*
X691558Y371350D01*
X691850Y371267D01*
X692142D01*
X692433Y371350D01*
X692683Y371475D01*
X692892Y371642D01*
G01X694158Y372309D02*
X694450Y372600D01*
X694700Y372767D01*
X695033Y372850D01*
X695325Y372767D01*
X695533Y372600D01*
X695700Y372350D01*
X695742Y372059D01*
X695700Y371809D01*
X695533Y371559D01*
X695283Y371350D01*
X694992Y371267D01*
X694658Y371350D01*
X694367Y371600D01*
X694200Y371975D01*
X694158Y372392D01*
X694242Y372934D01*
X694367Y373225D01*
X694575Y373517D01*
X694867Y373725D01*
X695158Y373767D01*
X695450Y373684D01*
X695658Y373475D01*
G01X697258Y373350D02*
X697508Y373600D01*
X697800Y373725D01*
X698133Y373767D01*
X698550Y373684D01*
X698842Y373475D01*
X698925Y373225D01*
X698883Y372975D01*
X698717Y372767D01*
X697883Y372350D01*
X697508Y372059D01*
X697258Y371642D01*
X697175Y371267D01*
X698925D01*
G01X700358Y373350D02*
X700608Y373600D01*
X700900Y373725D01*
X701233Y373767D01*
X701650Y373684D01*
X701942Y373475D01*
X702025Y373225D01*
X701983Y372975D01*
X701817Y372767D01*
X700983Y372350D01*
X700608Y372059D01*
X700358Y371642D01*
X700275Y371267D01*
X702025D01*
G01X637208Y373767D02*
X637083Y373517D01*
X637000Y373225D01*
Y372892D01*
X637125Y372517D01*
X637333Y372225D01*
X637583Y372017D01*
X638000Y371850D01*
X638375Y371808D01*
X638750Y371892D01*
X639000Y372017D01*
X639250Y372267D01*
X639417Y372558D01*
X639500Y372850D01*
Y373142D01*
X639417Y373433D01*
X639292Y373683D01*
X639125Y373892D01*
G01X638458Y375158D02*
X638167Y375450D01*
X638000Y375700D01*
X637917Y376033D01*
X638000Y376325D01*
X638167Y376533D01*
X638417Y376700D01*
X638708Y376742D01*
X638958Y376700D01*
X639208Y376533D01*
X639417Y376283D01*
X639500Y375992D01*
X639417Y375658D01*
X639167Y375367D01*
X638792Y375200D01*
X638375Y375158D01*
X637833Y375242D01*
X637542Y375367D01*
X637250Y375575D01*
X637042Y375867D01*
X637000Y376158D01*
X637083Y376450D01*
X637292Y376658D01*
G01X637417Y378258D02*
X637167Y378508D01*
X637042Y378800D01*
X637000Y379133D01*
X637083Y379550D01*
X637292Y379842D01*
X637542Y379925D01*
X637792Y379883D01*
X638000Y379717D01*
X638417Y378883D01*
X638708Y378508D01*
X639125Y378258D01*
X639500Y378175D01*
Y379925D01*
G01X637000Y382150D02*
X637083Y381817D01*
X637292Y381567D01*
X637542Y381400D01*
X637875Y381275D01*
X638250Y381233D01*
X638625Y381275D01*
X638958Y381400D01*
X639208Y381567D01*
X639417Y381817D01*
X639500Y382150D01*
X639417Y382483D01*
X639208Y382733D01*
X638958Y382900D01*
X638625Y383025D01*
X638250Y383067D01*
X637875Y383025D01*
X637542Y382900D01*
X637292Y382733D01*
X637083Y382483D01*
X637000Y382150D01*
G01X692777Y369439D02*
X692527Y369564D01*
X692235Y369647D01*
X691902D01*
X691527Y369522D01*
X691235Y369314D01*
X691027Y369064D01*
X690860Y368647D01*
X690818Y368272D01*
X690902Y367897D01*
X691027Y367647D01*
X691277Y367397D01*
X691568Y367230D01*
X691860Y367147D01*
X692152D01*
X692443Y367230D01*
X692693Y367355D01*
X692902Y367522D01*
G01X694168Y368189D02*
X694460Y368480D01*
X694710Y368647D01*
X695043Y368730D01*
X695335Y368647D01*
X695543Y368480D01*
X695710Y368230D01*
X695752Y367939D01*
X695710Y367689D01*
X695543Y367439D01*
X695293Y367230D01*
X695002Y367147D01*
X694668Y367230D01*
X694377Y367480D01*
X694210Y367855D01*
X694168Y368272D01*
X694252Y368814D01*
X694377Y369105D01*
X694585Y369397D01*
X694877Y369605D01*
X695168Y369647D01*
X695460Y369564D01*
X695668Y369355D01*
G01X697268Y369230D02*
X697518Y369480D01*
X697810Y369605D01*
X698143Y369647D01*
X698560Y369564D01*
X698852Y369355D01*
X698935Y369105D01*
X698893Y368855D01*
X698727Y368647D01*
X697893Y368230D01*
X697518Y367939D01*
X697268Y367522D01*
X697185Y367147D01*
X698935D01*
G01X700243Y367647D02*
X700493Y367355D01*
X700827Y367189D01*
X701202Y367147D01*
X701535Y367189D01*
X701868Y367397D01*
X702077Y367647D01*
X702118Y367897D01*
X702035Y368189D01*
X701743Y368397D01*
X701452Y368480D01*
X701077D01*
G01X701452D02*
X701702Y368605D01*
X701910Y368814D01*
X701993Y369064D01*
X701910Y369314D01*
X701702Y369522D01*
X701327Y369647D01*
X700952Y369605D01*
X700577Y369439D01*
G01X670033Y389500D02*
Y387708D01*
X670200Y387333D01*
X670533Y387083D01*
X670950Y387000D01*
X671367Y387083D01*
X671700Y387333D01*
X671867Y387708D01*
Y389500D01*
G01X673258Y388042D02*
X673550Y388333D01*
X673800Y388500D01*
X674133Y388583D01*
X674425Y388500D01*
X674633Y388333D01*
X674800Y388083D01*
X674842Y387792D01*
X674800Y387542D01*
X674633Y387292D01*
X674383Y387083D01*
X674092Y387000D01*
X673758Y387083D01*
X673467Y387333D01*
X673300Y387708D01*
X673258Y388125D01*
X673342Y388667D01*
X673467Y388958D01*
X673675Y389250D01*
X673967Y389458D01*
X674258Y389500D01*
X674550Y389417D01*
X674758Y389208D01*
G01X680053Y381307D02*
Y386307D01*
X675053D01*
G01Y363307D02*
X680053D01*
Y368307D01*
G01X655853D02*
Y363307D01*
X660853D01*
G01X668893Y385265D02*
Y387265D01*
G01X678961Y377173D02*
X681961D01*
G01X656845Y369223D02*
X654845D01*
G01X671117Y362667D02*
X664117D01*
G01X691738Y365574D02*
Y363074D01*
X693404D01*
G01X694754Y363574D02*
X695004Y363282D01*
X695338Y363116D01*
X695713Y363074D01*
X696046Y363116D01*
X696379Y363324D01*
X696588Y363574D01*
X696629Y363824D01*
X696546Y364116D01*
X696254Y364324D01*
X695963Y364407D01*
X695588D01*
G01X695963D02*
X696213Y364532D01*
X696421Y364741D01*
X696504Y364991D01*
X696421Y365241D01*
X696213Y365449D01*
X695838Y365574D01*
X695463Y365532D01*
X695088Y365366D01*
G01X697854Y363574D02*
X698104Y363282D01*
X698438Y363116D01*
X698813Y363074D01*
X699146Y363116D01*
X699479Y363324D01*
X699688Y363574D01*
X699729Y363824D01*
X699646Y364116D01*
X699354Y364324D01*
X699063Y364407D01*
X698688D01*
G01X699063D02*
X699313Y364532D01*
X699521Y364741D01*
X699604Y364991D01*
X699521Y365241D01*
X699313Y365449D01*
X698938Y365574D01*
X698563Y365532D01*
X698188Y365366D01*
G01X649833Y431033D02*
X651625D01*
X652000Y431200D01*
X652250Y431533D01*
X652333Y431950D01*
X652250Y432367D01*
X652000Y432700D01*
X651625Y432867D01*
X649833D01*
G01X652041Y434342D02*
X652250Y434633D01*
X652333Y434967D01*
X652250Y435300D01*
X652000Y435592D01*
X651625Y435800D01*
X651250Y435883D01*
X650791D01*
X650416Y435800D01*
X650083Y435592D01*
X649916Y435342D01*
X649833Y435050D01*
X649916Y434717D01*
X650083Y434467D01*
X650333Y434300D01*
X650666Y434217D01*
X650958Y434300D01*
X651250Y434508D01*
X651416Y434758D01*
X651458Y435050D01*
X651375Y435383D01*
X651166Y435633D01*
X650791Y435883D01*
G01X668054Y435406D02*
X678054D01*
G01X662334Y425517D02*
X659834D01*
Y426558D01*
X659959Y426892D01*
X660126Y427100D01*
X660459Y427183D01*
X660792Y427100D01*
X661001Y426850D01*
X661126Y426558D01*
Y425517D01*
G01Y426558D02*
X662334Y427183D01*
G01Y429950D02*
X659834D01*
X661626Y428408D01*
Y430492D01*
G01X662334Y433050D02*
X659834D01*
X661626Y431508D01*
Y433592D01*
G01X661834Y434733D02*
X662126Y434983D01*
X662292Y435317D01*
X662334Y435692D01*
X662292Y436025D01*
X662084Y436358D01*
X661834Y436567D01*
X661584Y436608D01*
X661292Y436525D01*
X661084Y436233D01*
X661001Y435942D01*
Y435567D01*
G01Y435942D02*
X660876Y436192D01*
X660667Y436400D01*
X660417Y436483D01*
X660167Y436400D01*
X659959Y436192D01*
X659834Y435817D01*
X659876Y435442D01*
X660042Y435067D01*
G01X673834Y461017D02*
X671334D01*
Y462058D01*
X671459Y462392D01*
X671626Y462600D01*
X671959Y462683D01*
X672292Y462600D01*
X672501Y462350D01*
X672626Y462058D01*
Y461017D01*
G01Y462058D02*
X673834Y462683D01*
G01X672792Y464158D02*
X672501Y464450D01*
X672334Y464700D01*
X672251Y465033D01*
X672334Y465325D01*
X672501Y465533D01*
X672751Y465700D01*
X673042Y465742D01*
X673292Y465700D01*
X673542Y465533D01*
X673751Y465283D01*
X673834Y464992D01*
X673751Y464658D01*
X673501Y464367D01*
X673126Y464200D01*
X672709Y464158D01*
X672167Y464242D01*
X671876Y464367D01*
X671584Y464575D01*
X671376Y464867D01*
X671334Y465158D01*
X671417Y465450D01*
X671626Y465658D01*
G01X671334Y468050D02*
X671417Y467717D01*
X671626Y467467D01*
X671876Y467300D01*
X672209Y467175D01*
X672584Y467133D01*
X672959Y467175D01*
X673292Y467300D01*
X673542Y467467D01*
X673751Y467717D01*
X673834Y468050D01*
X673751Y468383D01*
X673542Y468633D01*
X673292Y468800D01*
X672959Y468925D01*
X672584Y468967D01*
X672209Y468925D01*
X671876Y468800D01*
X671626Y468633D01*
X671417Y468383D01*
X671334Y468050D01*
G01X673834Y471067D02*
X673292Y471150D01*
X672834Y471275D01*
X672417Y471442D01*
X671959Y471650D01*
X671334Y471983D01*
Y470317D01*
G01X673380Y452460D02*
X677380D01*
Y459860D01*
G01X666334Y427017D02*
X663834D01*
Y428058D01*
X663959Y428392D01*
X664126Y428600D01*
X664459Y428683D01*
X664792Y428600D01*
X665001Y428350D01*
X665126Y428058D01*
Y427017D01*
G01Y428058D02*
X666334Y428683D01*
G01Y431450D02*
X663834D01*
X665626Y429908D01*
Y431992D01*
G01X666334Y434550D02*
X663834D01*
X665626Y433008D01*
Y435092D01*
G01X666334Y437650D02*
X663834D01*
X665626Y436108D01*
Y438192D01*
G01X649870Y461347D02*
X647370D01*
Y462388D01*
X647495Y462722D01*
X647662Y462930D01*
X647995Y463013D01*
X648328Y462930D01*
X648537Y462680D01*
X648662Y462388D01*
Y461347D01*
G01Y462388D02*
X649870Y463013D01*
G01X649370Y464363D02*
X649662Y464613D01*
X649828Y464947D01*
X649870Y465322D01*
X649828Y465655D01*
X649620Y465988D01*
X649370Y466197D01*
X649120Y466238D01*
X648828Y466155D01*
X648620Y465863D01*
X648537Y465572D01*
Y465197D01*
G01Y465572D02*
X648412Y465822D01*
X648203Y466030D01*
X647953Y466113D01*
X647703Y466030D01*
X647495Y465822D01*
X647370Y465447D01*
X647412Y465072D01*
X647578Y464697D01*
G01X649870Y468380D02*
X647370D01*
X647870Y467880D01*
G01X649870D02*
Y468880D01*
G01X648828Y470688D02*
X648537Y470980D01*
X648370Y471230D01*
X648287Y471563D01*
X648370Y471855D01*
X648537Y472063D01*
X648787Y472230D01*
X649078Y472272D01*
X649328Y472230D01*
X649578Y472063D01*
X649787Y471813D01*
X649870Y471522D01*
X649787Y471188D01*
X649537Y470897D01*
X649162Y470730D01*
X648745Y470688D01*
X648203Y470772D01*
X647912Y470897D01*
X647620Y471105D01*
X647412Y471397D01*
X647370Y471688D01*
X647453Y471980D01*
X647662Y472188D01*
G01X644567Y443167D02*
Y445667D01*
X645608D01*
X645942Y445542D01*
X646150Y445375D01*
X646233Y445042D01*
X646150Y444709D01*
X645900Y444500D01*
X645608Y444375D01*
X644567D01*
G01X645608D02*
X646233Y443167D01*
G01X647792Y443459D02*
X648083Y443250D01*
X648417Y443167D01*
X648750Y443250D01*
X649042Y443500D01*
X649250Y443875D01*
X649333Y444250D01*
Y444709D01*
X649250Y445084D01*
X649042Y445417D01*
X648792Y445584D01*
X648500Y445667D01*
X648167Y445584D01*
X647917Y445417D01*
X647750Y445167D01*
X647667Y444834D01*
X647750Y444542D01*
X647958Y444250D01*
X648208Y444084D01*
X648500Y444042D01*
X648833Y444125D01*
X649083Y444334D01*
X649333Y444709D01*
G01X650683Y443667D02*
X650933Y443375D01*
X651267Y443209D01*
X651642Y443167D01*
X651975Y443209D01*
X652308Y443417D01*
X652517Y443667D01*
X652558Y443917D01*
X652475Y444209D01*
X652183Y444417D01*
X651892Y444500D01*
X651517D01*
G01X651892D02*
X652142Y444625D01*
X652350Y444834D01*
X652433Y445084D01*
X652350Y445334D01*
X652142Y445542D01*
X651767Y445667D01*
X651392Y445625D01*
X651017Y445459D01*
G01X680400Y442950D02*
Y438950D01*
X687800D01*
G01X666000Y449567D02*
X663500D01*
Y450608D01*
X663625Y450942D01*
X663792Y451150D01*
X664125Y451233D01*
X664458Y451150D01*
X664667Y450900D01*
X664792Y450608D01*
Y449567D01*
G01Y450608D02*
X666000Y451233D01*
G01X665708Y452792D02*
X665917Y453083D01*
X666000Y453417D01*
X665917Y453750D01*
X665667Y454042D01*
X665292Y454250D01*
X664917Y454333D01*
X664458D01*
X664083Y454250D01*
X663750Y454042D01*
X663583Y453792D01*
X663500Y453500D01*
X663583Y453167D01*
X663750Y452917D01*
X664000Y452750D01*
X664333Y452667D01*
X664625Y452750D01*
X664917Y452958D01*
X665083Y453208D01*
X665125Y453500D01*
X665042Y453833D01*
X664833Y454083D01*
X664458Y454333D01*
G01X665625Y455683D02*
X665833Y455933D01*
X665958Y456225D01*
X666000Y456600D01*
X665917Y456975D01*
X665750Y457267D01*
X665458Y457475D01*
X665125Y457517D01*
X664792Y457433D01*
X664583Y457225D01*
X664417Y456933D01*
X664375Y456642D01*
X664417Y456350D01*
X664583Y455975D01*
X663500Y456100D01*
Y457225D01*
G01X665900Y441200D02*
X669900D01*
Y448600D01*
G01X654567Y439167D02*
Y441667D01*
X655608D01*
X655942Y441542D01*
X656150Y441375D01*
X656233Y441042D01*
X656150Y440709D01*
X655900Y440500D01*
X655608Y440375D01*
X654567D01*
G01X655608D02*
X656233Y439167D01*
G01X657792Y439459D02*
X658083Y439250D01*
X658417Y439167D01*
X658750Y439250D01*
X659042Y439500D01*
X659250Y439875D01*
X659333Y440250D01*
Y440709D01*
X659250Y441084D01*
X659042Y441417D01*
X658792Y441584D01*
X658500Y441667D01*
X658167Y441584D01*
X657917Y441417D01*
X657750Y441167D01*
X657667Y440834D01*
X657750Y440542D01*
X657958Y440250D01*
X658208Y440084D01*
X658500Y440042D01*
X658833Y440125D01*
X659083Y440334D01*
X659333Y440709D01*
G01X660808Y441250D02*
X661058Y441500D01*
X661350Y441625D01*
X661683Y441667D01*
X662100Y441584D01*
X662392Y441375D01*
X662475Y441125D01*
X662433Y440875D01*
X662267Y440667D01*
X661433Y440250D01*
X661058Y439959D01*
X660808Y439542D01*
X660725Y439167D01*
X662475D01*
G01X681300Y435300D02*
Y431300D01*
X688700D01*
G01X655767Y445459D02*
X655517Y445584D01*
X655225Y445667D01*
X654892D01*
X654517Y445542D01*
X654225Y445334D01*
X654017Y445084D01*
X653850Y444667D01*
X653808Y444292D01*
X653892Y443917D01*
X654017Y443667D01*
X654267Y443417D01*
X654558Y443250D01*
X654850Y443167D01*
X655142D01*
X655433Y443250D01*
X655683Y443375D01*
X655892Y443542D01*
G01X657158Y444209D02*
X657450Y444500D01*
X657700Y444667D01*
X658033Y444750D01*
X658325Y444667D01*
X658533Y444500D01*
X658700Y444250D01*
X658742Y443959D01*
X658700Y443709D01*
X658533Y443459D01*
X658283Y443250D01*
X657992Y443167D01*
X657658Y443250D01*
X657367Y443500D01*
X657200Y443875D01*
X657158Y444292D01*
X657242Y444834D01*
X657367Y445125D01*
X657575Y445417D01*
X657867Y445625D01*
X658158Y445667D01*
X658450Y445584D01*
X658658Y445375D01*
G01X661050Y445667D02*
X660717Y445584D01*
X660467Y445375D01*
X660300Y445125D01*
X660175Y444792D01*
X660133Y444417D01*
X660175Y444042D01*
X660300Y443709D01*
X660467Y443459D01*
X660717Y443250D01*
X661050Y443167D01*
X661383Y443250D01*
X661633Y443459D01*
X661800Y443709D01*
X661925Y444042D01*
X661967Y444417D01*
X661925Y444792D01*
X661800Y445125D01*
X661633Y445375D01*
X661383Y445584D01*
X661050Y445667D01*
G01X664150Y443167D02*
Y445667D01*
X663650Y445167D01*
G01Y443167D02*
X664650D01*
G01X649708Y450267D02*
X649583Y450017D01*
X649500Y449725D01*
Y449392D01*
X649625Y449017D01*
X649833Y448725D01*
X650083Y448517D01*
X650500Y448350D01*
X650875Y448308D01*
X651250Y448392D01*
X651500Y448517D01*
X651750Y448767D01*
X651917Y449058D01*
X652000Y449350D01*
Y449642D01*
X651917Y449933D01*
X651792Y450183D01*
X651625Y450392D01*
G01X650958Y451658D02*
X650667Y451950D01*
X650500Y452200D01*
X650417Y452533D01*
X650500Y452825D01*
X650667Y453033D01*
X650917Y453200D01*
X651208Y453242D01*
X651458Y453200D01*
X651708Y453033D01*
X651917Y452783D01*
X652000Y452492D01*
X651917Y452158D01*
X651667Y451867D01*
X651292Y451700D01*
X650875Y451658D01*
X650333Y451742D01*
X650042Y451867D01*
X649750Y452075D01*
X649542Y452367D01*
X649500Y452658D01*
X649583Y452950D01*
X649792Y453158D01*
G01X651708Y454842D02*
X651917Y455133D01*
X652000Y455467D01*
X651917Y455800D01*
X651667Y456092D01*
X651292Y456300D01*
X650917Y456383D01*
X650458D01*
X650083Y456300D01*
X649750Y456092D01*
X649583Y455842D01*
X649500Y455550D01*
X649583Y455217D01*
X649750Y454967D01*
X650000Y454800D01*
X650333Y454717D01*
X650625Y454800D01*
X650917Y455008D01*
X651083Y455258D01*
X651125Y455550D01*
X651042Y455883D01*
X650833Y456133D01*
X650458Y456383D01*
G01X652000Y458650D02*
X651958Y458942D01*
X651833Y459275D01*
X651625Y459483D01*
X651333Y459567D01*
X651042Y459483D01*
X650792Y459233D01*
X650667Y458858D01*
Y458442D01*
X650583Y458192D01*
X650375Y457983D01*
X650083Y457900D01*
X649792Y458025D01*
X649583Y458317D01*
X649500Y458650D01*
X649583Y458983D01*
X649792Y459275D01*
X650083Y459400D01*
X650375Y459317D01*
X650583Y459108D01*
X650667Y458858D01*
Y458442D01*
X650792Y458067D01*
X651042Y457817D01*
X651333Y457733D01*
X651625Y457817D01*
X651833Y458025D01*
X651958Y458358D01*
X652000Y458650D01*
G01X667708Y451267D02*
X667583Y451017D01*
X667500Y450725D01*
Y450392D01*
X667625Y450017D01*
X667833Y449725D01*
X668083Y449517D01*
X668500Y449350D01*
X668875Y449308D01*
X669250Y449392D01*
X669500Y449517D01*
X669750Y449767D01*
X669917Y450058D01*
X670000Y450350D01*
Y450642D01*
X669917Y450933D01*
X669792Y451183D01*
X669625Y451392D01*
G01X668958Y452658D02*
X668667Y452950D01*
X668500Y453200D01*
X668417Y453533D01*
X668500Y453825D01*
X668667Y454033D01*
X668917Y454200D01*
X669208Y454242D01*
X669458Y454200D01*
X669708Y454033D01*
X669917Y453783D01*
X670000Y453492D01*
X669917Y453158D01*
X669667Y452867D01*
X669292Y452700D01*
X668875Y452658D01*
X668333Y452742D01*
X668042Y452867D01*
X667750Y453075D01*
X667542Y453367D01*
X667500Y453658D01*
X667583Y453950D01*
X667792Y454158D01*
G01X667500Y456550D02*
X667583Y456217D01*
X667792Y455967D01*
X668042Y455800D01*
X668375Y455675D01*
X668750Y455633D01*
X669125Y455675D01*
X669458Y455800D01*
X669708Y455967D01*
X669917Y456217D01*
X670000Y456550D01*
X669917Y456883D01*
X669708Y457133D01*
X669458Y457300D01*
X669125Y457425D01*
X668750Y457467D01*
X668375Y457425D01*
X668042Y457300D01*
X667792Y457133D01*
X667583Y456883D01*
X667500Y456550D01*
G01X669500Y458733D02*
X669792Y458983D01*
X669958Y459317D01*
X670000Y459692D01*
X669958Y460025D01*
X669750Y460358D01*
X669500Y460567D01*
X669250Y460608D01*
X668958Y460525D01*
X668750Y460233D01*
X668667Y459942D01*
Y459567D01*
G01Y459942D02*
X668542Y460192D01*
X668333Y460400D01*
X668083Y460483D01*
X667833Y460400D01*
X667625Y460192D01*
X667500Y459817D01*
X667542Y459442D01*
X667708Y459067D01*
G01X653708Y428767D02*
X653583Y428517D01*
X653500Y428225D01*
Y427892D01*
X653625Y427517D01*
X653833Y427225D01*
X654083Y427017D01*
X654500Y426850D01*
X654875Y426808D01*
X655250Y426892D01*
X655500Y427017D01*
X655750Y427267D01*
X655917Y427558D01*
X656000Y427850D01*
Y428142D01*
X655917Y428433D01*
X655792Y428683D01*
X655625Y428892D01*
G01X654958Y430158D02*
X654667Y430450D01*
X654500Y430700D01*
X654417Y431033D01*
X654500Y431325D01*
X654667Y431533D01*
X654917Y431700D01*
X655208Y431742D01*
X655458Y431700D01*
X655708Y431533D01*
X655917Y431283D01*
X656000Y430992D01*
X655917Y430658D01*
X655667Y430367D01*
X655292Y430200D01*
X654875Y430158D01*
X654333Y430242D01*
X654042Y430367D01*
X653750Y430575D01*
X653542Y430867D01*
X653500Y431158D01*
X653583Y431450D01*
X653792Y431658D01*
G01X654958Y433258D02*
X654667Y433550D01*
X654500Y433800D01*
X654417Y434133D01*
X654500Y434425D01*
X654667Y434633D01*
X654917Y434800D01*
X655208Y434842D01*
X655458Y434800D01*
X655708Y434633D01*
X655917Y434383D01*
X656000Y434092D01*
X655917Y433758D01*
X655667Y433467D01*
X655292Y433300D01*
X654875Y433258D01*
X654333Y433342D01*
X654042Y433467D01*
X653750Y433675D01*
X653542Y433967D01*
X653500Y434258D01*
X653583Y434550D01*
X653792Y434758D01*
G01X656000Y437650D02*
X653500D01*
X655292Y436108D01*
Y438192D01*
G01X643478Y462997D02*
X643353Y462747D01*
X643270Y462455D01*
Y462122D01*
X643395Y461747D01*
X643603Y461455D01*
X643853Y461247D01*
X644270Y461080D01*
X644645Y461038D01*
X645020Y461122D01*
X645270Y461247D01*
X645520Y461497D01*
X645687Y461788D01*
X645770Y462080D01*
Y462372D01*
X645687Y462663D01*
X645562Y462913D01*
X645395Y463122D01*
G01X644728Y464388D02*
X644437Y464680D01*
X644270Y464930D01*
X644187Y465263D01*
X644270Y465555D01*
X644437Y465763D01*
X644687Y465930D01*
X644978Y465972D01*
X645228Y465930D01*
X645478Y465763D01*
X645687Y465513D01*
X645770Y465222D01*
X645687Y464888D01*
X645437Y464597D01*
X645062Y464430D01*
X644645Y464388D01*
X644103Y464472D01*
X643812Y464597D01*
X643520Y464805D01*
X643312Y465097D01*
X643270Y465388D01*
X643353Y465680D01*
X643562Y465888D01*
G01X643270Y468280D02*
X643353Y467947D01*
X643562Y467697D01*
X643812Y467530D01*
X644145Y467405D01*
X644520Y467363D01*
X644895Y467405D01*
X645228Y467530D01*
X645478Y467697D01*
X645687Y467947D01*
X645770Y468280D01*
X645687Y468613D01*
X645478Y468863D01*
X645228Y469030D01*
X644895Y469155D01*
X644520Y469197D01*
X644145Y469155D01*
X643812Y469030D01*
X643562Y468863D01*
X643353Y468613D01*
X643270Y468280D01*
G01X644728Y470588D02*
X644437Y470880D01*
X644270Y471130D01*
X644187Y471463D01*
X644270Y471755D01*
X644437Y471963D01*
X644687Y472130D01*
X644978Y472172D01*
X645228Y472130D01*
X645478Y471963D01*
X645687Y471713D01*
X645770Y471422D01*
X645687Y471088D01*
X645437Y470797D01*
X645062Y470630D01*
X644645Y470588D01*
X644103Y470672D01*
X643812Y470797D01*
X643520Y471005D01*
X643312Y471297D01*
X643270Y471588D01*
X643353Y471880D01*
X643562Y472088D01*
G01X641078Y450497D02*
X640953Y450247D01*
X640870Y449955D01*
Y449622D01*
X640995Y449247D01*
X641203Y448955D01*
X641453Y448747D01*
X641870Y448580D01*
X642245Y448538D01*
X642620Y448622D01*
X642870Y448747D01*
X643120Y448997D01*
X643287Y449288D01*
X643370Y449580D01*
Y449872D01*
X643287Y450163D01*
X643162Y450413D01*
X642995Y450622D01*
G01X642328Y451888D02*
X642037Y452180D01*
X641870Y452430D01*
X641787Y452763D01*
X641870Y453055D01*
X642037Y453263D01*
X642287Y453430D01*
X642578Y453472D01*
X642828Y453430D01*
X643078Y453263D01*
X643287Y453013D01*
X643370Y452722D01*
X643287Y452388D01*
X643037Y452097D01*
X642662Y451930D01*
X642245Y451888D01*
X641703Y451972D01*
X641412Y452097D01*
X641120Y452305D01*
X640912Y452597D01*
X640870Y452888D01*
X640953Y453180D01*
X641162Y453388D01*
G01X643078Y455072D02*
X643287Y455363D01*
X643370Y455697D01*
X643287Y456030D01*
X643037Y456322D01*
X642662Y456530D01*
X642287Y456613D01*
X641828D01*
X641453Y456530D01*
X641120Y456322D01*
X640953Y456072D01*
X640870Y455780D01*
X640953Y455447D01*
X641120Y455197D01*
X641370Y455030D01*
X641703Y454947D01*
X641995Y455030D01*
X642287Y455238D01*
X642453Y455488D01*
X642495Y455780D01*
X642412Y456113D01*
X642203Y456363D01*
X641828Y456613D01*
G01X643370Y458797D02*
X642828Y458880D01*
X642370Y459005D01*
X641953Y459172D01*
X641495Y459380D01*
X640870Y459713D01*
Y458047D01*
G01X645308Y450467D02*
X645183Y450217D01*
X645100Y449925D01*
Y449592D01*
X645225Y449217D01*
X645433Y448925D01*
X645683Y448717D01*
X646100Y448550D01*
X646475Y448508D01*
X646850Y448592D01*
X647100Y448717D01*
X647350Y448967D01*
X647517Y449258D01*
X647600Y449550D01*
Y449842D01*
X647517Y450133D01*
X647392Y450383D01*
X647225Y450592D01*
G01X646558Y451858D02*
X646267Y452150D01*
X646100Y452400D01*
X646017Y452733D01*
X646100Y453025D01*
X646267Y453233D01*
X646517Y453400D01*
X646808Y453442D01*
X647058Y453400D01*
X647308Y453233D01*
X647517Y452983D01*
X647600Y452692D01*
X647517Y452358D01*
X647267Y452067D01*
X646892Y451900D01*
X646475Y451858D01*
X645933Y451942D01*
X645642Y452067D01*
X645350Y452275D01*
X645142Y452567D01*
X645100Y452858D01*
X645183Y453150D01*
X645392Y453358D01*
G01X647308Y455042D02*
X647517Y455333D01*
X647600Y455667D01*
X647517Y456000D01*
X647267Y456292D01*
X646892Y456500D01*
X646517Y456583D01*
X646058D01*
X645683Y456500D01*
X645350Y456292D01*
X645183Y456042D01*
X645100Y455750D01*
X645183Y455417D01*
X645350Y455167D01*
X645600Y455000D01*
X645933Y454917D01*
X646225Y455000D01*
X646517Y455208D01*
X646683Y455458D01*
X646725Y455750D01*
X646642Y456083D01*
X646433Y456333D01*
X646058Y456583D01*
G01X646558Y458058D02*
X646267Y458350D01*
X646100Y458600D01*
X646017Y458933D01*
X646100Y459225D01*
X646267Y459433D01*
X646517Y459600D01*
X646808Y459642D01*
X647058Y459600D01*
X647308Y459433D01*
X647517Y459183D01*
X647600Y458892D01*
X647517Y458558D01*
X647267Y458267D01*
X646892Y458100D01*
X646475Y458058D01*
X645933Y458142D01*
X645642Y458267D01*
X645350Y458475D01*
X645142Y458767D01*
X645100Y459058D01*
X645183Y459350D01*
X645392Y459558D01*
G01X680662Y448421D02*
Y443421D01*
X685662D01*
G01Y471121D02*
X680662D01*
Y466121D01*
G01X682069Y452153D02*
X679069D01*
G01X689394Y469714D02*
Y471714D01*
G01X639500Y448517D02*
X637000D01*
Y449558D01*
X637125Y449892D01*
X637292Y450100D01*
X637625Y450183D01*
X637958Y450100D01*
X638167Y449850D01*
X638292Y449558D01*
Y448517D01*
G01Y449558D02*
X639500Y450183D01*
G01X639000Y451533D02*
X639292Y451783D01*
X639458Y452117D01*
X639500Y452492D01*
X639458Y452825D01*
X639250Y453158D01*
X639000Y453367D01*
X638750Y453408D01*
X638458Y453325D01*
X638250Y453033D01*
X638167Y452742D01*
Y452367D01*
G01Y452742D02*
X638042Y452992D01*
X637833Y453200D01*
X637583Y453283D01*
X637333Y453200D01*
X637125Y452992D01*
X637000Y452617D01*
X637042Y452242D01*
X637208Y451867D01*
G01X639500Y455467D02*
X638958Y455550D01*
X638500Y455675D01*
X638083Y455842D01*
X637625Y456050D01*
X637000Y456383D01*
Y454717D01*
G01X639208Y457942D02*
X639417Y458233D01*
X639500Y458567D01*
X639417Y458900D01*
X639167Y459192D01*
X638792Y459400D01*
X638417Y459483D01*
X637958D01*
X637583Y459400D01*
X637250Y459192D01*
X637083Y458942D01*
X637000Y458650D01*
X637083Y458317D01*
X637250Y458067D01*
X637500Y457900D01*
X637833Y457817D01*
X638125Y457900D01*
X638417Y458108D01*
X638583Y458358D01*
X638625Y458650D01*
X638542Y458983D01*
X638333Y459233D01*
X637958Y459483D01*
G01X692200Y479900D02*
X700000D01*
G01X692200Y486900D02*
Y479900D01*
G01X653334Y449117D02*
X655834D01*
Y450783D01*
G01X654792Y452258D02*
X654501Y452550D01*
X654334Y452800D01*
X654251Y453133D01*
X654334Y453425D01*
X654501Y453633D01*
X654751Y453800D01*
X655042Y453842D01*
X655292Y453800D01*
X655542Y453633D01*
X655751Y453383D01*
X655834Y453092D01*
X655751Y452758D01*
X655501Y452467D01*
X655126Y452300D01*
X654709Y452258D01*
X654167Y452342D01*
X653876Y452467D01*
X653584Y452675D01*
X653376Y452967D01*
X653334Y453258D01*
X653417Y453550D01*
X653626Y453758D01*
G01X638600Y430800D02*
Y444200D01*
G01X692200Y486900D02*
X697400D01*
G01X705600D02*
X696900D01*
G01X736101Y-9511D02*
X736634Y-9844D01*
X737234Y-10044D01*
X737768D01*
X738301Y-9844D01*
X738701Y-9511D01*
X738901Y-9044D01*
X738768Y-8577D01*
X738434Y-8177D01*
X737834Y-7911D01*
X737034Y-7777D01*
X736568Y-7511D01*
X736368Y-7044D01*
X736501Y-6577D01*
X736834Y-6244D01*
X737301Y-6044D01*
X737768D01*
X738234Y-6177D01*
X738634Y-6511D01*
G01X742101Y-10044D02*
Y-6044D01*
G01X746701Y-7377D02*
Y-10044D01*
G01Y-6311D02*
X746568Y-6244D01*
Y-6111D01*
X746701Y-6044D01*
X746834Y-6111D01*
Y-6244D01*
X746701Y-6311D01*
G01X751301Y-6044D02*
Y-10044D01*
G01X750368Y-7377D02*
X752234D01*
G01X704961Y0D02*
Y63561D01*
X763561D01*
Y0D01*
X704961D01*
G01X727500Y71017D02*
X725000D01*
Y72058D01*
X725125Y72392D01*
X725292Y72600D01*
X725625Y72683D01*
X725958Y72600D01*
X726167Y72350D01*
X726292Y72058D01*
Y71017D01*
G01Y72058D02*
X727500Y72683D01*
G01X725417Y74158D02*
X725167Y74408D01*
X725042Y74700D01*
X725000Y75033D01*
X725083Y75450D01*
X725292Y75742D01*
X725542Y75825D01*
X725792Y75783D01*
X726000Y75617D01*
X726417Y74783D01*
X726708Y74408D01*
X727125Y74158D01*
X727500Y74075D01*
Y75825D01*
G01Y77967D02*
X726958Y78050D01*
X726500Y78175D01*
X726083Y78342D01*
X725625Y78550D01*
X725000Y78883D01*
Y77217D01*
G01X726458Y80358D02*
X726167Y80650D01*
X726000Y80900D01*
X725917Y81233D01*
X726000Y81525D01*
X726167Y81733D01*
X726417Y81900D01*
X726708Y81942D01*
X726958Y81900D01*
X727208Y81733D01*
X727417Y81483D01*
X727500Y81192D01*
X727417Y80858D01*
X727167Y80567D01*
X726792Y80400D01*
X726375Y80358D01*
X725833Y80442D01*
X725542Y80567D01*
X725250Y80775D01*
X725042Y81067D01*
X725000Y81358D01*
X725083Y81650D01*
X725292Y81858D01*
G01X733900Y94000D02*
X729900D01*
Y86600D01*
G01X753523Y88115D02*
X757523D01*
Y95515D01*
G01X745017Y79000D02*
Y81500D01*
X746058D01*
X746392Y81375D01*
X746600Y81208D01*
X746683Y80875D01*
X746600Y80542D01*
X746350Y80333D01*
X746058Y80208D01*
X745017D01*
G01X746058D02*
X746683Y79000D01*
G01X748158Y81083D02*
X748408Y81333D01*
X748700Y81458D01*
X749033Y81500D01*
X749450Y81417D01*
X749742Y81208D01*
X749825Y80958D01*
X749783Y80708D01*
X749617Y80500D01*
X748783Y80083D01*
X748408Y79792D01*
X748158Y79375D01*
X748075Y79000D01*
X749825D01*
G01X751133Y79375D02*
X751383Y79167D01*
X751675Y79042D01*
X752050Y79000D01*
X752425Y79083D01*
X752717Y79250D01*
X752925Y79542D01*
X752967Y79875D01*
X752883Y80208D01*
X752675Y80417D01*
X752383Y80583D01*
X752092Y80625D01*
X751800Y80583D01*
X751425Y80417D01*
X751550Y81500D01*
X752675D01*
G01X755150Y79000D02*
X755442Y79042D01*
X755775Y79167D01*
X755983Y79375D01*
X756067Y79667D01*
X755983Y79958D01*
X755733Y80208D01*
X755358Y80333D01*
X754942D01*
X754692Y80417D01*
X754483Y80625D01*
X754400Y80917D01*
X754525Y81208D01*
X754817Y81417D01*
X755150Y81500D01*
X755483Y81417D01*
X755775Y81208D01*
X755900Y80917D01*
X755817Y80625D01*
X755608Y80417D01*
X755358Y80333D01*
X754942D01*
X754567Y80208D01*
X754317Y79958D01*
X754233Y79667D01*
X754317Y79375D01*
X754525Y79167D01*
X754858Y79042D01*
X755150Y79000D01*
G01X748900Y92500D02*
Y96500D01*
X741500D01*
G01X727517Y101500D02*
Y104000D01*
X728558D01*
X728892Y103875D01*
X729100Y103708D01*
X729183Y103375D01*
X729100Y103042D01*
X728850Y102833D01*
X728558Y102708D01*
X727517D01*
G01X728558D02*
X729183Y101500D01*
G01X730658Y103583D02*
X730908Y103833D01*
X731200Y103958D01*
X731533Y104000D01*
X731950Y103917D01*
X732242Y103708D01*
X732325Y103458D01*
X732283Y103208D01*
X732117Y103000D01*
X731283Y102583D01*
X730908Y102292D01*
X730658Y101875D01*
X730575Y101500D01*
X732325D01*
G01X733633Y102000D02*
X733883Y101708D01*
X734217Y101542D01*
X734592Y101500D01*
X734925Y101542D01*
X735258Y101750D01*
X735467Y102000D01*
X735508Y102250D01*
X735425Y102542D01*
X735133Y102750D01*
X734842Y102833D01*
X734467D01*
G01X734842D02*
X735092Y102958D01*
X735300Y103167D01*
X735383Y103417D01*
X735300Y103667D01*
X735092Y103875D01*
X734717Y104000D01*
X734342Y103958D01*
X733967Y103792D01*
G01X736733Y101875D02*
X736983Y101667D01*
X737275Y101542D01*
X737650Y101500D01*
X738025Y101583D01*
X738317Y101750D01*
X738525Y102042D01*
X738567Y102375D01*
X738483Y102708D01*
X738275Y102917D01*
X737983Y103083D01*
X737692Y103125D01*
X737400Y103083D01*
X737025Y102917D01*
X737150Y104000D01*
X738275D01*
G01X733931Y96293D02*
Y100293D01*
X726531D01*
G01X729217Y70700D02*
Y73200D01*
X730258D01*
X730592Y73075D01*
X730800Y72908D01*
X730883Y72575D01*
X730800Y72242D01*
X730550Y72033D01*
X730258Y71908D01*
X729217D01*
G01X730258D02*
X730883Y70700D01*
G01X732358Y72783D02*
X732608Y73033D01*
X732900Y73158D01*
X733233Y73200D01*
X733650Y73117D01*
X733942Y72908D01*
X734025Y72658D01*
X733983Y72408D01*
X733817Y72200D01*
X732983Y71783D01*
X732608Y71492D01*
X732358Y71075D01*
X732275Y70700D01*
X734025D01*
G01X736167D02*
X736250Y71242D01*
X736375Y71700D01*
X736542Y72117D01*
X736750Y72575D01*
X737083Y73200D01*
X735417D01*
G01X738558Y72783D02*
X738808Y73033D01*
X739100Y73158D01*
X739433Y73200D01*
X739850Y73117D01*
X740142Y72908D01*
X740225Y72658D01*
X740183Y72408D01*
X740017Y72200D01*
X739183Y71783D01*
X738808Y71492D01*
X738558Y71075D01*
X738475Y70700D01*
X740225D01*
G01X741400Y84200D02*
Y88200D01*
X734000D01*
G01X757017Y84500D02*
Y87000D01*
X758058D01*
X758392Y86875D01*
X758600Y86708D01*
X758683Y86375D01*
X758600Y86042D01*
X758350Y85833D01*
X758058Y85708D01*
X757017D01*
G01X758058D02*
X758683Y84500D01*
G01X760158Y86583D02*
X760408Y86833D01*
X760700Y86958D01*
X761033Y87000D01*
X761450Y86917D01*
X761742Y86708D01*
X761825Y86458D01*
X761783Y86208D01*
X761617Y86000D01*
X760783Y85583D01*
X760408Y85292D01*
X760158Y84875D01*
X760075Y84500D01*
X761825D01*
G01X763967D02*
X764050Y85042D01*
X764175Y85500D01*
X764342Y85917D01*
X764550Y86375D01*
X764883Y87000D01*
X763217D01*
G01X767150Y84500D02*
Y87000D01*
X766650Y86500D01*
G01Y84500D02*
X767650D01*
G01X749000Y99800D02*
Y95800D01*
X756400D01*
G01X729217Y74800D02*
Y77300D01*
X730258D01*
X730592Y77175D01*
X730800Y77008D01*
X730883Y76675D01*
X730800Y76342D01*
X730550Y76133D01*
X730258Y76008D01*
X729217D01*
G01X730258D02*
X730883Y74800D01*
G01X732358Y76883D02*
X732608Y77133D01*
X732900Y77258D01*
X733233Y77300D01*
X733650Y77217D01*
X733942Y77008D01*
X734025Y76758D01*
X733983Y76508D01*
X733817Y76300D01*
X732983Y75883D01*
X732608Y75592D01*
X732358Y75175D01*
X732275Y74800D01*
X734025D01*
G01X736167D02*
X736250Y75342D01*
X736375Y75800D01*
X736542Y76217D01*
X736750Y76675D01*
X737083Y77300D01*
X735417D01*
G01X739350D02*
X739017Y77217D01*
X738767Y77008D01*
X738600Y76758D01*
X738475Y76425D01*
X738433Y76050D01*
X738475Y75675D01*
X738600Y75342D01*
X738767Y75092D01*
X739017Y74883D01*
X739350Y74800D01*
X739683Y74883D01*
X739933Y75092D01*
X740100Y75342D01*
X740225Y75675D01*
X740267Y76050D01*
X740225Y76425D01*
X740100Y76758D01*
X739933Y77008D01*
X739683Y77217D01*
X739350Y77300D01*
G01X741400Y88300D02*
Y92300D01*
X734000D01*
G01X745217Y70800D02*
Y73300D01*
X746258D01*
X746592Y73175D01*
X746800Y73008D01*
X746883Y72675D01*
X746800Y72342D01*
X746550Y72133D01*
X746258Y72008D01*
X745217D01*
G01X746258D02*
X746883Y70800D01*
G01X748358Y72883D02*
X748608Y73133D01*
X748900Y73258D01*
X749233Y73300D01*
X749650Y73217D01*
X749942Y73008D01*
X750025Y72758D01*
X749983Y72508D01*
X749817Y72300D01*
X748983Y71883D01*
X748608Y71592D01*
X748358Y71175D01*
X748275Y70800D01*
X750025D01*
G01X751333Y71175D02*
X751583Y70967D01*
X751875Y70842D01*
X752250Y70800D01*
X752625Y70883D01*
X752917Y71050D01*
X753125Y71342D01*
X753167Y71675D01*
X753083Y72008D01*
X752875Y72217D01*
X752583Y72383D01*
X752292Y72425D01*
X752000Y72383D01*
X751625Y72217D01*
X751750Y73300D01*
X752875D01*
G01X755350D02*
X755017Y73217D01*
X754767Y73008D01*
X754600Y72758D01*
X754475Y72425D01*
X754433Y72050D01*
X754475Y71675D01*
X754600Y71342D01*
X754767Y71092D01*
X755017Y70883D01*
X755350Y70800D01*
X755683Y70883D01*
X755933Y71092D01*
X756100Y71342D01*
X756225Y71675D01*
X756267Y72050D01*
X756225Y72425D01*
X756100Y72758D01*
X755933Y73008D01*
X755683Y73217D01*
X755350Y73300D01*
G01X748900Y84300D02*
Y88300D01*
X741500D01*
G01X761000Y71017D02*
X758500D01*
Y72058D01*
X758625Y72392D01*
X758792Y72600D01*
X759125Y72683D01*
X759458Y72600D01*
X759667Y72350D01*
X759792Y72058D01*
Y71017D01*
G01Y72058D02*
X761000Y72683D01*
G01X758917Y74158D02*
X758667Y74408D01*
X758542Y74700D01*
X758500Y75033D01*
X758583Y75450D01*
X758792Y75742D01*
X759042Y75825D01*
X759292Y75783D01*
X759500Y75617D01*
X759917Y74783D01*
X760208Y74408D01*
X760625Y74158D01*
X761000Y74075D01*
Y75825D01*
G01Y78550D02*
X758500D01*
X760292Y77008D01*
Y79092D01*
G01X760708Y80442D02*
X760917Y80733D01*
X761000Y81067D01*
X760917Y81400D01*
X760667Y81692D01*
X760292Y81900D01*
X759917Y81983D01*
X759458D01*
X759083Y81900D01*
X758750Y81692D01*
X758583Y81442D01*
X758500Y81150D01*
X758583Y80817D01*
X758750Y80567D01*
X759000Y80400D01*
X759333Y80317D01*
X759625Y80400D01*
X759917Y80608D01*
X760083Y80858D01*
X760125Y81150D01*
X760042Y81483D01*
X759833Y81733D01*
X759458Y81983D01*
G01X749023Y88115D02*
X753023D01*
Y95515D01*
G01X745217Y74900D02*
Y77400D01*
X746258D01*
X746592Y77275D01*
X746800Y77108D01*
X746883Y76775D01*
X746800Y76442D01*
X746550Y76233D01*
X746258Y76108D01*
X745217D01*
G01X746258D02*
X746883Y74900D01*
G01X748358Y76983D02*
X748608Y77233D01*
X748900Y77358D01*
X749233Y77400D01*
X749650Y77317D01*
X749942Y77108D01*
X750025Y76858D01*
X749983Y76608D01*
X749817Y76400D01*
X748983Y75983D01*
X748608Y75692D01*
X748358Y75275D01*
X748275Y74900D01*
X750025D01*
G01X752750D02*
Y77400D01*
X751208Y75608D01*
X753292D01*
G01X755350Y74900D02*
X755642Y74942D01*
X755975Y75067D01*
X756183Y75275D01*
X756267Y75567D01*
X756183Y75858D01*
X755933Y76108D01*
X755558Y76233D01*
X755142D01*
X754892Y76317D01*
X754683Y76525D01*
X754600Y76817D01*
X754725Y77108D01*
X755017Y77317D01*
X755350Y77400D01*
X755683Y77317D01*
X755975Y77108D01*
X756100Y76817D01*
X756017Y76525D01*
X755808Y76317D01*
X755558Y76233D01*
X755142D01*
X754767Y76108D01*
X754517Y75858D01*
X754433Y75567D01*
X754517Y75275D01*
X754725Y75067D01*
X755058Y74942D01*
X755350Y74900D01*
G01X748900Y88400D02*
Y92400D01*
X741500D01*
G01X738189Y110117D02*
Y114685D01*
G01X736339Y108267D02*
X731771D01*
G01X740039D02*
G02I-1850J0D01*
G01X731771D02*
G02I-1850J0D01*
G01X720500Y76800D02*
X723000D01*
G01X720500Y75842D02*
Y77758D01*
G01X723000Y79067D02*
X720500D01*
Y80067D01*
X720625Y80400D01*
X720917Y80650D01*
X721250Y80733D01*
X721583Y80650D01*
X721833Y80442D01*
X721958Y80067D01*
Y79067D01*
G01X723000Y83000D02*
X720500D01*
X721000Y82500D01*
G01X723000D02*
Y83500D01*
G01X722500Y85183D02*
X722792Y85433D01*
X722958Y85767D01*
X723000Y86142D01*
X722958Y86475D01*
X722750Y86808D01*
X722500Y87017D01*
X722250Y87058D01*
X721958Y86975D01*
X721750Y86683D01*
X721667Y86392D01*
Y86017D01*
G01Y86392D02*
X721542Y86642D01*
X721333Y86850D01*
X721083Y86933D01*
X720833Y86850D01*
X720625Y86642D01*
X720500Y86267D01*
X720542Y85892D01*
X720708Y85517D01*
G01X722500Y88283D02*
X722792Y88533D01*
X722958Y88867D01*
X723000Y89242D01*
X722958Y89575D01*
X722750Y89908D01*
X722500Y90117D01*
X722250Y90158D01*
X721958Y90075D01*
X721750Y89783D01*
X721667Y89492D01*
Y89117D01*
G01Y89492D02*
X721542Y89742D01*
X721333Y89950D01*
X721083Y90033D01*
X720833Y89950D01*
X720625Y89742D01*
X720500Y89367D01*
X720542Y88992D01*
X720708Y88617D01*
G01X729800Y81500D02*
Y79000D01*
G01X728842Y81500D02*
X730758D01*
G01X732067Y79000D02*
Y81500D01*
X733067D01*
X733400Y81375D01*
X733650Y81083D01*
X733733Y80750D01*
X733650Y80417D01*
X733442Y80167D01*
X733067Y80042D01*
X732067D01*
G01X736000Y79000D02*
Y81500D01*
X735500Y81000D01*
G01Y79000D02*
X736500D01*
G01X738183Y79500D02*
X738433Y79208D01*
X738767Y79042D01*
X739142Y79000D01*
X739475Y79042D01*
X739808Y79250D01*
X740017Y79500D01*
X740058Y79750D01*
X739975Y80042D01*
X739683Y80250D01*
X739392Y80333D01*
X739017D01*
G01X739392D02*
X739642Y80458D01*
X739850Y80667D01*
X739933Y80917D01*
X739850Y81167D01*
X739642Y81375D01*
X739267Y81500D01*
X738892Y81458D01*
X738517Y81292D01*
G01X742200Y81500D02*
X741867Y81417D01*
X741617Y81208D01*
X741450Y80958D01*
X741325Y80625D01*
X741283Y80250D01*
X741325Y79875D01*
X741450Y79542D01*
X741617Y79292D01*
X741867Y79083D01*
X742200Y79000D01*
X742533Y79083D01*
X742783Y79292D01*
X742950Y79542D01*
X743075Y79875D01*
X743117Y80250D01*
X743075Y80625D01*
X742950Y80958D01*
X742783Y81208D01*
X742533Y81417D01*
X742200Y81500D01*
G01X714574Y56187D02*
Y60187D01*
X716174D01*
X716707Y59987D01*
X717107Y59520D01*
X717240Y58987D01*
X717107Y58454D01*
X716774Y58054D01*
X716174Y57854D01*
X714574D01*
G01X719574Y56187D02*
Y58854D01*
G01Y58320D02*
X719907Y58587D01*
X720240Y58787D01*
X720707Y58854D01*
X721040Y58787D01*
X721440Y58587D01*
G01X724107Y57987D02*
X726240D01*
X726040Y58454D01*
X725707Y58720D01*
X725240Y58854D01*
X724774Y58787D01*
X724374Y58587D01*
X724107Y58120D01*
X723974Y57720D01*
Y57320D01*
X724107Y56920D01*
X724440Y56520D01*
X724840Y56254D01*
X725307Y56187D01*
X725774Y56320D01*
X726240Y56720D01*
G01X728707Y56654D02*
X729040Y56387D01*
X729507Y56187D01*
X729907D01*
X730307Y56320D01*
X730574Y56520D01*
X730707Y56787D01*
X730640Y57187D01*
X730374Y57387D01*
X729174Y57787D01*
X728907Y58254D01*
X729040Y58587D01*
X729307Y58787D01*
X729707Y58854D01*
X730107Y58787D01*
X730507Y58587D01*
G01X733307Y56654D02*
X733640Y56387D01*
X734107Y56187D01*
X734507D01*
X734907Y56320D01*
X735174Y56520D01*
X735307Y56787D01*
X735240Y57187D01*
X734974Y57387D01*
X733774Y57787D01*
X733507Y58254D01*
X733640Y58587D01*
X733907Y58787D01*
X734307Y58854D01*
X734707Y58787D01*
X735107Y58587D01*
G01X742240Y56187D02*
Y60187D01*
X744774D01*
G01X743840Y58254D02*
X742240D01*
G01X748107Y58854D02*
Y56187D01*
G01Y59920D02*
X747974Y59987D01*
Y60120D01*
X748107Y60187D01*
X748240Y60120D01*
Y59987D01*
X748107Y59920D01*
G01X752707Y60187D02*
Y56187D01*
G01X751774Y58854D02*
X753640D01*
G01X709817Y69459D02*
X709567Y69584D01*
X709275Y69667D01*
X708942D01*
X708567Y69542D01*
X708275Y69334D01*
X708067Y69084D01*
X707900Y68667D01*
X707858Y68292D01*
X707942Y67917D01*
X708067Y67667D01*
X708317Y67417D01*
X708608Y67250D01*
X708900Y67167D01*
X709192D01*
X709483Y67250D01*
X709733Y67375D01*
X709942Y67542D01*
G01X711042Y67167D02*
Y69667D01*
X712958Y67167D01*
Y69667D01*
G01X714308Y68209D02*
X714600Y68500D01*
X714850Y68667D01*
X715183Y68750D01*
X715475Y68667D01*
X715683Y68500D01*
X715850Y68250D01*
X715892Y67959D01*
X715850Y67709D01*
X715683Y67459D01*
X715433Y67250D01*
X715142Y67167D01*
X714808Y67250D01*
X714517Y67500D01*
X714350Y67875D01*
X714308Y68292D01*
X714392Y68834D01*
X714517Y69125D01*
X714725Y69417D01*
X715017Y69625D01*
X715308Y69667D01*
X715600Y69584D01*
X715808Y69375D01*
G01X762871Y141624D02*
Y145624D01*
X755471D01*
G01X762850Y137500D02*
Y141500D01*
X755450D01*
G01X759000Y167550D02*
Y171550D01*
X751600D01*
G01X763900Y133400D02*
Y137400D01*
X756500D01*
G01X755808Y152100D02*
Y156100D01*
X748408D01*
G01X755800Y158050D02*
Y162050D01*
X748400D01*
G01X755823Y146245D02*
Y150245D01*
X748423D01*
G01X759002Y171715D02*
Y175715D01*
X751602D01*
G01X756668Y162081D02*
Y166081D01*
X749268D01*
G01X738189Y196575D02*
Y118385D01*
G01X740039Y116535D02*
G02I-1850J0D01*
G01X747350Y121167D02*
Y118667D01*
G01X746392Y121167D02*
X748308D01*
G01X749617Y118667D02*
Y121167D01*
X750617D01*
X750950Y121042D01*
X751200Y120750D01*
X751283Y120417D01*
X751200Y120084D01*
X750992Y119834D01*
X750617Y119709D01*
X749617D01*
G01X752633Y119042D02*
X752883Y118834D01*
X753175Y118709D01*
X753550Y118667D01*
X753925Y118750D01*
X754217Y118917D01*
X754425Y119209D01*
X754467Y119542D01*
X754383Y119875D01*
X754175Y120084D01*
X753883Y120250D01*
X753592Y120292D01*
X753300Y120250D01*
X752925Y120084D01*
X753050Y121167D01*
X754175D01*
G01X755733Y119167D02*
X755983Y118875D01*
X756317Y118709D01*
X756692Y118667D01*
X757025Y118709D01*
X757358Y118917D01*
X757567Y119167D01*
X757608Y119417D01*
X757525Y119709D01*
X757233Y119917D01*
X756942Y120000D01*
X756567D01*
G01X756942D02*
X757192Y120125D01*
X757400Y120334D01*
X757483Y120584D01*
X757400Y120834D01*
X757192Y121042D01*
X756817Y121167D01*
X756442Y121125D01*
X756067Y120959D01*
G01X759018Y177053D02*
Y181053D01*
X751618D01*
G01X759030Y195200D02*
Y199200D01*
X751630D01*
G01X732334Y237017D02*
X729834D01*
Y238058D01*
X729959Y238392D01*
X730126Y238600D01*
X730459Y238683D01*
X730792Y238600D01*
X731001Y238350D01*
X731126Y238058D01*
Y237017D01*
G01Y238058D02*
X732334Y238683D01*
G01X731834Y240033D02*
X732126Y240283D01*
X732292Y240617D01*
X732334Y240992D01*
X732292Y241325D01*
X732084Y241658D01*
X731834Y241867D01*
X731584Y241908D01*
X731292Y241825D01*
X731084Y241533D01*
X731001Y241242D01*
Y240867D01*
G01Y241242D02*
X730876Y241492D01*
X730667Y241700D01*
X730417Y241783D01*
X730167Y241700D01*
X729959Y241492D01*
X729834Y241117D01*
X729876Y240742D01*
X730042Y240367D01*
G01X732042Y243342D02*
X732251Y243633D01*
X732334Y243967D01*
X732251Y244300D01*
X732001Y244592D01*
X731626Y244800D01*
X731251Y244883D01*
X730792D01*
X730417Y244800D01*
X730084Y244592D01*
X729917Y244342D01*
X729834Y244050D01*
X729917Y243717D01*
X730084Y243467D01*
X730334Y243300D01*
X730667Y243217D01*
X730959Y243300D01*
X731251Y243508D01*
X731417Y243758D01*
X731459Y244050D01*
X731376Y244383D01*
X731167Y244633D01*
X730792Y244883D01*
G01X731959Y246233D02*
X732167Y246483D01*
X732292Y246775D01*
X732334Y247150D01*
X732251Y247525D01*
X732084Y247817D01*
X731792Y248025D01*
X731459Y248067D01*
X731126Y247983D01*
X730917Y247775D01*
X730751Y247483D01*
X730709Y247192D01*
X730751Y246900D01*
X730917Y246525D01*
X729834Y246650D01*
Y247775D01*
G01X732712Y233907D02*
X728712D01*
Y226507D01*
G01X697600Y231800D02*
X701600D01*
Y239200D01*
G01X705017Y221500D02*
Y224000D01*
X706058D01*
X706392Y223875D01*
X706600Y223708D01*
X706683Y223375D01*
X706600Y223042D01*
X706350Y222833D01*
X706058Y222708D01*
X705017D01*
G01X706058D02*
X706683Y221500D01*
G01X708158Y223583D02*
X708408Y223833D01*
X708700Y223958D01*
X709033Y224000D01*
X709450Y223917D01*
X709742Y223708D01*
X709825Y223458D01*
X709783Y223208D01*
X709617Y223000D01*
X708783Y222583D01*
X708408Y222292D01*
X708158Y221875D01*
X708075Y221500D01*
X709825D01*
G01X711258Y223583D02*
X711508Y223833D01*
X711800Y223958D01*
X712133Y224000D01*
X712550Y223917D01*
X712842Y223708D01*
X712925Y223458D01*
X712883Y223208D01*
X712717Y223000D01*
X711883Y222583D01*
X711508Y222292D01*
X711258Y221875D01*
X711175Y221500D01*
X712925D01*
G01X714442Y221792D02*
X714733Y221583D01*
X715067Y221500D01*
X715400Y221583D01*
X715692Y221833D01*
X715900Y222208D01*
X715983Y222583D01*
Y223042D01*
X715900Y223417D01*
X715692Y223750D01*
X715442Y223917D01*
X715150Y224000D01*
X714817Y223917D01*
X714567Y223750D01*
X714400Y223500D01*
X714317Y223167D01*
X714400Y222875D01*
X714608Y222583D01*
X714858Y222417D01*
X715150Y222375D01*
X715483Y222458D01*
X715733Y222667D01*
X715983Y223042D01*
G01X717200Y215500D02*
Y219500D01*
X709800D01*
G01X751630Y203700D02*
Y199700D01*
X759030D01*
G01X751630Y216200D02*
Y212200D01*
X759030D01*
G01X757600Y218717D02*
X755100D01*
Y219758D01*
X755225Y220092D01*
X755392Y220300D01*
X755725Y220383D01*
X756058Y220300D01*
X756267Y220050D01*
X756392Y219758D01*
Y218717D01*
G01Y219758D02*
X757600Y220383D01*
G01X755517Y221858D02*
X755267Y222108D01*
X755142Y222400D01*
X755100Y222733D01*
X755183Y223150D01*
X755392Y223442D01*
X755642Y223525D01*
X755892Y223483D01*
X756100Y223317D01*
X756517Y222483D01*
X756808Y222108D01*
X757225Y221858D01*
X757600Y221775D01*
Y223525D01*
G01X755517Y224958D02*
X755267Y225208D01*
X755142Y225500D01*
X755100Y225833D01*
X755183Y226250D01*
X755392Y226542D01*
X755642Y226625D01*
X755892Y226583D01*
X756100Y226417D01*
X756517Y225583D01*
X756808Y225208D01*
X757225Y224958D01*
X757600Y224875D01*
Y226625D01*
G01X756558Y228058D02*
X756267Y228350D01*
X756100Y228600D01*
X756017Y228933D01*
X756100Y229225D01*
X756267Y229433D01*
X756517Y229600D01*
X756808Y229642D01*
X757058Y229600D01*
X757308Y229433D01*
X757517Y229183D01*
X757600Y228892D01*
X757517Y228558D01*
X757267Y228267D01*
X756892Y228100D01*
X756475Y228058D01*
X755933Y228142D01*
X755642Y228267D01*
X755350Y228475D01*
X755142Y228767D01*
X755100Y229058D01*
X755183Y229350D01*
X755392Y229558D01*
G01X741600Y219000D02*
X745600D01*
Y226400D01*
G01X751630Y212200D02*
Y208200D01*
X759030D01*
G01X753500Y218717D02*
X751000D01*
Y219758D01*
X751125Y220092D01*
X751292Y220300D01*
X751625Y220383D01*
X751958Y220300D01*
X752167Y220050D01*
X752292Y219758D01*
Y218717D01*
G01Y219758D02*
X753500Y220383D01*
G01X751417Y221858D02*
X751167Y222108D01*
X751042Y222400D01*
X751000Y222733D01*
X751083Y223150D01*
X751292Y223442D01*
X751542Y223525D01*
X751792Y223483D01*
X752000Y223317D01*
X752417Y222483D01*
X752708Y222108D01*
X753125Y221858D01*
X753500Y221775D01*
Y223525D01*
G01X751417Y224958D02*
X751167Y225208D01*
X751042Y225500D01*
X751000Y225833D01*
X751083Y226250D01*
X751292Y226542D01*
X751542Y226625D01*
X751792Y226583D01*
X752000Y226417D01*
X752417Y225583D01*
X752708Y225208D01*
X753125Y224958D01*
X753500Y224875D01*
Y226625D01*
G01Y229350D02*
X751000D01*
X752792Y227808D01*
Y229892D01*
G01X737500Y219000D02*
X741500D01*
Y226400D01*
G01X749286Y218740D02*
X746786D01*
Y219781D01*
X746911Y220115D01*
X747078Y220323D01*
X747411Y220406D01*
X747744Y220323D01*
X747953Y220073D01*
X748078Y219781D01*
Y218740D01*
G01Y219781D02*
X749286Y220406D01*
G01X747203Y221881D02*
X746953Y222131D01*
X746828Y222423D01*
X746786Y222756D01*
X746869Y223173D01*
X747078Y223465D01*
X747328Y223548D01*
X747578Y223506D01*
X747786Y223340D01*
X748203Y222506D01*
X748494Y222131D01*
X748911Y221881D01*
X749286Y221798D01*
Y223548D01*
G01X747203Y224981D02*
X746953Y225231D01*
X746828Y225523D01*
X746786Y225856D01*
X746869Y226273D01*
X747078Y226565D01*
X747328Y226648D01*
X747578Y226606D01*
X747786Y226440D01*
X748203Y225606D01*
X748494Y225231D01*
X748911Y224981D01*
X749286Y224898D01*
Y226648D01*
G01X748786Y227956D02*
X749078Y228206D01*
X749244Y228540D01*
X749286Y228915D01*
X749244Y229248D01*
X749036Y229581D01*
X748786Y229790D01*
X748536Y229831D01*
X748244Y229748D01*
X748036Y229456D01*
X747953Y229165D01*
Y228790D01*
G01Y229165D02*
X747828Y229415D01*
X747619Y229623D01*
X747369Y229706D01*
X747119Y229623D01*
X746911Y229415D01*
X746786Y229040D01*
X746828Y228665D01*
X746994Y228290D01*
G01X732286Y219023D02*
X736286D01*
Y226423D01*
G01X728000Y237017D02*
X725500D01*
Y238058D01*
X725625Y238392D01*
X725792Y238600D01*
X726125Y238683D01*
X726458Y238600D01*
X726667Y238350D01*
X726792Y238058D01*
Y237017D01*
G01Y238058D02*
X728000Y238683D01*
G01X725917Y240158D02*
X725667Y240408D01*
X725542Y240700D01*
X725500Y241033D01*
X725583Y241450D01*
X725792Y241742D01*
X726042Y241825D01*
X726292Y241783D01*
X726500Y241617D01*
X726917Y240783D01*
X727208Y240408D01*
X727625Y240158D01*
X728000Y240075D01*
Y241825D01*
G01X725917Y243258D02*
X725667Y243508D01*
X725542Y243800D01*
X725500Y244133D01*
X725583Y244550D01*
X725792Y244842D01*
X726042Y244925D01*
X726292Y244883D01*
X726500Y244717D01*
X726917Y243883D01*
X727208Y243508D01*
X727625Y243258D01*
X728000Y243175D01*
Y244925D01*
G01X725917Y246358D02*
X725667Y246608D01*
X725542Y246900D01*
X725500Y247233D01*
X725583Y247650D01*
X725792Y247942D01*
X726042Y248025D01*
X726292Y247983D01*
X726500Y247817D01*
X726917Y246983D01*
X727208Y246608D01*
X727625Y246358D01*
X728000Y246275D01*
Y248025D01*
G01X724656Y226498D02*
X728656D01*
Y233898D01*
G01X719500Y224017D02*
X717000D01*
Y225058D01*
X717125Y225392D01*
X717292Y225600D01*
X717625Y225683D01*
X717958Y225600D01*
X718167Y225350D01*
X718292Y225058D01*
Y224017D01*
G01Y225058D02*
X719500Y225683D01*
G01X717417Y227158D02*
X717167Y227408D01*
X717042Y227700D01*
X717000Y228033D01*
X717083Y228450D01*
X717292Y228742D01*
X717542Y228825D01*
X717792Y228783D01*
X718000Y228617D01*
X718417Y227783D01*
X718708Y227408D01*
X719125Y227158D01*
X719500Y227075D01*
Y228825D01*
G01X717417Y230258D02*
X717167Y230508D01*
X717042Y230800D01*
X717000Y231133D01*
X717083Y231550D01*
X717292Y231842D01*
X717542Y231925D01*
X717792Y231883D01*
X718000Y231717D01*
X718417Y230883D01*
X718708Y230508D01*
X719125Y230258D01*
X719500Y230175D01*
Y231925D01*
G01Y234150D02*
X717000D01*
X717500Y233650D01*
G01X719500D02*
Y234650D01*
G01X717300Y215500D02*
X721300D01*
Y222900D01*
G01X759018Y181153D02*
Y185153D01*
X751618D01*
G01X759018Y185253D02*
Y189253D01*
X751618D01*
G01X759030Y204200D02*
Y208200D01*
X751630D01*
G01X740286Y235740D02*
X737786D01*
Y236781D01*
X737911Y237115D01*
X738078Y237323D01*
X738411Y237406D01*
X738744Y237323D01*
X738953Y237073D01*
X739078Y236781D01*
Y235740D01*
G01Y236781D02*
X740286Y237406D01*
G01X738203Y238881D02*
X737953Y239131D01*
X737828Y239423D01*
X737786Y239756D01*
X737869Y240173D01*
X738078Y240465D01*
X738328Y240548D01*
X738578Y240506D01*
X738786Y240340D01*
X739203Y239506D01*
X739494Y239131D01*
X739911Y238881D01*
X740286Y238798D01*
Y240548D01*
G01Y242773D02*
X737786D01*
X738286Y242273D01*
G01X740286D02*
Y243273D01*
G01Y246373D02*
X737786D01*
X739578Y244831D01*
Y246915D01*
G01X740786Y233923D02*
X736786D01*
Y226523D01*
G01X723500Y224017D02*
X721000D01*
Y225058D01*
X721125Y225392D01*
X721292Y225600D01*
X721625Y225683D01*
X721958Y225600D01*
X722167Y225350D01*
X722292Y225058D01*
Y224017D01*
G01Y225058D02*
X723500Y225683D01*
G01X721417Y227158D02*
X721167Y227408D01*
X721042Y227700D01*
X721000Y228033D01*
X721083Y228450D01*
X721292Y228742D01*
X721542Y228825D01*
X721792Y228783D01*
X722000Y228617D01*
X722417Y227783D01*
X722708Y227408D01*
X723125Y227158D01*
X723500Y227075D01*
Y228825D01*
G01Y231050D02*
X721000D01*
X721500Y230550D01*
G01X723500D02*
Y231550D01*
G01X723000Y233233D02*
X723292Y233483D01*
X723458Y233817D01*
X723500Y234192D01*
X723458Y234525D01*
X723250Y234858D01*
X723000Y235067D01*
X722750Y235108D01*
X722458Y235025D01*
X722250Y234733D01*
X722167Y234442D01*
Y234067D01*
G01Y234442D02*
X722042Y234692D01*
X721833Y234900D01*
X721583Y234983D01*
X721333Y234900D01*
X721125Y234692D01*
X721000Y234317D01*
X721042Y233942D01*
X721208Y233567D01*
G01X727750Y222972D02*
X723750D01*
Y215572D01*
G01X714720Y239822D02*
X710720D01*
Y232422D01*
G01X738189Y204843D02*
Y200275D01*
G01X736339Y206693D02*
X731771D01*
G01X740039D02*
G02I-1850J0D01*
G01Y198425D02*
G02I-1850J0D01*
G01X731771Y206693D02*
G02I-1850J0D01*
G01X702500Y229300D02*
X705000D01*
G01X702500Y228342D02*
Y230258D01*
G01X705000Y231567D02*
X702500D01*
Y232567D01*
X702625Y232900D01*
X702917Y233150D01*
X703250Y233233D01*
X703583Y233150D01*
X703833Y232942D01*
X703958Y232567D01*
Y231567D01*
G01X705000Y235500D02*
X702500D01*
X703000Y235000D01*
G01X705000D02*
Y236000D01*
G01Y239100D02*
X702500D01*
X704292Y237558D01*
Y239642D01*
G01X702500Y241700D02*
X702583Y241367D01*
X702792Y241117D01*
X703042Y240950D01*
X703375Y240825D01*
X703750Y240783D01*
X704125Y240825D01*
X704458Y240950D01*
X704708Y241117D01*
X704917Y241367D01*
X705000Y241700D01*
X704917Y242033D01*
X704708Y242283D01*
X704458Y242450D01*
X704125Y242575D01*
X703750Y242617D01*
X703375Y242575D01*
X703042Y242450D01*
X702792Y242283D01*
X702583Y242033D01*
X702500Y241700D01*
G01X708300Y214500D02*
Y212000D01*
G01X707342Y214500D02*
X709258D01*
G01X710567Y212000D02*
Y214500D01*
X711567D01*
X711900Y214375D01*
X712150Y214083D01*
X712233Y213750D01*
X712150Y213417D01*
X711942Y213167D01*
X711567Y213042D01*
X710567D01*
G01X714500Y212000D02*
Y214500D01*
X714000Y214000D01*
G01Y212000D02*
X715000D01*
G01X717600D02*
Y214500D01*
X717100Y214000D01*
G01Y212000D02*
X718100D01*
G01X721200D02*
Y214500D01*
X719658Y212708D01*
X721742D01*
G01X747800Y195300D02*
X750300D01*
G01X747800Y194342D02*
Y196258D01*
G01X750300Y197567D02*
X747800D01*
Y198567D01*
X747925Y198900D01*
X748217Y199150D01*
X748550Y199233D01*
X748883Y199150D01*
X749133Y198942D01*
X749258Y198567D01*
Y197567D01*
G01X750300Y201500D02*
X747800D01*
X748300Y201000D01*
G01X750300D02*
Y202000D01*
G01X747800Y204600D02*
X747883Y204267D01*
X748092Y204017D01*
X748342Y203850D01*
X748675Y203725D01*
X749050Y203683D01*
X749425Y203725D01*
X749758Y203850D01*
X750008Y204017D01*
X750217Y204267D01*
X750300Y204600D01*
X750217Y204933D01*
X750008Y205183D01*
X749758Y205350D01*
X749425Y205475D01*
X749050Y205517D01*
X748675Y205475D01*
X748342Y205350D01*
X748092Y205183D01*
X747883Y204933D01*
X747800Y204600D01*
G01X749800Y206783D02*
X750092Y207033D01*
X750258Y207367D01*
X750300Y207742D01*
X750258Y208075D01*
X750050Y208408D01*
X749800Y208617D01*
X749550Y208658D01*
X749258Y208575D01*
X749050Y208283D01*
X748967Y207992D01*
Y207617D01*
G01Y207992D02*
X748842Y208242D01*
X748633Y208450D01*
X748383Y208533D01*
X748133Y208450D01*
X747925Y208242D01*
X747800Y207867D01*
X747842Y207492D01*
X748008Y207117D01*
G01X706500Y227300D02*
X709000D01*
G01X706500Y226342D02*
Y228258D01*
G01X709000Y229567D02*
X706500D01*
Y230567D01*
X706625Y230900D01*
X706917Y231150D01*
X707250Y231233D01*
X707583Y231150D01*
X707833Y230942D01*
X707958Y230567D01*
Y229567D01*
G01X709000Y233500D02*
X706500D01*
X707000Y233000D01*
G01X709000D02*
Y234000D01*
G01Y237100D02*
X706500D01*
X708292Y235558D01*
Y237642D01*
G01X708500Y238783D02*
X708792Y239033D01*
X708958Y239367D01*
X709000Y239742D01*
X708958Y240075D01*
X708750Y240408D01*
X708500Y240617D01*
X708250Y240658D01*
X707958Y240575D01*
X707750Y240283D01*
X707667Y239992D01*
Y239617D01*
G01Y239992D02*
X707542Y240242D01*
X707333Y240450D01*
X707083Y240533D01*
X706833Y240450D01*
X706625Y240242D01*
X706500Y239867D01*
X706542Y239492D01*
X706708Y239117D01*
G01X758017Y292667D02*
Y295167D01*
X759058D01*
X759392Y295042D01*
X759600Y294875D01*
X759683Y294542D01*
X759600Y294209D01*
X759350Y294000D01*
X759058Y293875D01*
X758017D01*
G01X759058D02*
X759683Y292667D01*
G01X761158Y294750D02*
X761408Y295000D01*
X761700Y295125D01*
X762033Y295167D01*
X762450Y295084D01*
X762742Y294875D01*
X762825Y294625D01*
X762783Y294375D01*
X762617Y294167D01*
X761783Y293750D01*
X761408Y293459D01*
X761158Y293042D01*
X761075Y292667D01*
X762825D01*
G01X764342Y292959D02*
X764633Y292750D01*
X764967Y292667D01*
X765300Y292750D01*
X765592Y293000D01*
X765800Y293375D01*
X765883Y293750D01*
Y294209D01*
X765800Y294584D01*
X765592Y294917D01*
X765342Y295084D01*
X765050Y295167D01*
X764717Y295084D01*
X764467Y294917D01*
X764300Y294667D01*
X764217Y294334D01*
X764300Y294042D01*
X764508Y293750D01*
X764758Y293584D01*
X765050Y293542D01*
X765383Y293625D01*
X765633Y293834D01*
X765883Y294209D01*
G01X767358Y293709D02*
X767650Y294000D01*
X767900Y294167D01*
X768233Y294250D01*
X768525Y294167D01*
X768733Y294000D01*
X768900Y293750D01*
X768942Y293459D01*
X768900Y293209D01*
X768733Y292959D01*
X768483Y292750D01*
X768192Y292667D01*
X767858Y292750D01*
X767567Y293000D01*
X767400Y293375D01*
X767358Y293792D01*
X767442Y294334D01*
X767567Y294625D01*
X767775Y294917D01*
X768067Y295125D01*
X768358Y295167D01*
X768650Y295084D01*
X768858Y294875D01*
G01X755500Y261117D02*
X753000D01*
Y262158D01*
X753125Y262492D01*
X753292Y262700D01*
X753625Y262783D01*
X753958Y262700D01*
X754167Y262450D01*
X754292Y262158D01*
Y261117D01*
G01Y262158D02*
X755500Y262783D01*
G01X753417Y264258D02*
X753167Y264508D01*
X753042Y264800D01*
X753000Y265133D01*
X753083Y265550D01*
X753292Y265842D01*
X753542Y265925D01*
X753792Y265883D01*
X754000Y265717D01*
X754417Y264883D01*
X754708Y264508D01*
X755125Y264258D01*
X755500Y264175D01*
Y265925D01*
G01X755208Y267442D02*
X755417Y267733D01*
X755500Y268067D01*
X755417Y268400D01*
X755167Y268692D01*
X754792Y268900D01*
X754417Y268983D01*
X753958D01*
X753583Y268900D01*
X753250Y268692D01*
X753083Y268442D01*
X753000Y268150D01*
X753083Y267817D01*
X753250Y267567D01*
X753500Y267400D01*
X753833Y267317D01*
X754125Y267400D01*
X754417Y267608D01*
X754583Y267858D01*
X754625Y268150D01*
X754542Y268483D01*
X754333Y268733D01*
X753958Y268983D01*
G01X755500Y271167D02*
X754958Y271250D01*
X754500Y271375D01*
X754083Y271542D01*
X753625Y271750D01*
X753000Y272083D01*
Y270417D01*
G01X757651Y261407D02*
X761651D01*
Y268807D01*
G01X729017Y296500D02*
Y299000D01*
X730058D01*
X730392Y298875D01*
X730600Y298708D01*
X730683Y298375D01*
X730600Y298042D01*
X730350Y297833D01*
X730058Y297708D01*
X729017D01*
G01X730058D02*
X730683Y296500D01*
G01X732033Y297000D02*
X732283Y296708D01*
X732617Y296542D01*
X732992Y296500D01*
X733325Y296542D01*
X733658Y296750D01*
X733867Y297000D01*
X733908Y297250D01*
X733825Y297542D01*
X733533Y297750D01*
X733242Y297833D01*
X732867D01*
G01X733242D02*
X733492Y297958D01*
X733700Y298167D01*
X733783Y298417D01*
X733700Y298667D01*
X733492Y298875D01*
X733117Y299000D01*
X732742Y298958D01*
X732367Y298792D01*
G01X735967Y296500D02*
X736050Y297042D01*
X736175Y297500D01*
X736342Y297917D01*
X736550Y298375D01*
X736883Y299000D01*
X735217D01*
G01X739150D02*
X738817Y298917D01*
X738567Y298708D01*
X738400Y298458D01*
X738275Y298125D01*
X738233Y297750D01*
X738275Y297375D01*
X738400Y297042D01*
X738567Y296792D01*
X738817Y296583D01*
X739150Y296500D01*
X739483Y296583D01*
X739733Y296792D01*
X739900Y297042D01*
X740025Y297375D01*
X740067Y297750D01*
X740025Y298125D01*
X739900Y298458D01*
X739733Y298708D01*
X739483Y298917D01*
X739150Y299000D01*
G01X745270Y303620D02*
Y299620D01*
X752670D01*
G01X729017Y292000D02*
Y294500D01*
X730058D01*
X730392Y294375D01*
X730600Y294208D01*
X730683Y293875D01*
X730600Y293542D01*
X730350Y293333D01*
X730058Y293208D01*
X729017D01*
G01X730058D02*
X730683Y292000D01*
G01X732033Y292500D02*
X732283Y292208D01*
X732617Y292042D01*
X732992Y292000D01*
X733325Y292042D01*
X733658Y292250D01*
X733867Y292500D01*
X733908Y292750D01*
X733825Y293042D01*
X733533Y293250D01*
X733242Y293333D01*
X732867D01*
G01X733242D02*
X733492Y293458D01*
X733700Y293667D01*
X733783Y293917D01*
X733700Y294167D01*
X733492Y294375D01*
X733117Y294500D01*
X732742Y294458D01*
X732367Y294292D01*
G01X735967Y292000D02*
X736050Y292542D01*
X736175Y293000D01*
X736342Y293417D01*
X736550Y293875D01*
X736883Y294500D01*
X735217D01*
G01X739150Y292000D02*
Y294500D01*
X738650Y294000D01*
G01Y292000D02*
X739650D01*
G01X752670Y295120D02*
Y299120D01*
X745270D01*
G01X700834Y241517D02*
X698334D01*
Y242558D01*
X698459Y242892D01*
X698626Y243100D01*
X698959Y243183D01*
X699292Y243100D01*
X699501Y242850D01*
X699626Y242558D01*
Y241517D01*
G01Y242558D02*
X700834Y243183D01*
G01X698751Y244658D02*
X698501Y244908D01*
X698376Y245200D01*
X698334Y245533D01*
X698417Y245950D01*
X698626Y246242D01*
X698876Y246325D01*
X699126Y246283D01*
X699334Y246117D01*
X699751Y245283D01*
X700042Y244908D01*
X700459Y244658D01*
X700834Y244575D01*
Y246325D01*
G01Y248467D02*
X700292Y248550D01*
X699834Y248675D01*
X699417Y248842D01*
X698959Y249050D01*
X698334Y249383D01*
Y247717D01*
G01X700834Y252150D02*
X698334D01*
X700126Y250608D01*
Y252692D01*
G01X713834Y243517D02*
X711334D01*
Y244558D01*
X711459Y244892D01*
X711626Y245100D01*
X711959Y245183D01*
X712292Y245100D01*
X712501Y244850D01*
X712626Y244558D01*
Y243517D01*
G01Y244558D02*
X713834Y245183D01*
G01X711751Y246658D02*
X711501Y246908D01*
X711376Y247200D01*
X711334Y247533D01*
X711417Y247950D01*
X711626Y248242D01*
X711876Y248325D01*
X712126Y248283D01*
X712334Y248117D01*
X712751Y247283D01*
X713042Y246908D01*
X713459Y246658D01*
X713834Y246575D01*
Y248325D01*
G01Y250550D02*
X711334D01*
X711834Y250050D01*
G01X713834D02*
Y251050D01*
G01X713542Y252942D02*
X713751Y253233D01*
X713834Y253567D01*
X713751Y253900D01*
X713501Y254192D01*
X713126Y254400D01*
X712751Y254483D01*
X712292D01*
X711917Y254400D01*
X711584Y254192D01*
X711417Y253942D01*
X711334Y253650D01*
X711417Y253317D01*
X711584Y253067D01*
X711834Y252900D01*
X712167Y252817D01*
X712459Y252900D01*
X712751Y253108D01*
X712917Y253358D01*
X712959Y253650D01*
X712876Y253983D01*
X712667Y254233D01*
X712292Y254483D01*
G01X746767Y285292D02*
X746517Y285417D01*
X746225Y285500D01*
X745892D01*
X745517Y285375D01*
X745225Y285167D01*
X745017Y284917D01*
X744850Y284500D01*
X744808Y284125D01*
X744892Y283750D01*
X745017Y283500D01*
X745267Y283250D01*
X745558Y283083D01*
X745850Y283000D01*
X746142D01*
X746433Y283083D01*
X746683Y283208D01*
X746892Y283375D01*
G01X748033D02*
X748283Y283167D01*
X748575Y283042D01*
X748950Y283000D01*
X749325Y283083D01*
X749617Y283250D01*
X749825Y283542D01*
X749867Y283875D01*
X749783Y284208D01*
X749575Y284417D01*
X749283Y284583D01*
X748992Y284625D01*
X748700Y284583D01*
X748325Y284417D01*
X748450Y285500D01*
X749575D01*
G01X752050D02*
X751717Y285417D01*
X751467Y285208D01*
X751300Y284958D01*
X751175Y284625D01*
X751133Y284250D01*
X751175Y283875D01*
X751300Y283542D01*
X751467Y283292D01*
X751717Y283083D01*
X752050Y283000D01*
X752383Y283083D01*
X752633Y283292D01*
X752800Y283542D01*
X752925Y283875D01*
X752967Y284250D01*
X752925Y284625D01*
X752800Y284958D01*
X752633Y285208D01*
X752383Y285417D01*
X752050Y285500D01*
G01X755150Y283000D02*
X755442Y283042D01*
X755775Y283167D01*
X755983Y283375D01*
X756067Y283667D01*
X755983Y283958D01*
X755733Y284208D01*
X755358Y284333D01*
X754942D01*
X754692Y284417D01*
X754483Y284625D01*
X754400Y284917D01*
X754525Y285208D01*
X754817Y285417D01*
X755150Y285500D01*
X755483Y285417D01*
X755775Y285208D01*
X755900Y284917D01*
X755817Y284625D01*
X755608Y284417D01*
X755358Y284333D01*
X754942D01*
X754567Y284208D01*
X754317Y283958D01*
X754233Y283667D01*
X754317Y283375D01*
X754525Y283167D01*
X754858Y283042D01*
X755150Y283000D01*
G01X741708Y290267D02*
X741583Y290017D01*
X741500Y289725D01*
Y289392D01*
X741625Y289017D01*
X741833Y288725D01*
X742083Y288517D01*
X742500Y288350D01*
X742875Y288308D01*
X743250Y288392D01*
X743500Y288517D01*
X743750Y288767D01*
X743917Y289058D01*
X744000Y289350D01*
Y289642D01*
X743917Y289933D01*
X743792Y290183D01*
X743625Y290392D01*
G01Y291533D02*
X743833Y291783D01*
X743958Y292075D01*
X744000Y292450D01*
X743917Y292825D01*
X743750Y293117D01*
X743458Y293325D01*
X743125Y293367D01*
X742792Y293283D01*
X742583Y293075D01*
X742417Y292783D01*
X742375Y292492D01*
X742417Y292200D01*
X742583Y291825D01*
X741500Y291950D01*
Y293075D01*
G01X743500Y294633D02*
X743792Y294883D01*
X743958Y295217D01*
X744000Y295592D01*
X743958Y295925D01*
X743750Y296258D01*
X743500Y296467D01*
X743250Y296508D01*
X742958Y296425D01*
X742750Y296133D01*
X742667Y295842D01*
Y295467D01*
G01Y295842D02*
X742542Y296092D01*
X742333Y296300D01*
X742083Y296383D01*
X741833Y296300D01*
X741625Y296092D01*
X741500Y295717D01*
X741542Y295342D01*
X741708Y294967D01*
G01X743625Y297733D02*
X743833Y297983D01*
X743958Y298275D01*
X744000Y298650D01*
X743917Y299025D01*
X743750Y299317D01*
X743458Y299525D01*
X743125Y299567D01*
X742792Y299483D01*
X742583Y299275D01*
X742417Y298983D01*
X742375Y298692D01*
X742417Y298400D01*
X742583Y298025D01*
X741500Y298150D01*
Y299275D01*
G01X700067Y302492D02*
X699817Y302617D01*
X699525Y302700D01*
X699192D01*
X698817Y302575D01*
X698525Y302367D01*
X698317Y302117D01*
X698150Y301700D01*
X698108Y301325D01*
X698192Y300950D01*
X698317Y300700D01*
X698567Y300450D01*
X698858Y300283D01*
X699150Y300200D01*
X699442D01*
X699733Y300283D01*
X699983Y300408D01*
X700192Y300575D01*
G01X701333Y300700D02*
X701583Y300408D01*
X701917Y300242D01*
X702292Y300200D01*
X702625Y300242D01*
X702958Y300450D01*
X703167Y300700D01*
X703208Y300950D01*
X703125Y301242D01*
X702833Y301450D01*
X702542Y301533D01*
X702167D01*
G01X702542D02*
X702792Y301658D01*
X703000Y301867D01*
X703083Y302117D01*
X703000Y302367D01*
X702792Y302575D01*
X702417Y302700D01*
X702042Y302658D01*
X701667Y302492D01*
G01X705350Y300200D02*
X705642Y300242D01*
X705975Y300367D01*
X706183Y300575D01*
X706267Y300867D01*
X706183Y301158D01*
X705933Y301408D01*
X705558Y301533D01*
X705142D01*
X704892Y301617D01*
X704683Y301825D01*
X704600Y302117D01*
X704725Y302408D01*
X705017Y302617D01*
X705350Y302700D01*
X705683Y302617D01*
X705975Y302408D01*
X706100Y302117D01*
X706017Y301825D01*
X705808Y301617D01*
X705558Y301533D01*
X705142D01*
X704767Y301408D01*
X704517Y301158D01*
X704433Y300867D01*
X704517Y300575D01*
X704725Y300367D01*
X705058Y300242D01*
X705350Y300200D01*
G01X707533Y300700D02*
X707783Y300408D01*
X708117Y300242D01*
X708492Y300200D01*
X708825Y300242D01*
X709158Y300450D01*
X709367Y300700D01*
X709408Y300950D01*
X709325Y301242D01*
X709033Y301450D01*
X708742Y301533D01*
X708367D01*
G01X708742D02*
X708992Y301658D01*
X709200Y301867D01*
X709283Y302117D01*
X709200Y302367D01*
X708992Y302575D01*
X708617Y302700D01*
X708242Y302658D01*
X707867Y302492D01*
G01X700367Y298592D02*
X700117Y298717D01*
X699825Y298800D01*
X699492D01*
X699117Y298675D01*
X698825Y298467D01*
X698617Y298217D01*
X698450Y297800D01*
X698408Y297425D01*
X698492Y297050D01*
X698617Y296800D01*
X698867Y296550D01*
X699158Y296383D01*
X699450Y296300D01*
X699742D01*
X700033Y296383D01*
X700283Y296508D01*
X700492Y296675D01*
G01X701633Y296800D02*
X701883Y296508D01*
X702217Y296342D01*
X702592Y296300D01*
X702925Y296342D01*
X703258Y296550D01*
X703467Y296800D01*
X703508Y297050D01*
X703425Y297342D01*
X703133Y297550D01*
X702842Y297633D01*
X702467D01*
G01X702842D02*
X703092Y297758D01*
X703300Y297967D01*
X703383Y298217D01*
X703300Y298467D01*
X703092Y298675D01*
X702717Y298800D01*
X702342Y298758D01*
X701967Y298592D01*
G01X705650Y296300D02*
X705942Y296342D01*
X706275Y296467D01*
X706483Y296675D01*
X706567Y296967D01*
X706483Y297258D01*
X706233Y297508D01*
X705858Y297633D01*
X705442D01*
X705192Y297717D01*
X704983Y297925D01*
X704900Y298217D01*
X705025Y298508D01*
X705317Y298717D01*
X705650Y298800D01*
X705983Y298717D01*
X706275Y298508D01*
X706400Y298217D01*
X706317Y297925D01*
X706108Y297717D01*
X705858Y297633D01*
X705442D01*
X705067Y297508D01*
X704817Y297258D01*
X704733Y296967D01*
X704817Y296675D01*
X705025Y296467D01*
X705358Y296342D01*
X705650Y296300D01*
G01X709250D02*
Y298800D01*
X707708Y297008D01*
X709792D01*
G01X700367Y294392D02*
X700117Y294517D01*
X699825Y294600D01*
X699492D01*
X699117Y294475D01*
X698825Y294267D01*
X698617Y294017D01*
X698450Y293600D01*
X698408Y293225D01*
X698492Y292850D01*
X698617Y292600D01*
X698867Y292350D01*
X699158Y292183D01*
X699450Y292100D01*
X699742D01*
X700033Y292183D01*
X700283Y292308D01*
X700492Y292475D01*
G01X701633Y292600D02*
X701883Y292308D01*
X702217Y292142D01*
X702592Y292100D01*
X702925Y292142D01*
X703258Y292350D01*
X703467Y292600D01*
X703508Y292850D01*
X703425Y293142D01*
X703133Y293350D01*
X702842Y293433D01*
X702467D01*
G01X702842D02*
X703092Y293558D01*
X703300Y293767D01*
X703383Y294017D01*
X703300Y294267D01*
X703092Y294475D01*
X702717Y294600D01*
X702342Y294558D01*
X701967Y294392D01*
G01X705650Y292100D02*
X705942Y292142D01*
X706275Y292267D01*
X706483Y292475D01*
X706567Y292767D01*
X706483Y293058D01*
X706233Y293308D01*
X705858Y293433D01*
X705442D01*
X705192Y293517D01*
X704983Y293725D01*
X704900Y294017D01*
X705025Y294308D01*
X705317Y294517D01*
X705650Y294600D01*
X705983Y294517D01*
X706275Y294308D01*
X706400Y294017D01*
X706317Y293725D01*
X706108Y293517D01*
X705858Y293433D01*
X705442D01*
X705067Y293308D01*
X704817Y293058D01*
X704733Y292767D01*
X704817Y292475D01*
X705025Y292267D01*
X705358Y292142D01*
X705650Y292100D01*
G01X707833Y292475D02*
X708083Y292267D01*
X708375Y292142D01*
X708750Y292100D01*
X709125Y292183D01*
X709417Y292350D01*
X709625Y292642D01*
X709667Y292975D01*
X709583Y293308D01*
X709375Y293517D01*
X709083Y293683D01*
X708792Y293725D01*
X708500Y293683D01*
X708125Y293517D01*
X708250Y294600D01*
X709375D01*
G01X748983Y290500D02*
Y288708D01*
X749150Y288333D01*
X749483Y288083D01*
X749900Y288000D01*
X750317Y288083D01*
X750650Y288333D01*
X750817Y288708D01*
Y290500D01*
G01X752208Y290083D02*
X752458Y290333D01*
X752750Y290458D01*
X753083Y290500D01*
X753500Y290417D01*
X753792Y290208D01*
X753875Y289958D01*
X753833Y289708D01*
X753667Y289500D01*
X752833Y289083D01*
X752458Y288792D01*
X752208Y288375D01*
X752125Y288000D01*
X753875D01*
G01X755308Y290083D02*
X755558Y290333D01*
X755850Y290458D01*
X756183Y290500D01*
X756600Y290417D01*
X756892Y290208D01*
X756975Y289958D01*
X756933Y289708D01*
X756767Y289500D01*
X755933Y289083D01*
X755558Y288792D01*
X755308Y288375D01*
X755225Y288000D01*
X756975D01*
G01X775537Y276199D02*
X758337D01*
Y286099D01*
X775537D01*
Y276199D01*
G01X738470Y301637D02*
X735970D01*
Y302678D01*
X736095Y303012D01*
X736262Y303220D01*
X736595Y303303D01*
X736928Y303220D01*
X737137Y302970D01*
X737262Y302678D01*
Y301637D01*
G01Y302678D02*
X738470Y303303D01*
G01X737970Y304653D02*
X738262Y304903D01*
X738428Y305237D01*
X738470Y305612D01*
X738428Y305945D01*
X738220Y306278D01*
X737970Y306487D01*
X737720Y306528D01*
X737428Y306445D01*
X737220Y306153D01*
X737137Y305862D01*
Y305487D01*
G01Y305862D02*
X737012Y306112D01*
X736803Y306320D01*
X736553Y306403D01*
X736303Y306320D01*
X736095Y306112D01*
X735970Y305737D01*
X736012Y305362D01*
X736178Y304987D01*
G01X737428Y307878D02*
X737137Y308170D01*
X736970Y308420D01*
X736887Y308753D01*
X736970Y309045D01*
X737137Y309253D01*
X737387Y309420D01*
X737678Y309462D01*
X737928Y309420D01*
X738178Y309253D01*
X738387Y309003D01*
X738470Y308712D01*
X738387Y308378D01*
X738137Y308087D01*
X737762Y307920D01*
X737345Y307878D01*
X736803Y307962D01*
X736512Y308087D01*
X736220Y308295D01*
X736012Y308587D01*
X735970Y308878D01*
X736053Y309170D01*
X736262Y309378D01*
G01X738470Y312270D02*
X735970D01*
X737762Y310728D01*
Y312812D01*
G01X748970Y312720D02*
X744970D01*
Y305320D01*
G01X742470Y301637D02*
X739970D01*
Y302678D01*
X740095Y303012D01*
X740262Y303220D01*
X740595Y303303D01*
X740928Y303220D01*
X741137Y302970D01*
X741262Y302678D01*
Y301637D01*
G01Y302678D02*
X742470Y303303D01*
G01X741970Y304653D02*
X742262Y304903D01*
X742428Y305237D01*
X742470Y305612D01*
X742428Y305945D01*
X742220Y306278D01*
X741970Y306487D01*
X741720Y306528D01*
X741428Y306445D01*
X741220Y306153D01*
X741137Y305862D01*
Y305487D01*
G01Y305862D02*
X741012Y306112D01*
X740803Y306320D01*
X740553Y306403D01*
X740303Y306320D01*
X740095Y306112D01*
X739970Y305737D01*
X740012Y305362D01*
X740178Y304987D01*
G01X741428Y307878D02*
X741137Y308170D01*
X740970Y308420D01*
X740887Y308753D01*
X740970Y309045D01*
X741137Y309253D01*
X741387Y309420D01*
X741678Y309462D01*
X741928Y309420D01*
X742178Y309253D01*
X742387Y309003D01*
X742470Y308712D01*
X742387Y308378D01*
X742137Y308087D01*
X741762Y307920D01*
X741345Y307878D01*
X740803Y307962D01*
X740512Y308087D01*
X740220Y308295D01*
X740012Y308587D01*
X739970Y308878D01*
X740053Y309170D01*
X740262Y309378D01*
G01X742095Y310853D02*
X742303Y311103D01*
X742428Y311395D01*
X742470Y311770D01*
X742387Y312145D01*
X742220Y312437D01*
X741928Y312645D01*
X741595Y312687D01*
X741262Y312603D01*
X741053Y312395D01*
X740887Y312103D01*
X740845Y311812D01*
X740887Y311520D01*
X741053Y311145D01*
X739970Y311270D01*
Y312395D01*
G01X749470Y305320D02*
X753470D01*
Y312720D01*
G01X737317Y318200D02*
Y320700D01*
X738358D01*
X738692Y320575D01*
X738900Y320408D01*
X738983Y320075D01*
X738900Y319742D01*
X738650Y319533D01*
X738358Y319408D01*
X737317D01*
G01X738358D02*
X738983Y318200D01*
G01X740333Y318700D02*
X740583Y318408D01*
X740917Y318242D01*
X741292Y318200D01*
X741625Y318242D01*
X741958Y318450D01*
X742167Y318700D01*
X742208Y318950D01*
X742125Y319242D01*
X741833Y319450D01*
X741542Y319533D01*
X741167D01*
G01X741542D02*
X741792Y319658D01*
X742000Y319867D01*
X742083Y320117D01*
X742000Y320367D01*
X741792Y320575D01*
X741417Y320700D01*
X741042Y320658D01*
X740667Y320492D01*
G01X743558Y319242D02*
X743850Y319533D01*
X744100Y319700D01*
X744433Y319783D01*
X744725Y319700D01*
X744933Y319533D01*
X745100Y319283D01*
X745142Y318992D01*
X745100Y318742D01*
X744933Y318492D01*
X744683Y318283D01*
X744392Y318200D01*
X744058Y318283D01*
X743767Y318533D01*
X743600Y318908D01*
X743558Y319325D01*
X743642Y319867D01*
X743767Y320158D01*
X743975Y320450D01*
X744267Y320658D01*
X744558Y320700D01*
X744850Y320617D01*
X745058Y320408D01*
G01X747450Y318200D02*
X747742Y318242D01*
X748075Y318367D01*
X748283Y318575D01*
X748367Y318867D01*
X748283Y319158D01*
X748033Y319408D01*
X747658Y319533D01*
X747242D01*
X746992Y319617D01*
X746783Y319825D01*
X746700Y320117D01*
X746825Y320408D01*
X747117Y320617D01*
X747450Y320700D01*
X747783Y320617D01*
X748075Y320408D01*
X748200Y320117D01*
X748117Y319825D01*
X747908Y319617D01*
X747658Y319533D01*
X747242D01*
X746867Y319408D01*
X746617Y319158D01*
X746533Y318867D01*
X746617Y318575D01*
X746825Y318367D01*
X747158Y318242D01*
X747450Y318200D01*
G01X752183Y323684D02*
Y319684D01*
X759583D01*
G01X737417Y314100D02*
Y316600D01*
X738458D01*
X738792Y316475D01*
X739000Y316308D01*
X739083Y315975D01*
X739000Y315642D01*
X738750Y315433D01*
X738458Y315308D01*
X737417D01*
G01X738458D02*
X739083Y314100D01*
G01X740433Y314600D02*
X740683Y314308D01*
X741017Y314142D01*
X741392Y314100D01*
X741725Y314142D01*
X742058Y314350D01*
X742267Y314600D01*
X742308Y314850D01*
X742225Y315142D01*
X741933Y315350D01*
X741642Y315433D01*
X741267D01*
G01X741642D02*
X741892Y315558D01*
X742100Y315767D01*
X742183Y316017D01*
X742100Y316267D01*
X741892Y316475D01*
X741517Y316600D01*
X741142Y316558D01*
X740767Y316392D01*
G01X743658Y315142D02*
X743950Y315433D01*
X744200Y315600D01*
X744533Y315683D01*
X744825Y315600D01*
X745033Y315433D01*
X745200Y315183D01*
X745242Y314892D01*
X745200Y314642D01*
X745033Y314392D01*
X744783Y314183D01*
X744492Y314100D01*
X744158Y314183D01*
X743867Y314433D01*
X743700Y314808D01*
X743658Y315225D01*
X743742Y315767D01*
X743867Y316058D01*
X744075Y316350D01*
X744367Y316558D01*
X744658Y316600D01*
X744950Y316517D01*
X745158Y316308D01*
G01X746842Y314392D02*
X747133Y314183D01*
X747467Y314100D01*
X747800Y314183D01*
X748092Y314433D01*
X748300Y314808D01*
X748383Y315183D01*
Y315642D01*
X748300Y316017D01*
X748092Y316350D01*
X747842Y316517D01*
X747550Y316600D01*
X747217Y316517D01*
X746967Y316350D01*
X746800Y316100D01*
X746717Y315767D01*
X746800Y315475D01*
X747008Y315183D01*
X747258Y315017D01*
X747550Y314975D01*
X747883Y315058D01*
X748133Y315267D01*
X748383Y315642D01*
G01X759583Y315184D02*
Y319184D01*
X752183D01*
G01X712334Y306517D02*
X709834D01*
Y307558D01*
X709959Y307892D01*
X710126Y308100D01*
X710459Y308183D01*
X710792Y308100D01*
X711001Y307850D01*
X711126Y307558D01*
Y306517D01*
G01Y307558D02*
X712334Y308183D01*
G01X710251Y309658D02*
X710001Y309908D01*
X709876Y310200D01*
X709834Y310533D01*
X709917Y310950D01*
X710126Y311242D01*
X710376Y311325D01*
X710626Y311283D01*
X710834Y311117D01*
X711251Y310283D01*
X711542Y309908D01*
X711959Y309658D01*
X712334Y309575D01*
Y311325D01*
G01Y313550D02*
X712292Y313842D01*
X712167Y314175D01*
X711959Y314383D01*
X711667Y314467D01*
X711376Y314383D01*
X711126Y314133D01*
X711001Y313758D01*
Y313342D01*
X710917Y313092D01*
X710709Y312883D01*
X710417Y312800D01*
X710126Y312925D01*
X709917Y313217D01*
X709834Y313550D01*
X709917Y313883D01*
X710126Y314175D01*
X710417Y314300D01*
X710709Y314217D01*
X710917Y314008D01*
X711001Y313758D01*
Y313342D01*
X711126Y312967D01*
X711376Y312717D01*
X711667Y312633D01*
X711959Y312717D01*
X712167Y312925D01*
X712292Y313258D01*
X712334Y313550D01*
G01Y317150D02*
X709834D01*
X711626Y315608D01*
Y317692D01*
G01X714334Y306567D02*
X716834D01*
Y308233D01*
G01X714751Y309708D02*
X714501Y309958D01*
X714376Y310250D01*
X714334Y310583D01*
X714417Y311000D01*
X714626Y311292D01*
X714876Y311375D01*
X715126Y311333D01*
X715334Y311167D01*
X715751Y310333D01*
X716042Y309958D01*
X716459Y309708D01*
X716834Y309625D01*
Y311375D01*
G01X715792Y312808D02*
X715501Y313100D01*
X715334Y313350D01*
X715251Y313683D01*
X715334Y313975D01*
X715501Y314183D01*
X715751Y314350D01*
X716042Y314392D01*
X716292Y314350D01*
X716542Y314183D01*
X716751Y313933D01*
X716834Y313642D01*
X716751Y313308D01*
X716501Y313017D01*
X716126Y312850D01*
X715709Y312808D01*
X715167Y312892D01*
X714876Y313017D01*
X714584Y313225D01*
X714376Y313517D01*
X714334Y313808D01*
X714417Y314100D01*
X714626Y314308D01*
G01X718542Y308267D02*
X718417Y308017D01*
X718334Y307725D01*
Y307392D01*
X718459Y307017D01*
X718667Y306725D01*
X718917Y306517D01*
X719334Y306350D01*
X719709Y306308D01*
X720084Y306392D01*
X720334Y306517D01*
X720584Y306767D01*
X720751Y307058D01*
X720834Y307350D01*
Y307642D01*
X720751Y307933D01*
X720626Y308183D01*
X720459Y308392D01*
G01X719792Y309658D02*
X719501Y309950D01*
X719334Y310200D01*
X719251Y310533D01*
X719334Y310825D01*
X719501Y311033D01*
X719751Y311200D01*
X720042Y311242D01*
X720292Y311200D01*
X720542Y311033D01*
X720751Y310783D01*
X720834Y310492D01*
X720751Y310158D01*
X720501Y309867D01*
X720126Y309700D01*
X719709Y309658D01*
X719167Y309742D01*
X718876Y309867D01*
X718584Y310075D01*
X718376Y310367D01*
X718334Y310658D01*
X718417Y310950D01*
X718626Y311158D01*
G01X720334Y312633D02*
X720626Y312883D01*
X720792Y313217D01*
X720834Y313592D01*
X720792Y313925D01*
X720584Y314258D01*
X720334Y314467D01*
X720084Y314508D01*
X719792Y314425D01*
X719584Y314133D01*
X719501Y313842D01*
Y313467D01*
G01Y313842D02*
X719376Y314092D01*
X719167Y314300D01*
X718917Y314383D01*
X718667Y314300D01*
X718459Y314092D01*
X718334Y313717D01*
X718376Y313342D01*
X718542Y312967D01*
G01X718334Y316650D02*
X718417Y316317D01*
X718626Y316067D01*
X718876Y315900D01*
X719209Y315775D01*
X719584Y315733D01*
X719959Y315775D01*
X720292Y315900D01*
X720542Y316067D01*
X720751Y316317D01*
X720834Y316650D01*
X720751Y316983D01*
X720542Y317233D01*
X720292Y317400D01*
X719959Y317525D01*
X719584Y317567D01*
X719209Y317525D01*
X718876Y317400D01*
X718626Y317233D01*
X718417Y316983D01*
X718334Y316650D01*
G01X723042Y308267D02*
X722917Y308017D01*
X722834Y307725D01*
Y307392D01*
X722959Y307017D01*
X723167Y306725D01*
X723417Y306517D01*
X723834Y306350D01*
X724209Y306308D01*
X724584Y306392D01*
X724834Y306517D01*
X725084Y306767D01*
X725251Y307058D01*
X725334Y307350D01*
Y307642D01*
X725251Y307933D01*
X725126Y308183D01*
X724959Y308392D01*
G01X724292Y309658D02*
X724001Y309950D01*
X723834Y310200D01*
X723751Y310533D01*
X723834Y310825D01*
X724001Y311033D01*
X724251Y311200D01*
X724542Y311242D01*
X724792Y311200D01*
X725042Y311033D01*
X725251Y310783D01*
X725334Y310492D01*
X725251Y310158D01*
X725001Y309867D01*
X724626Y309700D01*
X724209Y309658D01*
X723667Y309742D01*
X723376Y309867D01*
X723084Y310075D01*
X722876Y310367D01*
X722834Y310658D01*
X722917Y310950D01*
X723126Y311158D01*
G01X723251Y312758D02*
X723001Y313008D01*
X722876Y313300D01*
X722834Y313633D01*
X722917Y314050D01*
X723126Y314342D01*
X723376Y314425D01*
X723626Y314383D01*
X723834Y314217D01*
X724251Y313383D01*
X724542Y313008D01*
X724959Y312758D01*
X725334Y312675D01*
Y314425D01*
G01Y316567D02*
X724792Y316650D01*
X724334Y316775D01*
X723917Y316942D01*
X723459Y317150D01*
X722834Y317483D01*
Y315817D01*
G01X699100Y317200D02*
Y309200D01*
G01X749893Y354842D02*
X752393D01*
G01X749893Y353884D02*
Y355800D01*
G01X750101Y358859D02*
X749976Y358609D01*
X749893Y358317D01*
Y357984D01*
X750018Y357609D01*
X750226Y357317D01*
X750476Y357109D01*
X750893Y356942D01*
X751268Y356900D01*
X751643Y356984D01*
X751893Y357109D01*
X752143Y357359D01*
X752310Y357650D01*
X752393Y357942D01*
Y358234D01*
X752310Y358525D01*
X752185Y358775D01*
X752018Y358984D01*
G01X751351Y360250D02*
X751060Y360542D01*
X750893Y360792D01*
X750810Y361125D01*
X750893Y361417D01*
X751060Y361625D01*
X751310Y361792D01*
X751601Y361834D01*
X751851Y361792D01*
X752101Y361625D01*
X752310Y361375D01*
X752393Y361084D01*
X752310Y360750D01*
X752060Y360459D01*
X751685Y360292D01*
X751268Y360250D01*
X750726Y360334D01*
X750435Y360459D01*
X750143Y360667D01*
X749935Y360959D01*
X749893Y361250D01*
X749976Y361542D01*
X750185Y361750D01*
G01X709693Y346942D02*
X720893D01*
G01X709693Y364942D02*
Y346942D01*
G01X748093D02*
X736893D01*
G01X748093Y364942D02*
Y346942D01*
G01X749893Y327292D02*
X752393D01*
G01X749893Y326334D02*
Y328250D01*
G01X750101Y331309D02*
X749976Y331059D01*
X749893Y330767D01*
Y330434D01*
X750018Y330059D01*
X750226Y329767D01*
X750476Y329559D01*
X750893Y329392D01*
X751268Y329350D01*
X751643Y329434D01*
X751893Y329559D01*
X752143Y329809D01*
X752310Y330100D01*
X752393Y330392D01*
Y330684D01*
X752310Y330975D01*
X752185Y331225D01*
X752018Y331434D01*
G01X752393Y333409D02*
X751851Y333492D01*
X751393Y333617D01*
X750976Y333784D01*
X750518Y333992D01*
X749893Y334325D01*
Y332659D01*
G01X709693Y321892D02*
X720893D01*
G01X709693Y339892D02*
Y321892D01*
G01X720893Y339892D02*
X709693D01*
G01X748093Y321892D02*
X736893D01*
G01X748093Y339892D02*
Y321892D01*
G01X736893Y339892D02*
X748093D01*
G01X797520Y357100D02*
X755520D01*
Y331500D01*
X797520D01*
Y357100D01*
G01X733117Y420500D02*
Y423000D01*
X734158D01*
X734492Y422875D01*
X734700Y422708D01*
X734783Y422375D01*
X734700Y422042D01*
X734450Y421833D01*
X734158Y421708D01*
X733117D01*
G01X734158D02*
X734783Y420500D01*
G01X737050D02*
X737342Y420542D01*
X737675Y420667D01*
X737883Y420875D01*
X737967Y421167D01*
X737883Y421458D01*
X737633Y421708D01*
X737258Y421833D01*
X736842D01*
X736592Y421917D01*
X736383Y422125D01*
X736300Y422417D01*
X736425Y422708D01*
X736717Y422917D01*
X737050Y423000D01*
X737383Y422917D01*
X737675Y422708D01*
X737800Y422417D01*
X737717Y422125D01*
X737508Y421917D01*
X737258Y421833D01*
X736842D01*
X736467Y421708D01*
X736217Y421458D01*
X736133Y421167D01*
X736217Y420875D01*
X736425Y420667D01*
X736758Y420542D01*
X737050Y420500D01*
G01X730670Y421930D02*
Y425930D01*
X723270D01*
G01X709500Y373967D02*
X707000D01*
Y375008D01*
X707125Y375342D01*
X707292Y375550D01*
X707625Y375633D01*
X707958Y375550D01*
X708167Y375300D01*
X708292Y375008D01*
Y373967D01*
G01Y375008D02*
X709500Y375633D01*
G01Y378400D02*
X707000D01*
X708792Y376858D01*
Y378942D01*
G01X709208Y380292D02*
X709417Y380583D01*
X709500Y380917D01*
X709417Y381250D01*
X709167Y381542D01*
X708792Y381750D01*
X708417Y381833D01*
X707958D01*
X707583Y381750D01*
X707250Y381542D01*
X707083Y381292D01*
X707000Y381000D01*
X707083Y380667D01*
X707250Y380417D01*
X707500Y380250D01*
X707833Y380167D01*
X708125Y380250D01*
X708417Y380458D01*
X708583Y380708D01*
X708625Y381000D01*
X708542Y381333D01*
X708333Y381583D01*
X707958Y381833D01*
G01X707000Y384100D02*
X707083Y383767D01*
X707292Y383517D01*
X707542Y383350D01*
X707875Y383225D01*
X708250Y383183D01*
X708625Y383225D01*
X708958Y383350D01*
X709208Y383517D01*
X709417Y383767D01*
X709500Y384100D01*
X709417Y384433D01*
X709208Y384683D01*
X708958Y384850D01*
X708625Y384975D01*
X708250Y385017D01*
X707875Y384975D01*
X707542Y384850D01*
X707292Y384683D01*
X707083Y384433D01*
X707000Y384100D01*
G01X702200Y396700D02*
X698200D01*
Y389300D01*
G01X713000Y374017D02*
X710500D01*
Y375058D01*
X710625Y375392D01*
X710792Y375600D01*
X711125Y375683D01*
X711458Y375600D01*
X711667Y375350D01*
X711792Y375058D01*
Y374017D01*
G01Y375058D02*
X713000Y375683D01*
G01Y378450D02*
X710500D01*
X712292Y376908D01*
Y378992D01*
G01X713000Y381050D02*
X712958Y381342D01*
X712833Y381675D01*
X712625Y381883D01*
X712333Y381967D01*
X712042Y381883D01*
X711792Y381633D01*
X711667Y381258D01*
Y380842D01*
X711583Y380592D01*
X711375Y380383D01*
X711083Y380300D01*
X710792Y380425D01*
X710583Y380717D01*
X710500Y381050D01*
X710583Y381383D01*
X710792Y381675D01*
X711083Y381800D01*
X711375Y381717D01*
X711583Y381508D01*
X711667Y381258D01*
Y380842D01*
X711792Y380467D01*
X712042Y380217D01*
X712333Y380133D01*
X712625Y380217D01*
X712833Y380425D01*
X712958Y380758D01*
X713000Y381050D01*
G01X712708Y383442D02*
X712917Y383733D01*
X713000Y384067D01*
X712917Y384400D01*
X712667Y384692D01*
X712292Y384900D01*
X711917Y384983D01*
X711458D01*
X711083Y384900D01*
X710750Y384692D01*
X710583Y384442D01*
X710500Y384150D01*
X710583Y383817D01*
X710750Y383567D01*
X711000Y383400D01*
X711333Y383317D01*
X711625Y383400D01*
X711917Y383608D01*
X712083Y383858D01*
X712125Y384150D01*
X712042Y384483D01*
X711833Y384733D01*
X711458Y384983D01*
G01X698200Y376300D02*
X702200D01*
Y383700D01*
G01X703708Y375767D02*
X703583Y375517D01*
X703500Y375225D01*
Y374892D01*
X703625Y374517D01*
X703833Y374225D01*
X704083Y374017D01*
X704500Y373850D01*
X704875Y373808D01*
X705250Y373892D01*
X705500Y374017D01*
X705750Y374267D01*
X705917Y374558D01*
X706000Y374850D01*
Y375142D01*
X705917Y375433D01*
X705792Y375683D01*
X705625Y375892D01*
G01X704958Y377158D02*
X704667Y377450D01*
X704500Y377700D01*
X704417Y378033D01*
X704500Y378325D01*
X704667Y378533D01*
X704917Y378700D01*
X705208Y378742D01*
X705458Y378700D01*
X705708Y378533D01*
X705917Y378283D01*
X706000Y377992D01*
X705917Y377658D01*
X705667Y377367D01*
X705292Y377200D01*
X704875Y377158D01*
X704333Y377242D01*
X704042Y377367D01*
X703750Y377575D01*
X703542Y377867D01*
X703500Y378158D01*
X703583Y378450D01*
X703792Y378658D01*
G01X704958Y380258D02*
X704667Y380550D01*
X704500Y380800D01*
X704417Y381133D01*
X704500Y381425D01*
X704667Y381633D01*
X704917Y381800D01*
X705208Y381842D01*
X705458Y381800D01*
X705708Y381633D01*
X705917Y381383D01*
X706000Y381092D01*
X705917Y380758D01*
X705667Y380467D01*
X705292Y380300D01*
X704875Y380258D01*
X704333Y380342D01*
X704042Y380467D01*
X703750Y380675D01*
X703542Y380967D01*
X703500Y381258D01*
X703583Y381550D01*
X703792Y381758D01*
G01X706000Y384150D02*
X703500D01*
X704000Y383650D01*
G01X706000D02*
Y384650D01*
G01X715833Y418400D02*
X715791Y418067D01*
X715625Y417775D01*
X715375Y417525D01*
X715083Y417358D01*
X714750Y417275D01*
X714416D01*
X714083Y417358D01*
X713791Y417525D01*
X713541Y417775D01*
X713375Y418067D01*
X713333Y418400D01*
X713375Y418733D01*
X713541Y419025D01*
X713791Y419275D01*
X714083Y419442D01*
X714416Y419525D01*
X714750D01*
X715083Y419442D01*
X715375Y419275D01*
X715625Y419025D01*
X715791Y418733D01*
X715833Y418400D01*
G01X715166Y418733D02*
X715833Y419233D01*
G01X713750Y420708D02*
X713500Y420958D01*
X713375Y421250D01*
X713333Y421583D01*
X713416Y422000D01*
X713625Y422292D01*
X713875Y422375D01*
X714125Y422333D01*
X714333Y422167D01*
X714750Y421333D01*
X715041Y420958D01*
X715458Y420708D01*
X715833Y420625D01*
Y422375D01*
G01X713750Y423808D02*
X713500Y424058D01*
X713375Y424350D01*
X713333Y424683D01*
X713416Y425100D01*
X713625Y425392D01*
X713875Y425475D01*
X714125Y425433D01*
X714333Y425267D01*
X714750Y424433D01*
X715041Y424058D01*
X715458Y423808D01*
X715833Y423725D01*
Y425475D01*
G01X698700Y431360D02*
Y417360D01*
G01X711700D02*
Y431360D01*
G01X698700Y417360D02*
X711700D01*
G01X701350Y409150D02*
X701308Y408817D01*
X701142Y408525D01*
X700892Y408275D01*
X700600Y408108D01*
X700267Y408025D01*
X699933D01*
X699600Y408108D01*
X699308Y408275D01*
X699058Y408525D01*
X698892Y408817D01*
X698850Y409150D01*
X698892Y409483D01*
X699058Y409775D01*
X699308Y410025D01*
X699600Y410192D01*
X699933Y410275D01*
X700267D01*
X700600Y410192D01*
X700892Y410025D01*
X701142Y409775D01*
X701308Y409483D01*
X701350Y409150D01*
G01X700683Y409483D02*
X701350Y409983D01*
G01Y412250D02*
X698850D01*
X699350Y411750D01*
G01X701350D02*
Y412750D01*
G01Y415350D02*
X698850D01*
X699350Y414850D01*
G01X701350D02*
Y415850D01*
G01X697390Y408270D02*
Y422270D01*
G01X723000Y373517D02*
X720500D01*
Y374558D01*
X720625Y374892D01*
X720792Y375100D01*
X721125Y375183D01*
X721458Y375100D01*
X721667Y374850D01*
X721792Y374558D01*
Y373517D01*
G01Y374558D02*
X723000Y375183D01*
G01X720917Y376658D02*
X720667Y376908D01*
X720542Y377200D01*
X720500Y377533D01*
X720583Y377950D01*
X720792Y378242D01*
X721042Y378325D01*
X721292Y378283D01*
X721500Y378117D01*
X721917Y377283D01*
X722208Y376908D01*
X722625Y376658D01*
X723000Y376575D01*
Y378325D01*
G01Y380550D02*
X722958Y380842D01*
X722833Y381175D01*
X722625Y381383D01*
X722333Y381467D01*
X722042Y381383D01*
X721792Y381133D01*
X721667Y380758D01*
Y380342D01*
X721583Y380092D01*
X721375Y379883D01*
X721083Y379800D01*
X720792Y379925D01*
X720583Y380217D01*
X720500Y380550D01*
X720583Y380883D01*
X720792Y381175D01*
X721083Y381300D01*
X721375Y381217D01*
X721583Y381008D01*
X721667Y380758D01*
Y380342D01*
X721792Y379967D01*
X722042Y379717D01*
X722333Y379633D01*
X722625Y379717D01*
X722833Y379925D01*
X722958Y380258D01*
X723000Y380550D01*
G01X722625Y382733D02*
X722833Y382983D01*
X722958Y383275D01*
X723000Y383650D01*
X722917Y384025D01*
X722750Y384317D01*
X722458Y384525D01*
X722125Y384567D01*
X721792Y384483D01*
X721583Y384275D01*
X721417Y383983D01*
X721375Y383692D01*
X721417Y383400D01*
X721583Y383025D01*
X720500Y383150D01*
Y384275D01*
G01X720267Y419792D02*
X720017Y419917D01*
X719725Y420000D01*
X719392D01*
X719017Y419875D01*
X718725Y419667D01*
X718517Y419417D01*
X718350Y419000D01*
X718308Y418625D01*
X718392Y418250D01*
X718517Y418000D01*
X718767Y417750D01*
X719058Y417583D01*
X719350Y417500D01*
X719642D01*
X719933Y417583D01*
X720183Y417708D01*
X720392Y417875D01*
G01X721533Y418000D02*
X721783Y417708D01*
X722117Y417542D01*
X722492Y417500D01*
X722825Y417542D01*
X723158Y417750D01*
X723367Y418000D01*
X723408Y418250D01*
X723325Y418542D01*
X723033Y418750D01*
X722742Y418833D01*
X722367D01*
G01X722742D02*
X722992Y418958D01*
X723200Y419167D01*
X723283Y419417D01*
X723200Y419667D01*
X722992Y419875D01*
X722617Y420000D01*
X722242Y419958D01*
X721867Y419792D01*
G01X724842Y417792D02*
X725133Y417583D01*
X725467Y417500D01*
X725800Y417583D01*
X726092Y417833D01*
X726300Y418208D01*
X726383Y418583D01*
Y419042D01*
X726300Y419417D01*
X726092Y419750D01*
X725842Y419917D01*
X725550Y420000D01*
X725217Y419917D01*
X724967Y419750D01*
X724800Y419500D01*
X724717Y419167D01*
X724800Y418875D01*
X725008Y418583D01*
X725258Y418417D01*
X725550Y418375D01*
X725883Y418458D01*
X726133Y418667D01*
X726383Y419042D01*
G01X727733Y417875D02*
X727983Y417667D01*
X728275Y417542D01*
X728650Y417500D01*
X729025Y417583D01*
X729317Y417750D01*
X729525Y418042D01*
X729567Y418375D01*
X729483Y418708D01*
X729275Y418917D01*
X728983Y419083D01*
X728692Y419125D01*
X728400Y419083D01*
X728025Y418917D01*
X728150Y420000D01*
X729275D01*
G01X706083Y416014D02*
X711583D01*
G01X706083Y408014D02*
Y416014D01*
G01X711583Y408014D02*
X706083D01*
G01X723683D02*
X718183D01*
G01X723683Y416014D02*
Y408014D01*
G01X718183Y416014D02*
X723683D01*
G01X714767Y397792D02*
X714517Y397917D01*
X714225Y398000D01*
X713892D01*
X713517Y397875D01*
X713225Y397667D01*
X713017Y397417D01*
X712850Y397000D01*
X712808Y396625D01*
X712892Y396250D01*
X713017Y396000D01*
X713267Y395750D01*
X713558Y395583D01*
X713850Y395500D01*
X714142D01*
X714433Y395583D01*
X714683Y395708D01*
X714892Y395875D01*
G01X716033Y396000D02*
X716283Y395708D01*
X716617Y395542D01*
X716992Y395500D01*
X717325Y395542D01*
X717658Y395750D01*
X717867Y396000D01*
X717908Y396250D01*
X717825Y396542D01*
X717533Y396750D01*
X717242Y396833D01*
X716867D01*
G01X717242D02*
X717492Y396958D01*
X717700Y397167D01*
X717783Y397417D01*
X717700Y397667D01*
X717492Y397875D01*
X717117Y398000D01*
X716742Y397958D01*
X716367Y397792D01*
G01X719342Y395792D02*
X719633Y395583D01*
X719967Y395500D01*
X720300Y395583D01*
X720592Y395833D01*
X720800Y396208D01*
X720883Y396583D01*
Y397042D01*
X720800Y397417D01*
X720592Y397750D01*
X720342Y397917D01*
X720050Y398000D01*
X719717Y397917D01*
X719467Y397750D01*
X719300Y397500D01*
X719217Y397167D01*
X719300Y396875D01*
X719508Y396583D01*
X719758Y396417D01*
X720050Y396375D01*
X720383Y396458D01*
X720633Y396667D01*
X720883Y397042D01*
G01X723650Y395500D02*
Y398000D01*
X722108Y396208D01*
X724192D01*
G01X706083Y407014D02*
X711583D01*
G01X706083Y399014D02*
Y407014D01*
G01X711583Y399014D02*
X706083D01*
G01X723683D02*
X718183D01*
G01X723683Y407014D02*
Y399014D01*
G01X718183Y407014D02*
X723683D01*
G01X747500Y407567D02*
X750000D01*
Y409233D01*
G01X747917Y410708D02*
X747667Y410958D01*
X747542Y411250D01*
X747500Y411583D01*
X747583Y412000D01*
X747792Y412292D01*
X748042Y412375D01*
X748292Y412333D01*
X748500Y412167D01*
X748917Y411333D01*
X749208Y410958D01*
X749625Y410708D01*
X750000Y410625D01*
Y412375D01*
G01Y414517D02*
X749458Y414600D01*
X749000Y414725D01*
X748583Y414892D01*
X748125Y415100D01*
X747500Y415433D01*
Y413767D01*
G01X745512Y416015D02*
X725512D01*
Y371415D01*
X745512D01*
Y416015D01*
G01X720893Y364942D02*
X709693D01*
G01X736893D02*
X748093D01*
G01X730042Y449367D02*
Y445367D01*
X737442D01*
G01X751937Y443200D02*
Y445700D01*
X752978D01*
X753312Y445575D01*
X753520Y445408D01*
X753603Y445075D01*
X753520Y444742D01*
X753270Y444533D01*
X752978Y444408D01*
X751937D01*
G01X752978D02*
X753603Y443200D01*
G01X755078Y444242D02*
X755370Y444533D01*
X755620Y444700D01*
X755953Y444783D01*
X756245Y444700D01*
X756453Y444533D01*
X756620Y444283D01*
X756662Y443992D01*
X756620Y443742D01*
X756453Y443492D01*
X756203Y443283D01*
X755912Y443200D01*
X755578Y443283D01*
X755287Y443533D01*
X755120Y443908D01*
X755078Y444325D01*
X755162Y444867D01*
X755287Y445158D01*
X755495Y445450D01*
X755787Y445658D01*
X756078Y445700D01*
X756370Y445617D01*
X756578Y445408D01*
G01X758970Y445700D02*
X758637Y445617D01*
X758387Y445408D01*
X758220Y445158D01*
X758095Y444825D01*
X758053Y444450D01*
X758095Y444075D01*
X758220Y443742D01*
X758387Y443492D01*
X758637Y443283D01*
X758970Y443200D01*
X759303Y443283D01*
X759553Y443492D01*
X759720Y443742D01*
X759845Y444075D01*
X759887Y444450D01*
X759845Y444825D01*
X759720Y445158D01*
X759553Y445408D01*
X759303Y445617D01*
X758970Y445700D01*
G01X761278Y444242D02*
X761570Y444533D01*
X761820Y444700D01*
X762153Y444783D01*
X762445Y444700D01*
X762653Y444533D01*
X762820Y444283D01*
X762862Y443992D01*
X762820Y443742D01*
X762653Y443492D01*
X762403Y443283D01*
X762112Y443200D01*
X761778Y443283D01*
X761487Y443533D01*
X761320Y443908D01*
X761278Y444325D01*
X761362Y444867D01*
X761487Y445158D01*
X761695Y445450D01*
X761987Y445658D01*
X762278Y445700D01*
X762570Y445617D01*
X762778Y445408D01*
G01X722390Y449430D02*
Y445430D01*
X729790D01*
G01X757000Y430017D02*
X754500D01*
Y431058D01*
X754625Y431392D01*
X754792Y431600D01*
X755125Y431683D01*
X755458Y431600D01*
X755667Y431350D01*
X755792Y431058D01*
Y430017D01*
G01Y431058D02*
X757000Y431683D01*
G01X755958Y433158D02*
X755667Y433450D01*
X755500Y433700D01*
X755417Y434033D01*
X755500Y434325D01*
X755667Y434533D01*
X755917Y434700D01*
X756208Y434742D01*
X756458Y434700D01*
X756708Y434533D01*
X756917Y434283D01*
X757000Y433992D01*
X756917Y433658D01*
X756667Y433367D01*
X756292Y433200D01*
X755875Y433158D01*
X755333Y433242D01*
X755042Y433367D01*
X754750Y433575D01*
X754542Y433867D01*
X754500Y434158D01*
X754583Y434450D01*
X754792Y434658D01*
G01X754500Y437050D02*
X754583Y436717D01*
X754792Y436467D01*
X755042Y436300D01*
X755375Y436175D01*
X755750Y436133D01*
X756125Y436175D01*
X756458Y436300D01*
X756708Y436467D01*
X756917Y436717D01*
X757000Y437050D01*
X756917Y437383D01*
X756708Y437633D01*
X756458Y437800D01*
X756125Y437925D01*
X755750Y437967D01*
X755375Y437925D01*
X755042Y437800D01*
X754792Y437633D01*
X754583Y437383D01*
X754500Y437050D01*
G01X757000Y440650D02*
X754500D01*
X756292Y439108D01*
Y441192D01*
G01X712200Y439930D02*
X708200D01*
Y432530D01*
G01X745117Y474500D02*
Y477000D01*
X746158D01*
X746492Y476875D01*
X746700Y476708D01*
X746783Y476375D01*
X746700Y476042D01*
X746450Y475833D01*
X746158Y475708D01*
X745117D01*
G01X746158D02*
X746783Y474500D01*
G01X748342Y474792D02*
X748633Y474583D01*
X748967Y474500D01*
X749300Y474583D01*
X749592Y474833D01*
X749800Y475208D01*
X749883Y475583D01*
Y476042D01*
X749800Y476417D01*
X749592Y476750D01*
X749342Y476917D01*
X749050Y477000D01*
X748717Y476917D01*
X748467Y476750D01*
X748300Y476500D01*
X748217Y476167D01*
X748300Y475875D01*
X748508Y475583D01*
X748758Y475417D01*
X749050Y475375D01*
X749383Y475458D01*
X749633Y475667D01*
X749883Y476042D01*
G01X733600Y473400D02*
Y477400D01*
X726200D01*
G01X742067Y443500D02*
Y446000D01*
X743108D01*
X743442Y445875D01*
X743650Y445708D01*
X743733Y445375D01*
X743650Y445042D01*
X743400Y444833D01*
X743108Y444708D01*
X742067D01*
G01X743108D02*
X743733Y443500D01*
G01X745292Y443792D02*
X745583Y443583D01*
X745917Y443500D01*
X746250Y443583D01*
X746542Y443833D01*
X746750Y444208D01*
X746833Y444583D01*
Y445042D01*
X746750Y445417D01*
X746542Y445750D01*
X746292Y445917D01*
X746000Y446000D01*
X745667Y445917D01*
X745417Y445750D01*
X745250Y445500D01*
X745167Y445167D01*
X745250Y444875D01*
X745458Y444583D01*
X745708Y444417D01*
X746000Y444375D01*
X746333Y444458D01*
X746583Y444667D01*
X746833Y445042D01*
G01X749100Y443500D02*
X749392Y443542D01*
X749725Y443667D01*
X749933Y443875D01*
X750017Y444167D01*
X749933Y444458D01*
X749683Y444708D01*
X749308Y444833D01*
X748892D01*
X748642Y444917D01*
X748433Y445125D01*
X748350Y445417D01*
X748475Y445708D01*
X748767Y445917D01*
X749100Y446000D01*
X749433Y445917D01*
X749725Y445708D01*
X749850Y445417D01*
X749767Y445125D01*
X749558Y444917D01*
X749308Y444833D01*
X748892D01*
X748517Y444708D01*
X748267Y444458D01*
X748183Y444167D01*
X748267Y443875D01*
X748475Y443667D01*
X748808Y443542D01*
X749100Y443500D01*
G01X712650Y448230D02*
Y444230D01*
X720050D01*
G01X750000Y447412D02*
X747500D01*
Y448453D01*
X747625Y448787D01*
X747792Y448995D01*
X748125Y449078D01*
X748458Y448995D01*
X748667Y448745D01*
X748792Y448453D01*
Y447412D01*
G01Y448453D02*
X750000Y449078D01*
G01X749708Y450637D02*
X749917Y450928D01*
X750000Y451262D01*
X749917Y451595D01*
X749667Y451887D01*
X749292Y452095D01*
X748917Y452178D01*
X748458D01*
X748083Y452095D01*
X747750Y451887D01*
X747583Y451637D01*
X747500Y451345D01*
X747583Y451012D01*
X747750Y450762D01*
X748000Y450595D01*
X748333Y450512D01*
X748625Y450595D01*
X748917Y450803D01*
X749083Y451053D01*
X749125Y451345D01*
X749042Y451678D01*
X748833Y451928D01*
X748458Y452178D01*
G01X749708Y453737D02*
X749917Y454028D01*
X750000Y454362D01*
X749917Y454695D01*
X749667Y454987D01*
X749292Y455195D01*
X748917Y455278D01*
X748458D01*
X748083Y455195D01*
X747750Y454987D01*
X747583Y454737D01*
X747500Y454445D01*
X747583Y454112D01*
X747750Y453862D01*
X748000Y453695D01*
X748333Y453612D01*
X748625Y453695D01*
X748917Y453903D01*
X749083Y454153D01*
X749125Y454445D01*
X749042Y454778D01*
X748833Y455028D01*
X748458Y455278D01*
G01X719150Y455695D02*
X715150D01*
Y448295D01*
G01X753000Y430017D02*
X750500D01*
Y431058D01*
X750625Y431392D01*
X750792Y431600D01*
X751125Y431683D01*
X751458Y431600D01*
X751667Y431350D01*
X751792Y431058D01*
Y430017D01*
G01Y431058D02*
X753000Y431683D01*
G01X751958Y433158D02*
X751667Y433450D01*
X751500Y433700D01*
X751417Y434033D01*
X751500Y434325D01*
X751667Y434533D01*
X751917Y434700D01*
X752208Y434742D01*
X752458Y434700D01*
X752708Y434533D01*
X752917Y434283D01*
X753000Y433992D01*
X752917Y433658D01*
X752667Y433367D01*
X752292Y433200D01*
X751875Y433158D01*
X751333Y433242D01*
X751042Y433367D01*
X750750Y433575D01*
X750542Y433867D01*
X750500Y434158D01*
X750583Y434450D01*
X750792Y434658D01*
G01X750500Y437050D02*
X750583Y436717D01*
X750792Y436467D01*
X751042Y436300D01*
X751375Y436175D01*
X751750Y436133D01*
X752125Y436175D01*
X752458Y436300D01*
X752708Y436467D01*
X752917Y436717D01*
X753000Y437050D01*
X752917Y437383D01*
X752708Y437633D01*
X752458Y437800D01*
X752125Y437925D01*
X751750Y437967D01*
X751375Y437925D01*
X751042Y437800D01*
X750792Y437633D01*
X750583Y437383D01*
X750500Y437050D01*
G01X752500Y439233D02*
X752792Y439483D01*
X752958Y439817D01*
X753000Y440192D01*
X752958Y440525D01*
X752750Y440858D01*
X752500Y441067D01*
X752250Y441108D01*
X751958Y441025D01*
X751750Y440733D01*
X751667Y440442D01*
Y440067D01*
G01Y440442D02*
X751542Y440692D01*
X751333Y440900D01*
X751083Y440983D01*
X750833Y440900D01*
X750625Y440692D01*
X750500Y440317D01*
X750542Y439942D01*
X750708Y439567D01*
G01X708120Y439930D02*
X704120D01*
Y432530D01*
G01X745480Y437590D02*
X741480D01*
Y430190D01*
G01X746708Y431767D02*
X746583Y431517D01*
X746500Y431225D01*
Y430892D01*
X746625Y430517D01*
X746833Y430225D01*
X747083Y430017D01*
X747500Y429850D01*
X747875Y429808D01*
X748250Y429892D01*
X748500Y430017D01*
X748750Y430267D01*
X748917Y430558D01*
X749000Y430850D01*
Y431142D01*
X748917Y431433D01*
X748792Y431683D01*
X748625Y431892D01*
G01X747958Y433158D02*
X747667Y433450D01*
X747500Y433700D01*
X747417Y434033D01*
X747500Y434325D01*
X747667Y434533D01*
X747917Y434700D01*
X748208Y434742D01*
X748458Y434700D01*
X748708Y434533D01*
X748917Y434283D01*
X749000Y433992D01*
X748917Y433658D01*
X748667Y433367D01*
X748292Y433200D01*
X747875Y433158D01*
X747333Y433242D01*
X747042Y433367D01*
X746750Y433575D01*
X746542Y433867D01*
X746500Y434158D01*
X746583Y434450D01*
X746792Y434658D01*
G01X746500Y437050D02*
X746583Y436717D01*
X746792Y436467D01*
X747042Y436300D01*
X747375Y436175D01*
X747750Y436133D01*
X748125Y436175D01*
X748458Y436300D01*
X748708Y436467D01*
X748917Y436717D01*
X749000Y437050D01*
X748917Y437383D01*
X748708Y437633D01*
X748458Y437800D01*
X748125Y437925D01*
X747750Y437967D01*
X747375Y437925D01*
X747042Y437800D01*
X746792Y437633D01*
X746583Y437383D01*
X746500Y437050D01*
G01X746917Y439358D02*
X746667Y439608D01*
X746542Y439900D01*
X746500Y440233D01*
X746583Y440650D01*
X746792Y440942D01*
X747042Y441025D01*
X747292Y440983D01*
X747500Y440817D01*
X747917Y439983D01*
X748208Y439608D01*
X748625Y439358D01*
X749000Y439275D01*
Y441025D01*
G01X743708Y449112D02*
X743583Y448862D01*
X743500Y448570D01*
Y448237D01*
X743625Y447862D01*
X743833Y447570D01*
X744083Y447362D01*
X744500Y447195D01*
X744875Y447153D01*
X745250Y447237D01*
X745500Y447362D01*
X745750Y447612D01*
X745917Y447903D01*
X746000Y448195D01*
Y448487D01*
X745917Y448778D01*
X745792Y449028D01*
X745625Y449237D01*
G01X744958Y450503D02*
X744667Y450795D01*
X744500Y451045D01*
X744417Y451378D01*
X744500Y451670D01*
X744667Y451878D01*
X744917Y452045D01*
X745208Y452087D01*
X745458Y452045D01*
X745708Y451878D01*
X745917Y451628D01*
X746000Y451337D01*
X745917Y451003D01*
X745667Y450712D01*
X745292Y450545D01*
X744875Y450503D01*
X744333Y450587D01*
X744042Y450712D01*
X743750Y450920D01*
X743542Y451212D01*
X743500Y451503D01*
X743583Y451795D01*
X743792Y452003D01*
G01X743500Y454395D02*
X743583Y454062D01*
X743792Y453812D01*
X744042Y453645D01*
X744375Y453520D01*
X744750Y453478D01*
X745125Y453520D01*
X745458Y453645D01*
X745708Y453812D01*
X745917Y454062D01*
X746000Y454395D01*
X745917Y454728D01*
X745708Y454978D01*
X745458Y455145D01*
X745125Y455270D01*
X744750Y455312D01*
X744375Y455270D01*
X744042Y455145D01*
X743792Y454978D01*
X743583Y454728D01*
X743500Y454395D01*
G01X745625Y456578D02*
X745833Y456828D01*
X745958Y457120D01*
X746000Y457495D01*
X745917Y457870D01*
X745750Y458162D01*
X745458Y458370D01*
X745125Y458412D01*
X744792Y458328D01*
X744583Y458120D01*
X744417Y457828D01*
X744375Y457537D01*
X744417Y457245D01*
X744583Y456870D01*
X743500Y456995D01*
Y458120D01*
G01X746667Y468692D02*
X746417Y468817D01*
X746125Y468900D01*
X745792D01*
X745417Y468775D01*
X745125Y468567D01*
X744917Y468317D01*
X744750Y467900D01*
X744708Y467525D01*
X744792Y467150D01*
X744917Y466900D01*
X745167Y466650D01*
X745458Y466483D01*
X745750Y466400D01*
X746042D01*
X746333Y466483D01*
X746583Y466608D01*
X746792Y466775D01*
G01X748058Y467442D02*
X748350Y467733D01*
X748600Y467900D01*
X748933Y467983D01*
X749225Y467900D01*
X749433Y467733D01*
X749600Y467483D01*
X749642Y467192D01*
X749600Y466942D01*
X749433Y466692D01*
X749183Y466483D01*
X748892Y466400D01*
X748558Y466483D01*
X748267Y466733D01*
X748100Y467108D01*
X748058Y467525D01*
X748142Y468067D01*
X748267Y468358D01*
X748475Y468650D01*
X748767Y468858D01*
X749058Y468900D01*
X749350Y468817D01*
X749558Y468608D01*
G01X751242Y466692D02*
X751533Y466483D01*
X751867Y466400D01*
X752200Y466483D01*
X752492Y466733D01*
X752700Y467108D01*
X752783Y467483D01*
Y467942D01*
X752700Y468317D01*
X752492Y468650D01*
X752242Y468817D01*
X751950Y468900D01*
X751617Y468817D01*
X751367Y468650D01*
X751200Y468400D01*
X751117Y468067D01*
X751200Y467775D01*
X751408Y467483D01*
X751658Y467317D01*
X751950Y467275D01*
X752283Y467358D01*
X752533Y467567D01*
X752783Y467942D01*
G01X754258Y468483D02*
X754508Y468733D01*
X754800Y468858D01*
X755133Y468900D01*
X755550Y468817D01*
X755842Y468608D01*
X755925Y468358D01*
X755883Y468108D01*
X755717Y467900D01*
X754883Y467483D01*
X754508Y467192D01*
X754258Y466775D01*
X754175Y466400D01*
X755925D01*
G01X747267Y427292D02*
X747017Y427417D01*
X746725Y427500D01*
X746392D01*
X746017Y427375D01*
X745725Y427167D01*
X745517Y426917D01*
X745350Y426500D01*
X745308Y426125D01*
X745392Y425750D01*
X745517Y425500D01*
X745767Y425250D01*
X746058Y425083D01*
X746350Y425000D01*
X746642D01*
X746933Y425083D01*
X747183Y425208D01*
X747392Y425375D01*
G01X749367Y425000D02*
X749450Y425542D01*
X749575Y426000D01*
X749742Y426417D01*
X749950Y426875D01*
X750283Y427500D01*
X748617D01*
G01X752550Y425000D02*
Y427500D01*
X752050Y427000D01*
G01Y425000D02*
X753050D01*
G01X754733Y425375D02*
X754983Y425167D01*
X755275Y425042D01*
X755650Y425000D01*
X756025Y425083D01*
X756317Y425250D01*
X756525Y425542D01*
X756567Y425875D01*
X756483Y426208D01*
X756275Y426417D01*
X755983Y426583D01*
X755692Y426625D01*
X755400Y426583D01*
X755025Y426417D01*
X755150Y427500D01*
X756275D01*
G01X727540Y444590D02*
Y430590D01*
G01X740540Y444590D02*
X727540D01*
G01X740540Y430590D02*
Y444590D01*
G01X727540Y430590D02*
X740540D01*
G01X761000Y430900D02*
X760958Y430567D01*
X760792Y430275D01*
X760542Y430025D01*
X760250Y429858D01*
X759917Y429775D01*
X759583D01*
X759250Y429858D01*
X758958Y430025D01*
X758708Y430275D01*
X758542Y430567D01*
X758500Y430900D01*
X758542Y431233D01*
X758708Y431525D01*
X758958Y431775D01*
X759250Y431942D01*
X759583Y432025D01*
X759917D01*
X760250Y431942D01*
X760542Y431775D01*
X760792Y431525D01*
X760958Y431233D01*
X761000Y430900D01*
G01X760333Y431233D02*
X761000Y431733D01*
G01Y434000D02*
X758500D01*
X759000Y433500D01*
G01X761000D02*
Y434500D01*
G01X758917Y436308D02*
X758667Y436558D01*
X758542Y436850D01*
X758500Y437183D01*
X758583Y437600D01*
X758792Y437892D01*
X759042Y437975D01*
X759292Y437933D01*
X759500Y437767D01*
X759917Y436933D01*
X760208Y436558D01*
X760625Y436308D01*
X761000Y436225D01*
Y437975D01*
G01X713350Y440720D02*
Y426720D01*
G01X726350Y440720D02*
X713350D01*
G01X726350Y426720D02*
Y440720D01*
G01X713350Y426720D02*
X726350D01*
G01X711700Y431360D02*
X698700D01*
G01X746667Y472692D02*
X746417Y472817D01*
X746125Y472900D01*
X745792D01*
X745417Y472775D01*
X745125Y472567D01*
X744917Y472317D01*
X744750Y471900D01*
X744708Y471525D01*
X744792Y471150D01*
X744917Y470900D01*
X745167Y470650D01*
X745458Y470483D01*
X745750Y470400D01*
X746042D01*
X746333Y470483D01*
X746583Y470608D01*
X746792Y470775D01*
G01X747933D02*
X748183Y470567D01*
X748475Y470442D01*
X748850Y470400D01*
X749225Y470483D01*
X749517Y470650D01*
X749725Y470942D01*
X749767Y471275D01*
X749683Y471608D01*
X749475Y471817D01*
X749183Y471983D01*
X748892Y472025D01*
X748600Y471983D01*
X748225Y471817D01*
X748350Y472900D01*
X749475D01*
G01X751242Y470692D02*
X751533Y470483D01*
X751867Y470400D01*
X752200Y470483D01*
X752492Y470733D01*
X752700Y471108D01*
X752783Y471483D01*
Y471942D01*
X752700Y472317D01*
X752492Y472650D01*
X752242Y472817D01*
X751950Y472900D01*
X751617Y472817D01*
X751367Y472650D01*
X751200Y472400D01*
X751117Y472067D01*
X751200Y471775D01*
X751408Y471483D01*
X751658Y471317D01*
X751950Y471275D01*
X752283Y471358D01*
X752533Y471567D01*
X752783Y471942D01*
G01X754967Y470400D02*
X755050Y470942D01*
X755175Y471400D01*
X755342Y471817D01*
X755550Y472275D01*
X755883Y472900D01*
X754217D01*
G01X700033Y475000D02*
Y473208D01*
X700200Y472833D01*
X700533Y472583D01*
X700950Y472500D01*
X701367Y472583D01*
X701700Y472833D01*
X701867Y473208D01*
Y475000D01*
G01X704550Y472500D02*
Y475000D01*
X703008Y473208D01*
X705092D01*
G01X703362Y443421D02*
X708362D01*
Y448421D01*
G01X706955Y462389D02*
X709955D01*
G01X699630Y444828D02*
Y442828D01*
G01X705600Y479900D02*
Y486900D01*
G01X699200Y479900D02*
X705600D01*
G01X720167Y512692D02*
X719917Y512817D01*
X719625Y512900D01*
X719292D01*
X718917Y512775D01*
X718625Y512567D01*
X718417Y512317D01*
X718250Y511900D01*
X718208Y511525D01*
X718292Y511150D01*
X718417Y510900D01*
X718667Y510650D01*
X718958Y510483D01*
X719250Y510400D01*
X719542D01*
X719833Y510483D01*
X720083Y510608D01*
X720292Y510775D01*
G01X721433D02*
X721683Y510567D01*
X721975Y510442D01*
X722350Y510400D01*
X722725Y510483D01*
X723017Y510650D01*
X723225Y510942D01*
X723267Y511275D01*
X723183Y511608D01*
X722975Y511817D01*
X722683Y511983D01*
X722392Y512025D01*
X722100Y511983D01*
X721725Y511817D01*
X721850Y512900D01*
X722975D01*
G01X724742Y510692D02*
X725033Y510483D01*
X725367Y510400D01*
X725700Y510483D01*
X725992Y510733D01*
X726200Y511108D01*
X726283Y511483D01*
Y511942D01*
X726200Y512317D01*
X725992Y512650D01*
X725742Y512817D01*
X725450Y512900D01*
X725117Y512817D01*
X724867Y512650D01*
X724700Y512400D01*
X724617Y512067D01*
X724700Y511775D01*
X724908Y511483D01*
X725158Y511317D01*
X725450Y511275D01*
X725783Y511358D01*
X726033Y511567D01*
X726283Y511942D01*
G01X727758Y511442D02*
X728050Y511733D01*
X728300Y511900D01*
X728633Y511983D01*
X728925Y511900D01*
X729133Y511733D01*
X729300Y511483D01*
X729342Y511192D01*
X729300Y510942D01*
X729133Y510692D01*
X728883Y510483D01*
X728592Y510400D01*
X728258Y510483D01*
X727967Y510733D01*
X727800Y511108D01*
X727758Y511525D01*
X727842Y512067D01*
X727967Y512358D01*
X728175Y512650D01*
X728467Y512858D01*
X728758Y512900D01*
X729050Y512817D01*
X729258Y512608D01*
G01X720665Y495521D02*
X720415Y495646D01*
X720123Y495729D01*
X719790D01*
X719415Y495604D01*
X719123Y495396D01*
X718915Y495146D01*
X718748Y494729D01*
X718706Y494354D01*
X718790Y493979D01*
X718915Y493729D01*
X719165Y493479D01*
X719456Y493312D01*
X719748Y493229D01*
X720040D01*
X720331Y493312D01*
X720581Y493437D01*
X720790Y493604D01*
G01X722848Y493229D02*
Y495729D01*
X722348Y495229D01*
G01Y493229D02*
X723348D01*
G01X725948Y495729D02*
X725615Y495646D01*
X725365Y495437D01*
X725198Y495187D01*
X725073Y494854D01*
X725031Y494479D01*
X725073Y494104D01*
X725198Y493771D01*
X725365Y493521D01*
X725615Y493312D01*
X725948Y493229D01*
X726281Y493312D01*
X726531Y493521D01*
X726698Y493771D01*
X726823Y494104D01*
X726865Y494479D01*
X726823Y494854D01*
X726698Y495187D01*
X726531Y495437D01*
X726281Y495646D01*
X725948Y495729D01*
G01X728340Y493521D02*
X728631Y493312D01*
X728965Y493229D01*
X729298Y493312D01*
X729590Y493562D01*
X729798Y493937D01*
X729881Y494312D01*
Y494771D01*
X729798Y495146D01*
X729590Y495479D01*
X729340Y495646D01*
X729048Y495729D01*
X728715Y495646D01*
X728465Y495479D01*
X728298Y495229D01*
X728215Y494896D01*
X728298Y494604D01*
X728506Y494312D01*
X728756Y494146D01*
X729048Y494104D01*
X729381Y494187D01*
X729631Y494396D01*
X729881Y494771D01*
G01X720167Y499692D02*
X719917Y499817D01*
X719625Y499900D01*
X719292D01*
X718917Y499775D01*
X718625Y499567D01*
X718417Y499317D01*
X718250Y498900D01*
X718208Y498525D01*
X718292Y498150D01*
X718417Y497900D01*
X718667Y497650D01*
X718958Y497483D01*
X719250Y497400D01*
X719542D01*
X719833Y497483D01*
X720083Y497608D01*
X720292Y497775D01*
G01X721558Y498442D02*
X721850Y498733D01*
X722100Y498900D01*
X722433Y498983D01*
X722725Y498900D01*
X722933Y498733D01*
X723100Y498483D01*
X723142Y498192D01*
X723100Y497942D01*
X722933Y497692D01*
X722683Y497483D01*
X722392Y497400D01*
X722058Y497483D01*
X721767Y497733D01*
X721600Y498108D01*
X721558Y498525D01*
X721642Y499067D01*
X721767Y499358D01*
X721975Y499650D01*
X722267Y499858D01*
X722558Y499900D01*
X722850Y499817D01*
X723058Y499608D01*
G01X725450Y497400D02*
X725742Y497442D01*
X726075Y497567D01*
X726283Y497775D01*
X726367Y498067D01*
X726283Y498358D01*
X726033Y498608D01*
X725658Y498733D01*
X725242D01*
X724992Y498817D01*
X724783Y499025D01*
X724700Y499317D01*
X724825Y499608D01*
X725117Y499817D01*
X725450Y499900D01*
X725783Y499817D01*
X726075Y499608D01*
X726200Y499317D01*
X726117Y499025D01*
X725908Y498817D01*
X725658Y498733D01*
X725242D01*
X724867Y498608D01*
X724617Y498358D01*
X724533Y498067D01*
X724617Y497775D01*
X724825Y497567D01*
X725158Y497442D01*
X725450Y497400D01*
G01X728550D02*
X728842Y497442D01*
X729175Y497567D01*
X729383Y497775D01*
X729467Y498067D01*
X729383Y498358D01*
X729133Y498608D01*
X728758Y498733D01*
X728342D01*
X728092Y498817D01*
X727883Y499025D01*
X727800Y499317D01*
X727925Y499608D01*
X728217Y499817D01*
X728550Y499900D01*
X728883Y499817D01*
X729175Y499608D01*
X729300Y499317D01*
X729217Y499025D01*
X729008Y498817D01*
X728758Y498733D01*
X728342D01*
X727967Y498608D01*
X727717Y498358D01*
X727633Y498067D01*
X727717Y497775D01*
X727925Y497567D01*
X728258Y497442D01*
X728550Y497400D01*
G01X720167Y503692D02*
X719917Y503817D01*
X719625Y503900D01*
X719292D01*
X718917Y503775D01*
X718625Y503567D01*
X718417Y503317D01*
X718250Y502900D01*
X718208Y502525D01*
X718292Y502150D01*
X718417Y501900D01*
X718667Y501650D01*
X718958Y501483D01*
X719250Y501400D01*
X719542D01*
X719833Y501483D01*
X720083Y501608D01*
X720292Y501775D01*
G01X721558Y502442D02*
X721850Y502733D01*
X722100Y502900D01*
X722433Y502983D01*
X722725Y502900D01*
X722933Y502733D01*
X723100Y502483D01*
X723142Y502192D01*
X723100Y501942D01*
X722933Y501692D01*
X722683Y501483D01*
X722392Y501400D01*
X722058Y501483D01*
X721767Y501733D01*
X721600Y502108D01*
X721558Y502525D01*
X721642Y503067D01*
X721767Y503358D01*
X721975Y503650D01*
X722267Y503858D01*
X722558Y503900D01*
X722850Y503817D01*
X723058Y503608D01*
G01X725450Y501400D02*
X725742Y501442D01*
X726075Y501567D01*
X726283Y501775D01*
X726367Y502067D01*
X726283Y502358D01*
X726033Y502608D01*
X725658Y502733D01*
X725242D01*
X724992Y502817D01*
X724783Y503025D01*
X724700Y503317D01*
X724825Y503608D01*
X725117Y503817D01*
X725450Y503900D01*
X725783Y503817D01*
X726075Y503608D01*
X726200Y503317D01*
X726117Y503025D01*
X725908Y502817D01*
X725658Y502733D01*
X725242D01*
X724867Y502608D01*
X724617Y502358D01*
X724533Y502067D01*
X724617Y501775D01*
X724825Y501567D01*
X725158Y501442D01*
X725450Y501400D01*
G01X728467D02*
X728550Y501942D01*
X728675Y502400D01*
X728842Y502817D01*
X729050Y503275D01*
X729383Y503900D01*
X727717D01*
G01X720167Y508192D02*
X719917Y508317D01*
X719625Y508400D01*
X719292D01*
X718917Y508275D01*
X718625Y508067D01*
X718417Y507817D01*
X718250Y507400D01*
X718208Y507025D01*
X718292Y506650D01*
X718417Y506400D01*
X718667Y506150D01*
X718958Y505983D01*
X719250Y505900D01*
X719542D01*
X719833Y505983D01*
X720083Y506108D01*
X720292Y506275D01*
G01X721558Y506942D02*
X721850Y507233D01*
X722100Y507400D01*
X722433Y507483D01*
X722725Y507400D01*
X722933Y507233D01*
X723100Y506983D01*
X723142Y506692D01*
X723100Y506442D01*
X722933Y506192D01*
X722683Y505983D01*
X722392Y505900D01*
X722058Y505983D01*
X721767Y506233D01*
X721600Y506608D01*
X721558Y507025D01*
X721642Y507567D01*
X721767Y507858D01*
X721975Y508150D01*
X722267Y508358D01*
X722558Y508400D01*
X722850Y508317D01*
X723058Y508108D01*
G01X725450Y505900D02*
X725742Y505942D01*
X726075Y506067D01*
X726283Y506275D01*
X726367Y506567D01*
X726283Y506858D01*
X726033Y507108D01*
X725658Y507233D01*
X725242D01*
X724992Y507317D01*
X724783Y507525D01*
X724700Y507817D01*
X724825Y508108D01*
X725117Y508317D01*
X725450Y508400D01*
X725783Y508317D01*
X726075Y508108D01*
X726200Y507817D01*
X726117Y507525D01*
X725908Y507317D01*
X725658Y507233D01*
X725242D01*
X724867Y507108D01*
X724617Y506858D01*
X724533Y506567D01*
X724617Y506275D01*
X724825Y506067D01*
X725158Y505942D01*
X725450Y505900D01*
G01X727758Y506942D02*
X728050Y507233D01*
X728300Y507400D01*
X728633Y507483D01*
X728925Y507400D01*
X729133Y507233D01*
X729300Y506983D01*
X729342Y506692D01*
X729300Y506442D01*
X729133Y506192D01*
X728883Y505983D01*
X728592Y505900D01*
X728258Y505983D01*
X727967Y506233D01*
X727800Y506608D01*
X727758Y507025D01*
X727842Y507567D01*
X727967Y507858D01*
X728175Y508150D01*
X728467Y508358D01*
X728758Y508400D01*
X729050Y508317D01*
X729258Y508108D01*
G01X699067Y489000D02*
Y491500D01*
X700108D01*
X700442Y491375D01*
X700650Y491208D01*
X700733Y490875D01*
X700650Y490542D01*
X700400Y490333D01*
X700108Y490208D01*
X699067D01*
G01X700108D02*
X700733Y489000D01*
G01X703000D02*
X703292Y489042D01*
X703625Y489167D01*
X703833Y489375D01*
X703917Y489667D01*
X703833Y489958D01*
X703583Y490208D01*
X703208Y490333D01*
X702792D01*
X702542Y490417D01*
X702333Y490625D01*
X702250Y490917D01*
X702375Y491208D01*
X702667Y491417D01*
X703000Y491500D01*
X703333Y491417D01*
X703625Y491208D01*
X703750Y490917D01*
X703667Y490625D01*
X703458Y490417D01*
X703208Y490333D01*
X702792D01*
X702417Y490208D01*
X702167Y489958D01*
X702083Y489667D01*
X702167Y489375D01*
X702375Y489167D01*
X702708Y489042D01*
X703000Y489000D01*
G01X706600D02*
Y491500D01*
X705058Y489708D01*
X707142D01*
G01X765000Y71017D02*
X762500D01*
Y72058D01*
X762625Y72392D01*
X762792Y72600D01*
X763125Y72683D01*
X763458Y72600D01*
X763667Y72350D01*
X763792Y72058D01*
Y71017D01*
G01Y72058D02*
X765000Y72683D01*
G01X762917Y74158D02*
X762667Y74408D01*
X762542Y74700D01*
X762500Y75033D01*
X762583Y75450D01*
X762792Y75742D01*
X763042Y75825D01*
X763292Y75783D01*
X763500Y75617D01*
X763917Y74783D01*
X764208Y74408D01*
X764625Y74158D01*
X765000Y74075D01*
Y75825D01*
G01X764625Y77133D02*
X764833Y77383D01*
X764958Y77675D01*
X765000Y78050D01*
X764917Y78425D01*
X764750Y78717D01*
X764458Y78925D01*
X764125Y78967D01*
X763792Y78883D01*
X763583Y78675D01*
X763417Y78383D01*
X763375Y78092D01*
X763417Y77800D01*
X763583Y77425D01*
X762500Y77550D01*
Y78675D01*
G01X764708Y80442D02*
X764917Y80733D01*
X765000Y81067D01*
X764917Y81400D01*
X764667Y81692D01*
X764292Y81900D01*
X763917Y81983D01*
X763458D01*
X763083Y81900D01*
X762750Y81692D01*
X762583Y81442D01*
X762500Y81150D01*
X762583Y80817D01*
X762750Y80567D01*
X763000Y80400D01*
X763333Y80317D01*
X763625Y80400D01*
X763917Y80608D01*
X764083Y80858D01*
X764125Y81150D01*
X764042Y81483D01*
X763833Y81733D01*
X763458Y81983D01*
G01X770350Y111667D02*
Y109167D01*
G01X769392Y111667D02*
X771308D01*
G01X772617Y109167D02*
Y111667D01*
X773617D01*
X773950Y111542D01*
X774200Y111250D01*
X774283Y110917D01*
X774200Y110584D01*
X773992Y110334D01*
X773617Y110209D01*
X772617D01*
G01X776467Y109167D02*
X776550Y109709D01*
X776675Y110167D01*
X776842Y110584D01*
X777050Y111042D01*
X777383Y111667D01*
X775717D01*
G01X778733Y109542D02*
X778983Y109334D01*
X779275Y109209D01*
X779650Y109167D01*
X780025Y109250D01*
X780317Y109417D01*
X780525Y109709D01*
X780567Y110042D01*
X780483Y110375D01*
X780275Y110584D01*
X779983Y110750D01*
X779692Y110792D01*
X779400Y110750D01*
X779025Y110584D01*
X779150Y111667D01*
X780275D01*
G01X768350Y116167D02*
Y113667D01*
G01X767392Y116167D02*
X769308D01*
G01X770617Y113667D02*
Y116167D01*
X771617D01*
X771950Y116042D01*
X772200Y115750D01*
X772283Y115417D01*
X772200Y115084D01*
X771992Y114834D01*
X771617Y114709D01*
X770617D01*
G01X773758D02*
X774050Y115000D01*
X774300Y115167D01*
X774633Y115250D01*
X774925Y115167D01*
X775133Y115000D01*
X775300Y114750D01*
X775342Y114459D01*
X775300Y114209D01*
X775133Y113959D01*
X774883Y113750D01*
X774592Y113667D01*
X774258Y113750D01*
X773967Y114000D01*
X773800Y114375D01*
X773758Y114792D01*
X773842Y115334D01*
X773967Y115625D01*
X774175Y115917D01*
X774467Y116125D01*
X774758Y116167D01*
X775050Y116084D01*
X775258Y115875D01*
G01X778150Y113667D02*
Y116167D01*
X776608Y114375D01*
X778692D01*
G01X783350Y111667D02*
Y109167D01*
G01X782392Y111667D02*
X784308D01*
G01X785617Y109167D02*
Y111667D01*
X786617D01*
X786950Y111542D01*
X787200Y111250D01*
X787283Y110917D01*
X787200Y110584D01*
X786992Y110334D01*
X786617Y110209D01*
X785617D01*
G01X788633Y109542D02*
X788883Y109334D01*
X789175Y109209D01*
X789550Y109167D01*
X789925Y109250D01*
X790217Y109417D01*
X790425Y109709D01*
X790467Y110042D01*
X790383Y110375D01*
X790175Y110584D01*
X789883Y110750D01*
X789592Y110792D01*
X789300Y110750D01*
X788925Y110584D01*
X789050Y111667D01*
X790175D01*
G01X791942Y109459D02*
X792233Y109250D01*
X792567Y109167D01*
X792900Y109250D01*
X793192Y109500D01*
X793400Y109875D01*
X793483Y110250D01*
Y110709D01*
X793400Y111084D01*
X793192Y111417D01*
X792942Y111584D01*
X792650Y111667D01*
X792317Y111584D01*
X792067Y111417D01*
X791900Y111167D01*
X791817Y110834D01*
X791900Y110542D01*
X792108Y110250D01*
X792358Y110084D01*
X792650Y110042D01*
X792983Y110125D01*
X793233Y110334D01*
X793483Y110709D01*
G01X767800Y99000D02*
Y96500D01*
G01X766842Y99000D02*
X768758D01*
G01X770067Y96500D02*
Y99000D01*
X771067D01*
X771400Y98875D01*
X771650Y98583D01*
X771733Y98250D01*
X771650Y97917D01*
X771442Y97667D01*
X771067Y97542D01*
X770067D01*
G01X774000Y96500D02*
Y99000D01*
X773500Y98500D01*
G01Y96500D02*
X774500D01*
G01X776183Y97000D02*
X776433Y96708D01*
X776767Y96542D01*
X777142Y96500D01*
X777475Y96542D01*
X777808Y96750D01*
X778017Y97000D01*
X778058Y97250D01*
X777975Y97542D01*
X777683Y97750D01*
X777392Y97833D01*
X777017D01*
G01X777392D02*
X777642Y97958D01*
X777850Y98167D01*
X777933Y98417D01*
X777850Y98667D01*
X777642Y98875D01*
X777267Y99000D01*
X776892Y98958D01*
X776517Y98792D01*
G01X780200Y96500D02*
Y99000D01*
X779700Y98500D01*
G01Y96500D02*
X780700D01*
G01X771017Y142500D02*
Y145000D01*
X772058D01*
X772392Y144875D01*
X772600Y144708D01*
X772683Y144375D01*
X772600Y144042D01*
X772350Y143833D01*
X772058Y143708D01*
X771017D01*
G01X772058D02*
X772683Y142500D01*
G01X774950D02*
Y145000D01*
X774450Y144500D01*
G01Y142500D02*
X775450D01*
G01X778050D02*
X778342Y142542D01*
X778675Y142667D01*
X778883Y142875D01*
X778967Y143167D01*
X778883Y143458D01*
X778633Y143708D01*
X778258Y143833D01*
X777842D01*
X777592Y143917D01*
X777383Y144125D01*
X777300Y144417D01*
X777425Y144708D01*
X777717Y144917D01*
X778050Y145000D01*
X778383Y144917D01*
X778675Y144708D01*
X778800Y144417D01*
X778717Y144125D01*
X778508Y143917D01*
X778258Y143833D01*
X777842D01*
X777467Y143708D01*
X777217Y143458D01*
X777133Y143167D01*
X777217Y142875D01*
X777425Y142667D01*
X777758Y142542D01*
X778050Y142500D01*
G01X780442Y142792D02*
X780733Y142583D01*
X781067Y142500D01*
X781400Y142583D01*
X781692Y142833D01*
X781900Y143208D01*
X781983Y143583D01*
Y144042D01*
X781900Y144417D01*
X781692Y144750D01*
X781442Y144917D01*
X781150Y145000D01*
X780817Y144917D01*
X780567Y144750D01*
X780400Y144500D01*
X780317Y144167D01*
X780400Y143875D01*
X780608Y143583D01*
X780858Y143417D01*
X781150Y143375D01*
X781483Y143458D01*
X781733Y143667D01*
X781983Y144042D01*
G01X771017Y138500D02*
Y141000D01*
X772058D01*
X772392Y140875D01*
X772600Y140708D01*
X772683Y140375D01*
X772600Y140042D01*
X772350Y139833D01*
X772058Y139708D01*
X771017D01*
G01X772058D02*
X772683Y138500D01*
G01X774950D02*
Y141000D01*
X774450Y140500D01*
G01Y138500D02*
X775450D01*
G01X778050D02*
X778342Y138542D01*
X778675Y138667D01*
X778883Y138875D01*
X778967Y139167D01*
X778883Y139458D01*
X778633Y139708D01*
X778258Y139833D01*
X777842D01*
X777592Y139917D01*
X777383Y140125D01*
X777300Y140417D01*
X777425Y140708D01*
X777717Y140917D01*
X778050Y141000D01*
X778383Y140917D01*
X778675Y140708D01*
X778800Y140417D01*
X778717Y140125D01*
X778508Y139917D01*
X778258Y139833D01*
X777842D01*
X777467Y139708D01*
X777217Y139458D01*
X777133Y139167D01*
X777217Y138875D01*
X777425Y138667D01*
X777758Y138542D01*
X778050Y138500D01*
G01X781650D02*
Y141000D01*
X780108Y139208D01*
X782192D01*
G01X773017Y169167D02*
Y171667D01*
X774058D01*
X774392Y171542D01*
X774600Y171375D01*
X774683Y171042D01*
X774600Y170709D01*
X774350Y170500D01*
X774058Y170375D01*
X773017D01*
G01X774058D02*
X774683Y169167D01*
G01X776950D02*
Y171667D01*
X776450Y171167D01*
G01Y169167D02*
X777450D01*
G01X780050D02*
X780342Y169209D01*
X780675Y169334D01*
X780883Y169542D01*
X780967Y169834D01*
X780883Y170125D01*
X780633Y170375D01*
X780258Y170500D01*
X779842D01*
X779592Y170584D01*
X779383Y170792D01*
X779300Y171084D01*
X779425Y171375D01*
X779717Y171584D01*
X780050Y171667D01*
X780383Y171584D01*
X780675Y171375D01*
X780800Y171084D01*
X780717Y170792D01*
X780508Y170584D01*
X780258Y170500D01*
X779842D01*
X779467Y170375D01*
X779217Y170125D01*
X779133Y169834D01*
X779217Y169542D01*
X779425Y169334D01*
X779758Y169209D01*
X780050Y169167D01*
G01X782233Y169667D02*
X782483Y169375D01*
X782817Y169209D01*
X783192Y169167D01*
X783525Y169209D01*
X783858Y169417D01*
X784067Y169667D01*
X784108Y169917D01*
X784025Y170209D01*
X783733Y170417D01*
X783442Y170500D01*
X783067D01*
G01X783442D02*
X783692Y170625D01*
X783900Y170834D01*
X783983Y171084D01*
X783900Y171334D01*
X783692Y171542D01*
X783317Y171667D01*
X782942Y171625D01*
X782567Y171459D01*
G01X771017Y134500D02*
Y137000D01*
X772058D01*
X772392Y136875D01*
X772600Y136708D01*
X772683Y136375D01*
X772600Y136042D01*
X772350Y135833D01*
X772058Y135708D01*
X771017D01*
G01X772058D02*
X772683Y134500D01*
G01X774950D02*
Y137000D01*
X774450Y136500D01*
G01Y134500D02*
X775450D01*
G01X778050D02*
X778342Y134542D01*
X778675Y134667D01*
X778883Y134875D01*
X778967Y135167D01*
X778883Y135458D01*
X778633Y135708D01*
X778258Y135833D01*
X777842D01*
X777592Y135917D01*
X777383Y136125D01*
X777300Y136417D01*
X777425Y136708D01*
X777717Y136917D01*
X778050Y137000D01*
X778383Y136917D01*
X778675Y136708D01*
X778800Y136417D01*
X778717Y136125D01*
X778508Y135917D01*
X778258Y135833D01*
X777842D01*
X777467Y135708D01*
X777217Y135458D01*
X777133Y135167D01*
X777217Y134875D01*
X777425Y134667D01*
X777758Y134542D01*
X778050Y134500D01*
G01X781150D02*
Y137000D01*
X780650Y136500D01*
G01Y134500D02*
X781650D01*
G01X764917Y151850D02*
Y154350D01*
X765958D01*
X766292Y154225D01*
X766500Y154058D01*
X766583Y153725D01*
X766500Y153392D01*
X766250Y153183D01*
X765958Y153058D01*
X764917D01*
G01X765958D02*
X766583Y151850D01*
G01X768850D02*
Y154350D01*
X768350Y153850D01*
G01Y151850D02*
X769350D01*
G01X771867D02*
X771950Y152392D01*
X772075Y152850D01*
X772242Y153267D01*
X772450Y153725D01*
X772783Y154350D01*
X771117D01*
G01X774342Y152142D02*
X774633Y151933D01*
X774967Y151850D01*
X775300Y151933D01*
X775592Y152183D01*
X775800Y152558D01*
X775883Y152933D01*
Y153392D01*
X775800Y153767D01*
X775592Y154100D01*
X775342Y154267D01*
X775050Y154350D01*
X774717Y154267D01*
X774467Y154100D01*
X774300Y153850D01*
X774217Y153517D01*
X774300Y153225D01*
X774508Y152933D01*
X774758Y152767D01*
X775050Y152725D01*
X775383Y152808D01*
X775633Y153017D01*
X775883Y153392D01*
G01X769517Y158000D02*
Y160500D01*
X770558D01*
X770892Y160375D01*
X771100Y160208D01*
X771183Y159875D01*
X771100Y159542D01*
X770850Y159333D01*
X770558Y159208D01*
X769517D01*
G01X770558D02*
X771183Y158000D01*
G01X772658Y160083D02*
X772908Y160333D01*
X773200Y160458D01*
X773533Y160500D01*
X773950Y160417D01*
X774242Y160208D01*
X774325Y159958D01*
X774283Y159708D01*
X774117Y159500D01*
X773283Y159083D01*
X772908Y158792D01*
X772658Y158375D01*
X772575Y158000D01*
X774325D01*
G01X775633Y158375D02*
X775883Y158167D01*
X776175Y158042D01*
X776550Y158000D01*
X776925Y158083D01*
X777217Y158250D01*
X777425Y158542D01*
X777467Y158875D01*
X777383Y159208D01*
X777175Y159417D01*
X776883Y159583D01*
X776592Y159625D01*
X776300Y159583D01*
X775925Y159417D01*
X776050Y160500D01*
X777175D01*
G01X778858Y159042D02*
X779150Y159333D01*
X779400Y159500D01*
X779733Y159583D01*
X780025Y159500D01*
X780233Y159333D01*
X780400Y159083D01*
X780442Y158792D01*
X780400Y158542D01*
X780233Y158292D01*
X779983Y158083D01*
X779692Y158000D01*
X779358Y158083D01*
X779067Y158333D01*
X778900Y158708D01*
X778858Y159125D01*
X778942Y159667D01*
X779067Y159958D01*
X779275Y160250D01*
X779567Y160458D01*
X779858Y160500D01*
X780150Y160417D01*
X780358Y160208D01*
G01X765017Y147550D02*
Y150050D01*
X766058D01*
X766392Y149925D01*
X766600Y149758D01*
X766683Y149425D01*
X766600Y149092D01*
X766350Y148883D01*
X766058Y148758D01*
X765017D01*
G01X766058D02*
X766683Y147550D01*
G01X768158Y149633D02*
X768408Y149883D01*
X768700Y150008D01*
X769033Y150050D01*
X769450Y149967D01*
X769742Y149758D01*
X769825Y149508D01*
X769783Y149258D01*
X769617Y149050D01*
X768783Y148633D01*
X768408Y148342D01*
X768158Y147925D01*
X768075Y147550D01*
X769825D01*
G01X771133Y147925D02*
X771383Y147717D01*
X771675Y147592D01*
X772050Y147550D01*
X772425Y147633D01*
X772717Y147800D01*
X772925Y148092D01*
X772967Y148425D01*
X772883Y148758D01*
X772675Y148967D01*
X772383Y149133D01*
X772092Y149175D01*
X771800Y149133D01*
X771425Y148967D01*
X771550Y150050D01*
X772675D01*
G01X775650Y147550D02*
Y150050D01*
X774108Y148258D01*
X776192D01*
G01X773017Y173500D02*
Y176000D01*
X774058D01*
X774392Y175875D01*
X774600Y175708D01*
X774683Y175375D01*
X774600Y175042D01*
X774350Y174833D01*
X774058Y174708D01*
X773017D01*
G01X774058D02*
X774683Y173500D01*
G01X776158Y175583D02*
X776408Y175833D01*
X776700Y175958D01*
X777033Y176000D01*
X777450Y175917D01*
X777742Y175708D01*
X777825Y175458D01*
X777783Y175208D01*
X777617Y175000D01*
X776783Y174583D01*
X776408Y174292D01*
X776158Y173875D01*
X776075Y173500D01*
X777825D01*
G01X779133Y174000D02*
X779383Y173708D01*
X779717Y173542D01*
X780092Y173500D01*
X780425Y173542D01*
X780758Y173750D01*
X780967Y174000D01*
X781008Y174250D01*
X780925Y174542D01*
X780633Y174750D01*
X780342Y174833D01*
X779967D01*
G01X780342D02*
X780592Y174958D01*
X780800Y175167D01*
X780883Y175417D01*
X780800Y175667D01*
X780592Y175875D01*
X780217Y176000D01*
X779842Y175958D01*
X779467Y175792D01*
G01X783067Y173500D02*
X783150Y174042D01*
X783275Y174500D01*
X783442Y174917D01*
X783650Y175375D01*
X783983Y176000D01*
X782317D01*
G01X771517Y162500D02*
Y165000D01*
X772558D01*
X772892Y164875D01*
X773100Y164708D01*
X773183Y164375D01*
X773100Y164042D01*
X772850Y163833D01*
X772558Y163708D01*
X771517D01*
G01X772558D02*
X773183Y162500D01*
G01X775450D02*
Y165000D01*
X774950Y164500D01*
G01Y162500D02*
X775950D01*
G01X778467D02*
X778550Y163042D01*
X778675Y163500D01*
X778842Y163917D01*
X779050Y164375D01*
X779383Y165000D01*
X777717D01*
G01X780733Y162875D02*
X780983Y162667D01*
X781275Y162542D01*
X781650Y162500D01*
X782025Y162583D01*
X782317Y162750D01*
X782525Y163042D01*
X782567Y163375D01*
X782483Y163708D01*
X782275Y163917D01*
X781983Y164083D01*
X781692Y164125D01*
X781400Y164083D01*
X781025Y163917D01*
X781150Y165000D01*
X782275D01*
G01X785017Y162500D02*
Y165000D01*
X786058D01*
X786392Y164875D01*
X786600Y164708D01*
X786683Y164375D01*
X786600Y164042D01*
X786350Y163833D01*
X786058Y163708D01*
X785017D01*
G01X786058D02*
X786683Y162500D01*
G01X788950D02*
Y165000D01*
X788450Y164500D01*
G01Y162500D02*
X789450D01*
G01X791967D02*
X792050Y163042D01*
X792175Y163500D01*
X792342Y163917D01*
X792550Y164375D01*
X792883Y165000D01*
X791217D01*
G01X795150Y162500D02*
Y165000D01*
X794650Y164500D01*
G01Y162500D02*
X795650D01*
G01X760600Y166200D02*
Y162200D01*
X768000D01*
G01X796850Y132000D02*
Y129500D01*
G01X795892Y132000D02*
X797808D01*
G01X799117Y129500D02*
Y132000D01*
X800117D01*
X800450Y131875D01*
X800700Y131583D01*
X800783Y131250D01*
X800700Y130917D01*
X800492Y130667D01*
X800117Y130542D01*
X799117D01*
G01X802342Y129792D02*
X802633Y129583D01*
X802967Y129500D01*
X803300Y129583D01*
X803592Y129833D01*
X803800Y130208D01*
X803883Y130583D01*
Y131042D01*
X803800Y131417D01*
X803592Y131750D01*
X803342Y131917D01*
X803050Y132000D01*
X802717Y131917D01*
X802467Y131750D01*
X802300Y131500D01*
X802217Y131167D01*
X802300Y130875D01*
X802508Y130583D01*
X802758Y130417D01*
X803050Y130375D01*
X803383Y130458D01*
X803633Y130667D01*
X803883Y131042D01*
G01X805442Y129792D02*
X805733Y129583D01*
X806067Y129500D01*
X806400Y129583D01*
X806692Y129833D01*
X806900Y130208D01*
X806983Y130583D01*
Y131042D01*
X806900Y131417D01*
X806692Y131750D01*
X806442Y131917D01*
X806150Y132000D01*
X805817Y131917D01*
X805567Y131750D01*
X805400Y131500D01*
X805317Y131167D01*
X805400Y130875D01*
X805608Y130583D01*
X805858Y130417D01*
X806150Y130375D01*
X806483Y130458D01*
X806733Y130667D01*
X806983Y131042D01*
G01X793350Y127500D02*
Y125000D01*
G01X792392Y127500D02*
X794308D01*
G01X795617Y125000D02*
Y127500D01*
X796617D01*
X796950Y127375D01*
X797200Y127083D01*
X797283Y126750D01*
X797200Y126417D01*
X796992Y126167D01*
X796617Y126042D01*
X795617D01*
G01X799550Y125000D02*
X799842Y125042D01*
X800175Y125167D01*
X800383Y125375D01*
X800467Y125667D01*
X800383Y125958D01*
X800133Y126208D01*
X799758Y126333D01*
X799342D01*
X799092Y126417D01*
X798883Y126625D01*
X798800Y126917D01*
X798925Y127208D01*
X799217Y127417D01*
X799550Y127500D01*
X799883Y127417D01*
X800175Y127208D01*
X800300Y126917D01*
X800217Y126625D01*
X800008Y126417D01*
X799758Y126333D01*
X799342D01*
X798967Y126208D01*
X798717Y125958D01*
X798633Y125667D01*
X798717Y125375D01*
X798925Y125167D01*
X799258Y125042D01*
X799550Y125000D01*
G01X801942Y125292D02*
X802233Y125083D01*
X802567Y125000D01*
X802900Y125083D01*
X803192Y125333D01*
X803400Y125708D01*
X803483Y126083D01*
Y126542D01*
X803400Y126917D01*
X803192Y127250D01*
X802942Y127417D01*
X802650Y127500D01*
X802317Y127417D01*
X802067Y127250D01*
X801900Y127000D01*
X801817Y126667D01*
X801900Y126375D01*
X802108Y126083D01*
X802358Y125917D01*
X802650Y125875D01*
X802983Y125958D01*
X803233Y126167D01*
X803483Y126542D01*
G01X809850Y132167D02*
Y129667D01*
G01X808892Y132167D02*
X810808D01*
G01X812117Y129667D02*
Y132167D01*
X813117D01*
X813450Y132042D01*
X813700Y131750D01*
X813783Y131417D01*
X813700Y131084D01*
X813492Y130834D01*
X813117Y130709D01*
X812117D01*
G01X816050Y129667D02*
X816342Y129709D01*
X816675Y129834D01*
X816883Y130042D01*
X816967Y130334D01*
X816883Y130625D01*
X816633Y130875D01*
X816258Y131000D01*
X815842D01*
X815592Y131084D01*
X815383Y131292D01*
X815300Y131584D01*
X815425Y131875D01*
X815717Y132084D01*
X816050Y132167D01*
X816383Y132084D01*
X816675Y131875D01*
X816800Y131584D01*
X816717Y131292D01*
X816508Y131084D01*
X816258Y131000D01*
X815842D01*
X815467Y130875D01*
X815217Y130625D01*
X815133Y130334D01*
X815217Y130042D01*
X815425Y129834D01*
X815758Y129709D01*
X816050Y129667D01*
G01X819067D02*
X819150Y130209D01*
X819275Y130667D01*
X819442Y131084D01*
X819650Y131542D01*
X819983Y132167D01*
X818317D01*
G01X768850Y127500D02*
Y125000D01*
G01X767892Y127500D02*
X769808D01*
G01X771117Y125000D02*
Y127500D01*
X772117D01*
X772450Y127375D01*
X772700Y127083D01*
X772783Y126750D01*
X772700Y126417D01*
X772492Y126167D01*
X772117Y126042D01*
X771117D01*
G01X774967Y125000D02*
X775050Y125542D01*
X775175Y126000D01*
X775342Y126417D01*
X775550Y126875D01*
X775883Y127500D01*
X774217D01*
G01X777358Y126042D02*
X777650Y126333D01*
X777900Y126500D01*
X778233Y126583D01*
X778525Y126500D01*
X778733Y126333D01*
X778900Y126083D01*
X778942Y125792D01*
X778900Y125542D01*
X778733Y125292D01*
X778483Y125083D01*
X778192Y125000D01*
X777858Y125083D01*
X777567Y125333D01*
X777400Y125708D01*
X777358Y126125D01*
X777442Y126667D01*
X777567Y126958D01*
X777775Y127250D01*
X778067Y127458D01*
X778358Y127500D01*
X778650Y127417D01*
X778858Y127208D01*
G01X769350Y123167D02*
Y120667D01*
G01X768392Y123167D02*
X770308D01*
G01X771617Y120667D02*
Y123167D01*
X772617D01*
X772950Y123042D01*
X773200Y122750D01*
X773283Y122417D01*
X773200Y122084D01*
X772992Y121834D01*
X772617Y121709D01*
X771617D01*
G01X775467Y120667D02*
X775550Y121209D01*
X775675Y121667D01*
X775842Y122084D01*
X776050Y122542D01*
X776383Y123167D01*
X774717D01*
G01X778650Y120667D02*
Y123167D01*
X778150Y122667D01*
G01Y120667D02*
X779150D01*
G01X784350Y132000D02*
Y129500D01*
G01X783392Y132000D02*
X785308D01*
G01X786617Y129500D02*
Y132000D01*
X787617D01*
X787950Y131875D01*
X788200Y131583D01*
X788283Y131250D01*
X788200Y130917D01*
X787992Y130667D01*
X787617Y130542D01*
X786617D01*
G01X789758D02*
X790050Y130833D01*
X790300Y131000D01*
X790633Y131083D01*
X790925Y131000D01*
X791133Y130833D01*
X791300Y130583D01*
X791342Y130292D01*
X791300Y130042D01*
X791133Y129792D01*
X790883Y129583D01*
X790592Y129500D01*
X790258Y129583D01*
X789967Y129833D01*
X789800Y130208D01*
X789758Y130625D01*
X789842Y131167D01*
X789967Y131458D01*
X790175Y131750D01*
X790467Y131958D01*
X790758Y132000D01*
X791050Y131917D01*
X791258Y131708D01*
G01X793650Y129500D02*
X793942Y129542D01*
X794275Y129667D01*
X794483Y129875D01*
X794567Y130167D01*
X794483Y130458D01*
X794233Y130708D01*
X793858Y130833D01*
X793442D01*
X793192Y130917D01*
X792983Y131125D01*
X792900Y131417D01*
X793025Y131708D01*
X793317Y131917D01*
X793650Y132000D01*
X793983Y131917D01*
X794275Y131708D01*
X794400Y131417D01*
X794317Y131125D01*
X794108Y130917D01*
X793858Y130833D01*
X793442D01*
X793067Y130708D01*
X792817Y130458D01*
X792733Y130167D01*
X792817Y129875D01*
X793025Y129667D01*
X793358Y129542D01*
X793650Y129500D01*
G01X781350Y127500D02*
Y125000D01*
G01X780392Y127500D02*
X782308D01*
G01X783617Y125000D02*
Y127500D01*
X784617D01*
X784950Y127375D01*
X785200Y127083D01*
X785283Y126750D01*
X785200Y126417D01*
X784992Y126167D01*
X784617Y126042D01*
X783617D01*
G01X786758D02*
X787050Y126333D01*
X787300Y126500D01*
X787633Y126583D01*
X787925Y126500D01*
X788133Y126333D01*
X788300Y126083D01*
X788342Y125792D01*
X788300Y125542D01*
X788133Y125292D01*
X787883Y125083D01*
X787592Y125000D01*
X787258Y125083D01*
X786967Y125333D01*
X786800Y125708D01*
X786758Y126125D01*
X786842Y126667D01*
X786967Y126958D01*
X787175Y127250D01*
X787467Y127458D01*
X787758Y127500D01*
X788050Y127417D01*
X788258Y127208D01*
G01X790650Y125000D02*
Y127500D01*
X790150Y127000D01*
G01Y125000D02*
X791150D01*
G01X768300Y132000D02*
Y129500D01*
G01X767342Y132000D02*
X769258D01*
G01X770567Y129500D02*
Y132000D01*
X771567D01*
X771900Y131875D01*
X772150Y131583D01*
X772233Y131250D01*
X772150Y130917D01*
X771942Y130667D01*
X771567Y130542D01*
X770567D01*
G01X774500Y129500D02*
Y132000D01*
X774000Y131500D01*
G01Y129500D02*
X775000D01*
G01X778100D02*
Y132000D01*
X776558Y130208D01*
X778642D01*
G01X780700Y129500D02*
X780992Y129542D01*
X781325Y129667D01*
X781533Y129875D01*
X781617Y130167D01*
X781533Y130458D01*
X781283Y130708D01*
X780908Y130833D01*
X780492D01*
X780242Y130917D01*
X780033Y131125D01*
X779950Y131417D01*
X780075Y131708D01*
X780367Y131917D01*
X780700Y132000D01*
X781033Y131917D01*
X781325Y131708D01*
X781450Y131417D01*
X781367Y131125D01*
X781158Y130917D01*
X780908Y130833D01*
X780492D01*
X780117Y130708D01*
X779867Y130458D01*
X779783Y130167D01*
X779867Y129875D01*
X780075Y129667D01*
X780408Y129542D01*
X780700Y129500D01*
G01X806800Y127167D02*
Y124667D01*
G01X805842Y127167D02*
X807758D01*
G01X809067Y124667D02*
Y127167D01*
X810067D01*
X810400Y127042D01*
X810650Y126750D01*
X810733Y126417D01*
X810650Y126084D01*
X810442Y125834D01*
X810067Y125709D01*
X809067D01*
G01X813000Y124667D02*
Y127167D01*
X812500Y126667D01*
G01Y124667D02*
X813500D01*
G01X816100Y127167D02*
X815767Y127084D01*
X815517Y126875D01*
X815350Y126625D01*
X815225Y126292D01*
X815183Y125917D01*
X815225Y125542D01*
X815350Y125209D01*
X815517Y124959D01*
X815767Y124750D01*
X816100Y124667D01*
X816433Y124750D01*
X816683Y124959D01*
X816850Y125209D01*
X816975Y125542D01*
X817017Y125917D01*
X816975Y126292D01*
X816850Y126625D01*
X816683Y126875D01*
X816433Y127084D01*
X816100Y127167D01*
G01X819200Y124667D02*
Y127167D01*
X818700Y126667D01*
G01Y124667D02*
X819700D01*
G01X766517Y179000D02*
Y181500D01*
X767558D01*
X767892Y181375D01*
X768100Y181208D01*
X768183Y180875D01*
X768100Y180542D01*
X767850Y180333D01*
X767558Y180208D01*
X766517D01*
G01X767558D02*
X768183Y179000D01*
G01X770450D02*
Y181500D01*
X769950Y181000D01*
G01Y179000D02*
X770950D01*
G01X773550D02*
X773842Y179042D01*
X774175Y179167D01*
X774383Y179375D01*
X774467Y179667D01*
X774383Y179958D01*
X774133Y180208D01*
X773758Y180333D01*
X773342D01*
X773092Y180417D01*
X772883Y180625D01*
X772800Y180917D01*
X772925Y181208D01*
X773217Y181417D01*
X773550Y181500D01*
X773883Y181417D01*
X774175Y181208D01*
X774300Y180917D01*
X774217Y180625D01*
X774008Y180417D01*
X773758Y180333D01*
X773342D01*
X772967Y180208D01*
X772717Y179958D01*
X772633Y179667D01*
X772717Y179375D01*
X772925Y179167D01*
X773258Y179042D01*
X773550Y179000D01*
G01X776650Y181500D02*
X776317Y181417D01*
X776067Y181208D01*
X775900Y180958D01*
X775775Y180625D01*
X775733Y180250D01*
X775775Y179875D01*
X775900Y179542D01*
X776067Y179292D01*
X776317Y179083D01*
X776650Y179000D01*
X776983Y179083D01*
X777233Y179292D01*
X777400Y179542D01*
X777525Y179875D01*
X777567Y180250D01*
X777525Y180625D01*
X777400Y180958D01*
X777233Y181208D01*
X776983Y181417D01*
X776650Y181500D01*
G01X762517Y194000D02*
Y196500D01*
X763558D01*
X763892Y196375D01*
X764100Y196208D01*
X764183Y195875D01*
X764100Y195542D01*
X763850Y195333D01*
X763558Y195208D01*
X762517D01*
G01X763558D02*
X764183Y194000D01*
G01X765533Y194500D02*
X765783Y194208D01*
X766117Y194042D01*
X766492Y194000D01*
X766825Y194042D01*
X767158Y194250D01*
X767367Y194500D01*
X767408Y194750D01*
X767325Y195042D01*
X767033Y195250D01*
X766742Y195333D01*
X766367D01*
G01X766742D02*
X766992Y195458D01*
X767200Y195667D01*
X767283Y195917D01*
X767200Y196167D01*
X766992Y196375D01*
X766617Y196500D01*
X766242Y196458D01*
X765867Y196292D01*
G01X768842Y194292D02*
X769133Y194083D01*
X769467Y194000D01*
X769800Y194083D01*
X770092Y194333D01*
X770300Y194708D01*
X770383Y195083D01*
Y195542D01*
X770300Y195917D01*
X770092Y196250D01*
X769842Y196417D01*
X769550Y196500D01*
X769217Y196417D01*
X768967Y196250D01*
X768800Y196000D01*
X768717Y195667D01*
X768800Y195375D01*
X769008Y195083D01*
X769258Y194917D01*
X769550Y194875D01*
X769883Y194958D01*
X770133Y195167D01*
X770383Y195542D01*
G01X771858Y195042D02*
X772150Y195333D01*
X772400Y195500D01*
X772733Y195583D01*
X773025Y195500D01*
X773233Y195333D01*
X773400Y195083D01*
X773442Y194792D01*
X773400Y194542D01*
X773233Y194292D01*
X772983Y194083D01*
X772692Y194000D01*
X772358Y194083D01*
X772067Y194333D01*
X771900Y194708D01*
X771858Y195125D01*
X771942Y195667D01*
X772067Y195958D01*
X772275Y196250D01*
X772567Y196458D01*
X772858Y196500D01*
X773150Y196417D01*
X773358Y196208D01*
G01X762517Y198500D02*
Y201000D01*
X763558D01*
X763892Y200875D01*
X764100Y200708D01*
X764183Y200375D01*
X764100Y200042D01*
X763850Y199833D01*
X763558Y199708D01*
X762517D01*
G01X763558D02*
X764183Y198500D01*
G01X765658Y200583D02*
X765908Y200833D01*
X766200Y200958D01*
X766533Y201000D01*
X766950Y200917D01*
X767242Y200708D01*
X767325Y200458D01*
X767283Y200208D01*
X767117Y200000D01*
X766283Y199583D01*
X765908Y199292D01*
X765658Y198875D01*
X765575Y198500D01*
X767325D01*
G01X768758Y200583D02*
X769008Y200833D01*
X769300Y200958D01*
X769633Y201000D01*
X770050Y200917D01*
X770342Y200708D01*
X770425Y200458D01*
X770383Y200208D01*
X770217Y200000D01*
X769383Y199583D01*
X769008Y199292D01*
X768758Y198875D01*
X768675Y198500D01*
X770425D01*
G01X772650D02*
X772942Y198542D01*
X773275Y198667D01*
X773483Y198875D01*
X773567Y199167D01*
X773483Y199458D01*
X773233Y199708D01*
X772858Y199833D01*
X772442D01*
X772192Y199917D01*
X771983Y200125D01*
X771900Y200417D01*
X772025Y200708D01*
X772317Y200917D01*
X772650Y201000D01*
X772983Y200917D01*
X773275Y200708D01*
X773400Y200417D01*
X773317Y200125D01*
X773108Y199917D01*
X772858Y199833D01*
X772442D01*
X772067Y199708D01*
X771817Y199458D01*
X771733Y199167D01*
X771817Y198875D01*
X772025Y198667D01*
X772358Y198542D01*
X772650Y198500D01*
G01X763017Y214000D02*
Y216500D01*
X764058D01*
X764392Y216375D01*
X764600Y216208D01*
X764683Y215875D01*
X764600Y215542D01*
X764350Y215333D01*
X764058Y215208D01*
X763017D01*
G01X764058D02*
X764683Y214000D01*
G01X766158Y216083D02*
X766408Y216333D01*
X766700Y216458D01*
X767033Y216500D01*
X767450Y216417D01*
X767742Y216208D01*
X767825Y215958D01*
X767783Y215708D01*
X767617Y215500D01*
X766783Y215083D01*
X766408Y214792D01*
X766158Y214375D01*
X766075Y214000D01*
X767825D01*
G01X769258Y216083D02*
X769508Y216333D01*
X769800Y216458D01*
X770133Y216500D01*
X770550Y216417D01*
X770842Y216208D01*
X770925Y215958D01*
X770883Y215708D01*
X770717Y215500D01*
X769883Y215083D01*
X769508Y214792D01*
X769258Y214375D01*
X769175Y214000D01*
X770925D01*
G01X773067D02*
X773150Y214542D01*
X773275Y215000D01*
X773442Y215417D01*
X773650Y215875D01*
X773983Y216500D01*
X772317D01*
G01X761017Y207000D02*
Y209500D01*
X762058D01*
X762392Y209375D01*
X762600Y209208D01*
X762683Y208875D01*
X762600Y208542D01*
X762350Y208333D01*
X762058Y208208D01*
X761017D01*
G01X762058D02*
X762683Y207000D01*
G01X764158Y209083D02*
X764408Y209333D01*
X764700Y209458D01*
X765033Y209500D01*
X765450Y209417D01*
X765742Y209208D01*
X765825Y208958D01*
X765783Y208708D01*
X765617Y208500D01*
X764783Y208083D01*
X764408Y207792D01*
X764158Y207375D01*
X764075Y207000D01*
X765825D01*
G01X767258Y209083D02*
X767508Y209333D01*
X767800Y209458D01*
X768133Y209500D01*
X768550Y209417D01*
X768842Y209208D01*
X768925Y208958D01*
X768883Y208708D01*
X768717Y208500D01*
X767883Y208083D01*
X767508Y207792D01*
X767258Y207375D01*
X767175Y207000D01*
X768925D01*
G01X770233Y207375D02*
X770483Y207167D01*
X770775Y207042D01*
X771150Y207000D01*
X771525Y207083D01*
X771817Y207250D01*
X772025Y207542D01*
X772067Y207875D01*
X771983Y208208D01*
X771775Y208417D01*
X771483Y208583D01*
X771192Y208625D01*
X770900Y208583D01*
X770525Y208417D01*
X770650Y209500D01*
X771775D01*
G01X766517Y183000D02*
Y185500D01*
X767558D01*
X767892Y185375D01*
X768100Y185208D01*
X768183Y184875D01*
X768100Y184542D01*
X767850Y184333D01*
X767558Y184208D01*
X766517D01*
G01X767558D02*
X768183Y183000D01*
G01X769658Y185083D02*
X769908Y185333D01*
X770200Y185458D01*
X770533Y185500D01*
X770950Y185417D01*
X771242Y185208D01*
X771325Y184958D01*
X771283Y184708D01*
X771117Y184500D01*
X770283Y184083D01*
X769908Y183792D01*
X769658Y183375D01*
X769575Y183000D01*
X771325D01*
G01X773550D02*
Y185500D01*
X773050Y185000D01*
G01Y183000D02*
X774050D01*
G01X776567D02*
X776650Y183542D01*
X776775Y184000D01*
X776942Y184417D01*
X777150Y184875D01*
X777483Y185500D01*
X775817D01*
G01X766517Y187000D02*
Y189500D01*
X767558D01*
X767892Y189375D01*
X768100Y189208D01*
X768183Y188875D01*
X768100Y188542D01*
X767850Y188333D01*
X767558Y188208D01*
X766517D01*
G01X767558D02*
X768183Y187000D01*
G01X769658Y189083D02*
X769908Y189333D01*
X770200Y189458D01*
X770533Y189500D01*
X770950Y189417D01*
X771242Y189208D01*
X771325Y188958D01*
X771283Y188708D01*
X771117Y188500D01*
X770283Y188083D01*
X769908Y187792D01*
X769658Y187375D01*
X769575Y187000D01*
X771325D01*
G01X773550D02*
Y189500D01*
X773050Y189000D01*
G01Y187000D02*
X774050D01*
G01X775858Y188042D02*
X776150Y188333D01*
X776400Y188500D01*
X776733Y188583D01*
X777025Y188500D01*
X777233Y188333D01*
X777400Y188083D01*
X777442Y187792D01*
X777400Y187542D01*
X777233Y187292D01*
X776983Y187083D01*
X776692Y187000D01*
X776358Y187083D01*
X776067Y187333D01*
X775900Y187708D01*
X775858Y188125D01*
X775942Y188667D01*
X776067Y188958D01*
X776275Y189250D01*
X776567Y189458D01*
X776858Y189500D01*
X777150Y189417D01*
X777358Y189208D01*
G01X761017Y203000D02*
Y205500D01*
X762058D01*
X762392Y205375D01*
X762600Y205208D01*
X762683Y204875D01*
X762600Y204542D01*
X762350Y204333D01*
X762058Y204208D01*
X761017D01*
G01X762058D02*
X762683Y203000D01*
G01X764158Y205083D02*
X764408Y205333D01*
X764700Y205458D01*
X765033Y205500D01*
X765450Y205417D01*
X765742Y205208D01*
X765825Y204958D01*
X765783Y204708D01*
X765617Y204500D01*
X764783Y204083D01*
X764408Y203792D01*
X764158Y203375D01*
X764075Y203000D01*
X765825D01*
G01X768050D02*
Y205500D01*
X767550Y205000D01*
G01Y203000D02*
X768550D01*
G01X770233Y203375D02*
X770483Y203167D01*
X770775Y203042D01*
X771150Y203000D01*
X771525Y203083D01*
X771817Y203250D01*
X772025Y203542D01*
X772067Y203875D01*
X771983Y204208D01*
X771775Y204417D01*
X771483Y204583D01*
X771192Y204625D01*
X770900Y204583D01*
X770525Y204417D01*
X770650Y205500D01*
X771775D01*
G01X812334Y285017D02*
X809834D01*
Y286058D01*
X809959Y286392D01*
X810126Y286600D01*
X810459Y286683D01*
X810792Y286600D01*
X811001Y286350D01*
X811126Y286058D01*
Y285017D01*
G01Y286058D02*
X812334Y286683D01*
G01X810251Y288158D02*
X810001Y288408D01*
X809876Y288700D01*
X809834Y289033D01*
X809917Y289450D01*
X810126Y289742D01*
X810376Y289825D01*
X810626Y289783D01*
X810834Y289617D01*
X811251Y288783D01*
X811542Y288408D01*
X811959Y288158D01*
X812334Y288075D01*
Y289825D01*
G01X811834Y291133D02*
X812126Y291383D01*
X812292Y291717D01*
X812334Y292092D01*
X812292Y292425D01*
X812084Y292758D01*
X811834Y292967D01*
X811584Y293008D01*
X811292Y292925D01*
X811084Y292633D01*
X811001Y292342D01*
Y291967D01*
G01Y292342D02*
X810876Y292592D01*
X810667Y292800D01*
X810417Y292883D01*
X810167Y292800D01*
X809959Y292592D01*
X809834Y292217D01*
X809876Y291842D01*
X810042Y291467D01*
G01X809834Y295150D02*
X809917Y294817D01*
X810126Y294567D01*
X810376Y294400D01*
X810709Y294275D01*
X811084Y294233D01*
X811459Y294275D01*
X811792Y294400D01*
X812042Y294567D01*
X812251Y294817D01*
X812334Y295150D01*
X812251Y295483D01*
X812042Y295733D01*
X811792Y295900D01*
X811459Y296025D01*
X811084Y296067D01*
X810709Y296025D01*
X810376Y295900D01*
X810126Y295733D01*
X809917Y295483D01*
X809834Y295150D01*
G01X803934Y293146D02*
X799934D01*
Y285746D01*
G01X770036Y295180D02*
Y291180D01*
X777436D01*
G01X782017Y287900D02*
Y290400D01*
X783058D01*
X783392Y290275D01*
X783600Y290108D01*
X783683Y289775D01*
X783600Y289442D01*
X783350Y289233D01*
X783058Y289108D01*
X782017D01*
G01X783058D02*
X783683Y287900D01*
G01X785158Y289983D02*
X785408Y290233D01*
X785700Y290358D01*
X786033Y290400D01*
X786450Y290317D01*
X786742Y290108D01*
X786825Y289858D01*
X786783Y289608D01*
X786617Y289400D01*
X785783Y288983D01*
X785408Y288692D01*
X785158Y288275D01*
X785075Y287900D01*
X786825D01*
G01X788342Y288192D02*
X788633Y287983D01*
X788967Y287900D01*
X789300Y287983D01*
X789592Y288233D01*
X789800Y288608D01*
X789883Y288983D01*
Y289442D01*
X789800Y289817D01*
X789592Y290150D01*
X789342Y290317D01*
X789050Y290400D01*
X788717Y290317D01*
X788467Y290150D01*
X788300Y289900D01*
X788217Y289567D01*
X788300Y289275D01*
X788508Y288983D01*
X788758Y288817D01*
X789050Y288775D01*
X789383Y288858D01*
X789633Y289067D01*
X789883Y289442D01*
G01X792150Y287900D02*
X792442Y287942D01*
X792775Y288067D01*
X792983Y288275D01*
X793067Y288567D01*
X792983Y288858D01*
X792733Y289108D01*
X792358Y289233D01*
X791942D01*
X791692Y289317D01*
X791483Y289525D01*
X791400Y289817D01*
X791525Y290108D01*
X791817Y290317D01*
X792150Y290400D01*
X792483Y290317D01*
X792775Y290108D01*
X792900Y289817D01*
X792817Y289525D01*
X792608Y289317D01*
X792358Y289233D01*
X791942D01*
X791567Y289108D01*
X791317Y288858D01*
X791233Y288567D01*
X791317Y288275D01*
X791525Y288067D01*
X791858Y287942D01*
X792150Y287900D01*
G01X777940Y295180D02*
Y291180D01*
X785340D01*
G01X769200Y260517D02*
X766700D01*
Y261558D01*
X766825Y261892D01*
X766992Y262100D01*
X767325Y262183D01*
X767658Y262100D01*
X767867Y261850D01*
X767992Y261558D01*
Y260517D01*
G01Y261558D02*
X769200Y262183D01*
G01X767117Y263658D02*
X766867Y263908D01*
X766742Y264200D01*
X766700Y264533D01*
X766783Y264950D01*
X766992Y265242D01*
X767242Y265325D01*
X767492Y265283D01*
X767700Y265117D01*
X768117Y264283D01*
X768408Y263908D01*
X768825Y263658D01*
X769200Y263575D01*
Y265325D01*
G01X768908Y266842D02*
X769117Y267133D01*
X769200Y267467D01*
X769117Y267800D01*
X768867Y268092D01*
X768492Y268300D01*
X768117Y268383D01*
X767658D01*
X767283Y268300D01*
X766950Y268092D01*
X766783Y267842D01*
X766700Y267550D01*
X766783Y267217D01*
X766950Y266967D01*
X767200Y266800D01*
X767533Y266717D01*
X767825Y266800D01*
X768117Y267008D01*
X768283Y267258D01*
X768325Y267550D01*
X768242Y267883D01*
X768033Y268133D01*
X767658Y268383D01*
G01X768908Y269942D02*
X769117Y270233D01*
X769200Y270567D01*
X769117Y270900D01*
X768867Y271192D01*
X768492Y271400D01*
X768117Y271483D01*
X767658D01*
X767283Y271400D01*
X766950Y271192D01*
X766783Y270942D01*
X766700Y270650D01*
X766783Y270317D01*
X766950Y270067D01*
X767200Y269900D01*
X767533Y269817D01*
X767825Y269900D01*
X768117Y270108D01*
X768283Y270358D01*
X768325Y270650D01*
X768242Y270983D01*
X768033Y271233D01*
X767658Y271483D01*
G01X761840Y261310D02*
X765840D01*
Y268710D01*
G01X806042Y290767D02*
X805917Y290517D01*
X805834Y290225D01*
Y289892D01*
X805959Y289517D01*
X806167Y289225D01*
X806417Y289017D01*
X806834Y288850D01*
X807209Y288808D01*
X807584Y288892D01*
X807834Y289017D01*
X808084Y289267D01*
X808251Y289558D01*
X808334Y289850D01*
Y290142D01*
X808251Y290433D01*
X808126Y290683D01*
X807959Y290892D01*
G01X807834Y292033D02*
X808126Y292283D01*
X808292Y292617D01*
X808334Y292992D01*
X808292Y293325D01*
X808084Y293658D01*
X807834Y293867D01*
X807584Y293908D01*
X807292Y293825D01*
X807084Y293533D01*
X807001Y293242D01*
Y292867D01*
G01Y293242D02*
X806876Y293492D01*
X806667Y293700D01*
X806417Y293783D01*
X806167Y293700D01*
X805959Y293492D01*
X805834Y293117D01*
X805876Y292742D01*
X806042Y292367D01*
G01X808334Y296550D02*
X805834D01*
X807626Y295008D01*
Y297092D01*
G01X808042Y298442D02*
X808251Y298733D01*
X808334Y299067D01*
X808251Y299400D01*
X808001Y299692D01*
X807626Y299900D01*
X807251Y299983D01*
X806792D01*
X806417Y299900D01*
X806084Y299692D01*
X805917Y299442D01*
X805834Y299150D01*
X805917Y298817D01*
X806084Y298567D01*
X806334Y298400D01*
X806667Y298317D01*
X806959Y298400D01*
X807251Y298608D01*
X807417Y298858D01*
X807459Y299150D01*
X807376Y299483D01*
X807167Y299733D01*
X806792Y299983D01*
G01X800208Y265267D02*
X800083Y265017D01*
X800000Y264725D01*
Y264392D01*
X800125Y264017D01*
X800333Y263725D01*
X800583Y263517D01*
X801000Y263350D01*
X801375Y263308D01*
X801750Y263392D01*
X802000Y263517D01*
X802250Y263767D01*
X802417Y264058D01*
X802500Y264350D01*
Y264642D01*
X802417Y264933D01*
X802292Y265183D01*
X802125Y265392D01*
G01X802000Y266533D02*
X802292Y266783D01*
X802458Y267117D01*
X802500Y267492D01*
X802458Y267825D01*
X802250Y268158D01*
X802000Y268367D01*
X801750Y268408D01*
X801458Y268325D01*
X801250Y268033D01*
X801167Y267742D01*
Y267367D01*
G01Y267742D02*
X801042Y267992D01*
X800833Y268200D01*
X800583Y268283D01*
X800333Y268200D01*
X800125Y267992D01*
X800000Y267617D01*
X800042Y267242D01*
X800208Y266867D01*
G01X802125Y269633D02*
X802333Y269883D01*
X802458Y270175D01*
X802500Y270550D01*
X802417Y270925D01*
X802250Y271217D01*
X801958Y271425D01*
X801625Y271467D01*
X801292Y271383D01*
X801083Y271175D01*
X800917Y270883D01*
X800875Y270592D01*
X800917Y270300D01*
X801083Y269925D01*
X800000Y270050D01*
Y271175D01*
G01Y273650D02*
X800083Y273317D01*
X800292Y273067D01*
X800542Y272900D01*
X800875Y272775D01*
X801250Y272733D01*
X801625Y272775D01*
X801958Y272900D01*
X802208Y273067D01*
X802417Y273317D01*
X802500Y273650D01*
X802417Y273983D01*
X802208Y274233D01*
X801958Y274400D01*
X801625Y274525D01*
X801250Y274567D01*
X800875Y274525D01*
X800542Y274400D01*
X800292Y274233D01*
X800083Y273983D01*
X800000Y273650D01*
G01X786708Y272267D02*
X786583Y272017D01*
X786500Y271725D01*
Y271392D01*
X786625Y271017D01*
X786833Y270725D01*
X787083Y270517D01*
X787500Y270350D01*
X787875Y270308D01*
X788250Y270392D01*
X788500Y270517D01*
X788750Y270767D01*
X788917Y271058D01*
X789000Y271350D01*
Y271642D01*
X788917Y271933D01*
X788792Y272183D01*
X788625Y272392D01*
G01Y273533D02*
X788833Y273783D01*
X788958Y274075D01*
X789000Y274450D01*
X788917Y274825D01*
X788750Y275117D01*
X788458Y275325D01*
X788125Y275367D01*
X787792Y275283D01*
X787583Y275075D01*
X787417Y274783D01*
X787375Y274492D01*
X787417Y274200D01*
X787583Y273825D01*
X786500Y273950D01*
Y275075D01*
G01X789000Y277550D02*
X786500D01*
X787000Y277050D01*
G01X789000D02*
Y278050D01*
G01X786500Y280650D02*
X786583Y280317D01*
X786792Y280067D01*
X787042Y279900D01*
X787375Y279775D01*
X787750Y279733D01*
X788125Y279775D01*
X788458Y279900D01*
X788708Y280067D01*
X788917Y280317D01*
X789000Y280650D01*
X788917Y280983D01*
X788708Y281233D01*
X788458Y281400D01*
X788125Y281525D01*
X787750Y281567D01*
X787375Y281525D01*
X787042Y281400D01*
X786792Y281233D01*
X786583Y280983D01*
X786500Y280650D01*
G01X765537Y276199D02*
Y276349D01*
X766787Y277599D01*
X767987Y276399D01*
Y276149D01*
G01X777108Y309201D02*
X769108D01*
Y297251D01*
X777108D01*
Y309201D01*
G01X770958Y297251D02*
X772958Y299251D01*
X774958Y297251D01*
G01X779500Y319017D02*
X777000D01*
Y320058D01*
X777125Y320392D01*
X777292Y320600D01*
X777625Y320683D01*
X777958Y320600D01*
X778167Y320350D01*
X778292Y320058D01*
Y319017D01*
G01Y320058D02*
X779500Y320683D01*
G01Y323450D02*
X777000D01*
X778792Y321908D01*
Y323992D01*
G01X779500Y326550D02*
X777000D01*
X778792Y325008D01*
Y327092D01*
G01X777417Y328358D02*
X777167Y328608D01*
X777042Y328900D01*
X777000Y329233D01*
X777083Y329650D01*
X777292Y329942D01*
X777542Y330025D01*
X777792Y329983D01*
X778000Y329817D01*
X778417Y328983D01*
X778708Y328608D01*
X779125Y328358D01*
X779500Y328275D01*
Y330025D01*
G01X780800Y322770D02*
X784800D01*
Y330170D01*
G01X803517Y307500D02*
Y310000D01*
X804558D01*
X804892Y309875D01*
X805100Y309708D01*
X805183Y309375D01*
X805100Y309042D01*
X804850Y308833D01*
X804558Y308708D01*
X803517D01*
G01X804558D02*
X805183Y307500D01*
G01X806533Y308000D02*
X806783Y307708D01*
X807117Y307542D01*
X807492Y307500D01*
X807825Y307542D01*
X808158Y307750D01*
X808367Y308000D01*
X808408Y308250D01*
X808325Y308542D01*
X808033Y308750D01*
X807742Y308833D01*
X807367D01*
G01X807742D02*
X807992Y308958D01*
X808200Y309167D01*
X808283Y309417D01*
X808200Y309667D01*
X807992Y309875D01*
X807617Y310000D01*
X807242Y309958D01*
X806867Y309792D01*
G01X809758Y308542D02*
X810050Y308833D01*
X810300Y309000D01*
X810633Y309083D01*
X810925Y309000D01*
X811133Y308833D01*
X811300Y308583D01*
X811342Y308292D01*
X811300Y308042D01*
X811133Y307792D01*
X810883Y307583D01*
X810592Y307500D01*
X810258Y307583D01*
X809967Y307833D01*
X809800Y308208D01*
X809758Y308625D01*
X809842Y309167D01*
X809967Y309458D01*
X810175Y309750D01*
X810467Y309958D01*
X810758Y310000D01*
X811050Y309917D01*
X811258Y309708D01*
G01X812858Y308542D02*
X813150Y308833D01*
X813400Y309000D01*
X813733Y309083D01*
X814025Y309000D01*
X814233Y308833D01*
X814400Y308583D01*
X814442Y308292D01*
X814400Y308042D01*
X814233Y307792D01*
X813983Y307583D01*
X813692Y307500D01*
X813358Y307583D01*
X813067Y307833D01*
X812900Y308208D01*
X812858Y308625D01*
X812942Y309167D01*
X813067Y309458D01*
X813275Y309750D01*
X813567Y309958D01*
X813858Y310000D01*
X814150Y309917D01*
X814358Y309708D01*
G01X800170Y305120D02*
Y309120D01*
X792770D01*
G01X803517Y303000D02*
Y305500D01*
X804558D01*
X804892Y305375D01*
X805100Y305208D01*
X805183Y304875D01*
X805100Y304542D01*
X804850Y304333D01*
X804558Y304208D01*
X803517D01*
G01X804558D02*
X805183Y303000D01*
G01X806533Y303500D02*
X806783Y303208D01*
X807117Y303042D01*
X807492Y303000D01*
X807825Y303042D01*
X808158Y303250D01*
X808367Y303500D01*
X808408Y303750D01*
X808325Y304042D01*
X808033Y304250D01*
X807742Y304333D01*
X807367D01*
G01X807742D02*
X807992Y304458D01*
X808200Y304667D01*
X808283Y304917D01*
X808200Y305167D01*
X807992Y305375D01*
X807617Y305500D01*
X807242Y305458D01*
X806867Y305292D01*
G01X809758Y304042D02*
X810050Y304333D01*
X810300Y304500D01*
X810633Y304583D01*
X810925Y304500D01*
X811133Y304333D01*
X811300Y304083D01*
X811342Y303792D01*
X811300Y303542D01*
X811133Y303292D01*
X810883Y303083D01*
X810592Y303000D01*
X810258Y303083D01*
X809967Y303333D01*
X809800Y303708D01*
X809758Y304125D01*
X809842Y304667D01*
X809967Y304958D01*
X810175Y305250D01*
X810467Y305458D01*
X810758Y305500D01*
X811050Y305417D01*
X811258Y305208D01*
G01X813567Y303000D02*
X813650Y303542D01*
X813775Y304000D01*
X813942Y304417D01*
X814150Y304875D01*
X814483Y305500D01*
X812817D01*
G01X800170Y300620D02*
Y304620D01*
X792770D01*
G01X790608Y315767D02*
X790483Y315517D01*
X790400Y315225D01*
Y314892D01*
X790525Y314517D01*
X790733Y314225D01*
X790983Y314017D01*
X791400Y313850D01*
X791775Y313808D01*
X792150Y313892D01*
X792400Y314017D01*
X792650Y314267D01*
X792817Y314558D01*
X792900Y314850D01*
Y315142D01*
X792817Y315433D01*
X792692Y315683D01*
X792525Y315892D01*
G01Y317033D02*
X792733Y317283D01*
X792858Y317575D01*
X792900Y317950D01*
X792817Y318325D01*
X792650Y318617D01*
X792358Y318825D01*
X792025Y318867D01*
X791692Y318783D01*
X791483Y318575D01*
X791317Y318283D01*
X791275Y317992D01*
X791317Y317700D01*
X791483Y317325D01*
X790400Y317450D01*
Y318575D01*
G01X792900Y320967D02*
X792358Y321050D01*
X791900Y321175D01*
X791483Y321342D01*
X791025Y321550D01*
X790400Y321883D01*
Y320217D01*
G01X792900Y324067D02*
X792358Y324150D01*
X791900Y324275D01*
X791483Y324442D01*
X791025Y324650D01*
X790400Y324983D01*
Y323317D01*
G01X762300Y321500D02*
Y319000D01*
G01X761342Y321500D02*
X763258D01*
G01X764567Y319000D02*
Y321500D01*
X765567D01*
X765900Y321375D01*
X766150Y321083D01*
X766233Y320750D01*
X766150Y320417D01*
X765942Y320167D01*
X765567Y320042D01*
X764567D01*
G01X768500Y319000D02*
Y321500D01*
X768000Y321000D01*
G01Y319000D02*
X769000D01*
G01X770808Y320042D02*
X771100Y320333D01*
X771350Y320500D01*
X771683Y320583D01*
X771975Y320500D01*
X772183Y320333D01*
X772350Y320083D01*
X772392Y319792D01*
X772350Y319542D01*
X772183Y319292D01*
X771933Y319083D01*
X771642Y319000D01*
X771308Y319083D01*
X771017Y319333D01*
X770850Y319708D01*
X770808Y320125D01*
X770892Y320667D01*
X771017Y320958D01*
X771225Y321250D01*
X771517Y321458D01*
X771808Y321500D01*
X772100Y321417D01*
X772308Y321208D01*
G01X773908Y320042D02*
X774200Y320333D01*
X774450Y320500D01*
X774783Y320583D01*
X775075Y320500D01*
X775283Y320333D01*
X775450Y320083D01*
X775492Y319792D01*
X775450Y319542D01*
X775283Y319292D01*
X775033Y319083D01*
X774742Y319000D01*
X774408Y319083D01*
X774117Y319333D01*
X773950Y319708D01*
X773908Y320125D01*
X773992Y320667D01*
X774117Y320958D01*
X774325Y321250D01*
X774617Y321458D01*
X774908Y321500D01*
X775200Y321417D01*
X775408Y321208D01*
G01X777983Y316167D02*
Y314375D01*
X778150Y314000D01*
X778483Y313750D01*
X778900Y313667D01*
X779317Y313750D01*
X779650Y314000D01*
X779817Y314375D01*
Y316167D01*
G01X781083Y314167D02*
X781333Y313875D01*
X781667Y313709D01*
X782042Y313667D01*
X782375Y313709D01*
X782708Y313917D01*
X782917Y314167D01*
X782958Y314417D01*
X782875Y314709D01*
X782583Y314917D01*
X782292Y315000D01*
X781917D01*
G01X782292D02*
X782542Y315125D01*
X782750Y315334D01*
X782833Y315584D01*
X782750Y315834D01*
X782542Y316042D01*
X782167Y316167D01*
X781792Y316125D01*
X781417Y315959D01*
G01X785100Y316167D02*
X784767Y316084D01*
X784517Y315875D01*
X784350Y315625D01*
X784225Y315292D01*
X784183Y314917D01*
X784225Y314542D01*
X784350Y314209D01*
X784517Y313959D01*
X784767Y313750D01*
X785100Y313667D01*
X785433Y313750D01*
X785683Y313959D01*
X785850Y314209D01*
X785975Y314542D01*
X786017Y314917D01*
X785975Y315292D01*
X785850Y315625D01*
X785683Y315875D01*
X785433Y316084D01*
X785100Y316167D01*
G01X768993Y359260D02*
Y361760D01*
X769827D01*
X770160Y361635D01*
X770410Y361468D01*
X770618Y361218D01*
X770785Y360927D01*
X770827Y360510D01*
X770785Y360093D01*
X770618Y359802D01*
X770410Y359552D01*
X770160Y359385D01*
X769827Y359260D01*
X768993D01*
G01X773843D02*
X772177D01*
Y361760D01*
X773843D01*
G01X773177Y360552D02*
X772177D01*
G01X776443Y360593D02*
X776610Y360718D01*
X776735Y360927D01*
X776818Y361218D01*
X776735Y361468D01*
X776568Y361635D01*
X776277Y361760D01*
X775152D01*
Y359260D01*
X776527D01*
X776818Y359427D01*
X776985Y359677D01*
X777068Y359968D01*
X776985Y360260D01*
X776735Y360510D01*
X776443Y360593D01*
X775152D01*
G01X778293Y361760D02*
Y359968D01*
X778460Y359593D01*
X778793Y359343D01*
X779210Y359260D01*
X779627Y359343D01*
X779960Y359593D01*
X780127Y359968D01*
Y361760D01*
G01X782560Y360510D02*
X783393D01*
Y359760D01*
X783143Y359510D01*
X782852Y359343D01*
X782435Y359260D01*
X782018Y359343D01*
X781727Y359510D01*
X781477Y359760D01*
X781310Y360052D01*
X781227Y360385D01*
Y360677D01*
X781310Y360927D01*
X781477Y361218D01*
X781727Y361468D01*
X781977Y361635D01*
X782310Y361760D01*
X782602D01*
X782935Y361677D01*
X783185Y361510D01*
G01X784618Y361343D02*
X784868Y361593D01*
X785160Y361718D01*
X785493Y361760D01*
X785910Y361677D01*
X786202Y361468D01*
X786285Y361218D01*
X786243Y360968D01*
X786077Y360760D01*
X785243Y360343D01*
X784868Y360052D01*
X784618Y359635D01*
X784535Y359260D01*
X786285D01*
G01X763210Y400810D02*
Y373010D01*
X791010D01*
Y400810D01*
X763210D01*
G01X764617Y443000D02*
Y445500D01*
X765658D01*
X765992Y445375D01*
X766200Y445208D01*
X766283Y444875D01*
X766200Y444542D01*
X765950Y444333D01*
X765658Y444208D01*
X764617D01*
G01X765658D02*
X766283Y443000D01*
G01X767633Y443500D02*
X767883Y443208D01*
X768217Y443042D01*
X768592Y443000D01*
X768925Y443042D01*
X769258Y443250D01*
X769467Y443500D01*
X769508Y443750D01*
X769425Y444042D01*
X769133Y444250D01*
X768842Y444333D01*
X768467D01*
G01X768842D02*
X769092Y444458D01*
X769300Y444667D01*
X769383Y444917D01*
X769300Y445167D01*
X769092Y445375D01*
X768717Y445500D01*
X768342Y445458D01*
X767967Y445292D01*
G01X770000Y430517D02*
X767500D01*
Y431558D01*
X767625Y431892D01*
X767792Y432100D01*
X768125Y432183D01*
X768458Y432100D01*
X768667Y431850D01*
X768792Y431558D01*
Y430517D01*
G01Y431558D02*
X770000Y432183D01*
G01X769625Y433533D02*
X769833Y433783D01*
X769958Y434075D01*
X770000Y434450D01*
X769917Y434825D01*
X769750Y435117D01*
X769458Y435325D01*
X769125Y435367D01*
X768792Y435283D01*
X768583Y435075D01*
X768417Y434783D01*
X768375Y434492D01*
X768417Y434200D01*
X768583Y433825D01*
X767500Y433950D01*
Y435075D01*
G01X769500Y436633D02*
X769792Y436883D01*
X769958Y437217D01*
X770000Y437592D01*
X769958Y437925D01*
X769750Y438258D01*
X769500Y438467D01*
X769250Y438508D01*
X768958Y438425D01*
X768750Y438133D01*
X768667Y437842D01*
Y437467D01*
G01Y437842D02*
X768542Y438092D01*
X768333Y438300D01*
X768083Y438383D01*
X767833Y438300D01*
X767625Y438092D01*
X767500Y437717D01*
X767542Y437342D01*
X767708Y436967D01*
G01X770000Y440650D02*
X769958Y440942D01*
X769833Y441275D01*
X769625Y441483D01*
X769333Y441567D01*
X769042Y441483D01*
X768792Y441233D01*
X768667Y440858D01*
Y440442D01*
X768583Y440192D01*
X768375Y439983D01*
X768083Y439900D01*
X767792Y440025D01*
X767583Y440317D01*
X767500Y440650D01*
X767583Y440983D01*
X767792Y441275D01*
X768083Y441400D01*
X768375Y441317D01*
X768583Y441108D01*
X768667Y440858D01*
Y440442D01*
X768792Y440067D01*
X769042Y439817D01*
X769333Y439733D01*
X769625Y439817D01*
X769833Y440025D01*
X769958Y440358D01*
X770000Y440650D01*
G01X765500Y430900D02*
X765458Y430567D01*
X765292Y430275D01*
X765042Y430025D01*
X764750Y429858D01*
X764417Y429775D01*
X764083D01*
X763750Y429858D01*
X763458Y430025D01*
X763208Y430275D01*
X763042Y430567D01*
X763000Y430900D01*
X763042Y431233D01*
X763208Y431525D01*
X763458Y431775D01*
X763750Y431942D01*
X764083Y432025D01*
X764417D01*
X764750Y431942D01*
X765042Y431775D01*
X765292Y431525D01*
X765458Y431233D01*
X765500Y430900D01*
G01X764833Y431233D02*
X765500Y431733D01*
G01X765000Y433083D02*
X765292Y433333D01*
X765458Y433667D01*
X765500Y434042D01*
X765458Y434375D01*
X765250Y434708D01*
X765000Y434917D01*
X764750Y434958D01*
X764458Y434875D01*
X764250Y434583D01*
X764167Y434292D01*
Y433917D01*
G01Y434292D02*
X764042Y434542D01*
X763833Y434750D01*
X763583Y434833D01*
X763333Y434750D01*
X763125Y434542D01*
X763000Y434167D01*
X763042Y433792D01*
X763208Y433417D01*
G01X765500Y437600D02*
X763000D01*
X764792Y436058D01*
Y438142D01*
G01X765708Y449267D02*
X765583Y449017D01*
X765500Y448725D01*
Y448392D01*
X765625Y448017D01*
X765833Y447725D01*
X766083Y447517D01*
X766500Y447350D01*
X766875Y447308D01*
X767250Y447392D01*
X767500Y447517D01*
X767750Y447767D01*
X767917Y448058D01*
X768000Y448350D01*
Y448642D01*
X767917Y448933D01*
X767792Y449183D01*
X767625Y449392D01*
G01X766958Y450658D02*
X766667Y450950D01*
X766500Y451200D01*
X766417Y451533D01*
X766500Y451825D01*
X766667Y452033D01*
X766917Y452200D01*
X767208Y452242D01*
X767458Y452200D01*
X767708Y452033D01*
X767917Y451783D01*
X768000Y451492D01*
X767917Y451158D01*
X767667Y450867D01*
X767292Y450700D01*
X766875Y450658D01*
X766333Y450742D01*
X766042Y450867D01*
X765750Y451075D01*
X765542Y451367D01*
X765500Y451658D01*
X765583Y451950D01*
X765792Y452158D01*
G01X767708Y453842D02*
X767917Y454133D01*
X768000Y454467D01*
X767917Y454800D01*
X767667Y455092D01*
X767292Y455300D01*
X766917Y455383D01*
X766458D01*
X766083Y455300D01*
X765750Y455092D01*
X765583Y454842D01*
X765500Y454550D01*
X765583Y454217D01*
X765750Y453967D01*
X766000Y453800D01*
X766333Y453717D01*
X766625Y453800D01*
X766917Y454008D01*
X767083Y454258D01*
X767125Y454550D01*
X767042Y454883D01*
X766833Y455133D01*
X766458Y455383D01*
G01X768000Y457650D02*
X765500D01*
X766000Y457150D01*
G01X768000D02*
Y458150D01*
G01X780721Y474660D02*
Y477160D01*
X781762D01*
X782096Y477035D01*
X782304Y476868D01*
X782387Y476535D01*
X782304Y476202D01*
X782054Y475993D01*
X781762Y475868D01*
X780721D01*
G01X781762D02*
X782387Y474660D01*
G01X783779D02*
Y477160D01*
G01X785529D02*
Y474660D01*
G01Y475910D02*
X783779D01*
G01X787754Y474660D02*
X787421Y474702D01*
X787129Y474868D01*
X786879Y475118D01*
X786712Y475410D01*
X786629Y475743D01*
Y476077D01*
X786712Y476410D01*
X786879Y476702D01*
X787129Y476952D01*
X787421Y477118D01*
X787754Y477160D01*
X788087Y477118D01*
X788379Y476952D01*
X788629Y476702D01*
X788796Y476410D01*
X788879Y476077D01*
Y475743D01*
X788796Y475410D01*
X788629Y475118D01*
X788379Y474868D01*
X788087Y474702D01*
X787754Y474660D01*
G01X790021Y477160D02*
Y474660D01*
X791687D01*
G01X794787D02*
X793121D01*
Y477160D01*
X794787D01*
G01X794121Y475952D02*
X793121D01*
G01X797054Y474660D02*
Y477160D01*
X796554Y476660D01*
G01Y474660D02*
X797554D01*
G54D19*
G01X70400Y184900D02*
X66400D01*
G01X57800Y185900D02*
X61800D01*
G01X80600Y225500D02*
X84600D01*
G01X85800Y201400D02*
Y197400D01*
G01Y211400D02*
Y207400D01*
G01X83300Y185000D02*
X79300D01*
G01X85800Y206400D02*
Y202400D01*
G01X173300Y106500D02*
Y102500D01*
G01X170600Y147000D02*
X171700D01*
G01X167900D02*
X169000D01*
G01X191657Y153996D02*
Y155096D01*
G01Y151296D02*
Y152396D01*
G01X175700Y172600D02*
X174600D01*
G01X178400D02*
X177300D01*
G01X176500Y196000D02*
X180500D01*
G01X208900Y164900D02*
X210000D01*
G01X206200D02*
X207300D01*
G01X232500Y382200D02*
Y386200D01*
G01X257720Y374270D02*
Y378270D01*
G01X259000Y433000D02*
Y429000D01*
G01X278000Y141800D02*
Y142900D01*
G01Y139100D02*
Y140200D01*
G01X277500Y163800D02*
Y164900D01*
G01Y161100D02*
Y162200D01*
G01X298500Y141500D02*
X294500D01*
G01X295000Y162000D02*
X299000D01*
G01X278000Y205300D02*
Y206400D01*
G01Y202600D02*
Y203700D01*
G01X277500Y183800D02*
Y184900D01*
G01Y181100D02*
Y182200D01*
G01X278000Y225300D02*
Y226400D01*
G01Y222600D02*
Y223700D01*
G01X294500Y203100D02*
X298500D01*
G01X299000Y225350D02*
X295000D01*
G01X298500Y183300D02*
X294500D01*
G01X277500Y246800D02*
Y247900D01*
G01Y244100D02*
Y245200D01*
G01X294500Y245150D02*
X298500D01*
G01X283900Y421400D02*
X285000D01*
G01X281200D02*
X282300D01*
G01X567300Y395500D02*
X568400D01*
G01X564600D02*
X565700D01*
G01X567070Y463230D02*
X571070D01*
G01X579000Y395500D02*
X583000D01*
G01X626770Y458230D02*
X622770D01*
G01X617870Y436730D02*
X613870D01*
G01X622600Y436700D02*
X618600D01*
G01X573300Y490500D02*
Y491600D01*
G01Y487800D02*
Y488900D01*
G01X682700Y324600D02*
X683800D01*
G01X680000D02*
X681100D01*
G01X692100Y308300D02*
Y304300D01*
G01X683540Y422460D02*
X679540D01*
G01X693700Y393050D02*
X697700D01*
G01X646460Y392820D02*
Y388820D01*
G01X687500Y379500D02*
Y375500D01*
G01X645623Y381289D02*
X649623D01*
G01X640907D02*
X644907D01*
G01X688300Y368300D02*
X684300D01*
G01X674800Y445400D02*
X670800D01*
G01X715000Y384600D02*
X713900D01*
G01X717700D02*
X716600D01*
G01X734400Y459400D02*
X738400D01*
M02*
